{ Packager-XL run on 24-Aug-2023 AT 15:36:33 }
FILE_TYPE = BACK_ANNOTATION;
DRAWING = "@s9s_mb_2u_lib.s9s_mb_2u(sch_1):page310";
BODY = "TP_TDR_4P_FTS","I5": LOCATION = "X38" #&CDS_LOCATION = "X38" &SEC = "1" #&CDS_SEC = "1";
"P1":   PN = "2"  !CDS_PN = "2";
"P2":   PN = "3"  !CDS_PN = "3";
"S1":   PN = "1"  !CDS_PN = "1";
"S2":   PN = "4"  !CDS_PN = "4";
BODY = "TP_TDR_4P_FTS","I6": LOCATION = "X44" #&CDS_LOCATION = "X44" &SEC = "1" #&CDS_SEC = "1";
"P1":   PN = "2"  !CDS_PN = "2";
"P2":   PN = "3"  !CDS_PN = "3";
"S1":   PN = "1"  !CDS_PN = "1";
"S2":   PN = "4"  !CDS_PN = "4";
BODY = "TP_TDR_4P_FTS","I7": LOCATION = "X37" #&CDS_LOCATION = "X37" &SEC = "1" #&CDS_SEC = "1";
"P1":   PN = "2"  !CDS_PN = "2";
"P2":   PN = "3"  !CDS_PN = "3";
"S1":   PN = "1"  !CDS_PN = "1";
"S2":   PN = "4"  !CDS_PN = "4";
BODY = "TP_TDR_4P_FTS","I8": LOCATION = "X36" #&CDS_LOCATION = "X36" &SEC = "1" #&CDS_SEC = "1";
"P1":   PN = "2"  !CDS_PN = "2";
"P2":   PN = "3"  !CDS_PN = "3";
"S1":   PN = "1"  !CDS_PN = "1";
"S2":   PN = "4"  !CDS_PN = "4";
BODY = "TP_TDR_4P_FTS","I9": LOCATION = "X43" #&CDS_LOCATION = "X43" &SEC = "1" #&CDS_SEC = "1";
"P1":   PN = "2"  !CDS_PN = "2";
"P2":   PN = "3"  !CDS_PN = "3";
"S1":   PN = "1"  !CDS_PN = "1";
"S2":   PN = "4"  !CDS_PN = "4";
BODY = "TP_TDR_4P_FTS","I10": LOCATION = "X42" #&CDS_LOCATION = "X42" &SEC = "1" #&CDS_SEC = "1";
"P1":   PN = "2"  !CDS_PN = "2";
"P2":   PN = "3"  !CDS_PN = "3";
"S1":   PN = "1"  !CDS_PN = "1";
"S2":   PN = "4"  !CDS_PN = "4";
BODY = "TP_TDR_4P_FTS","I15": LOCATION = "X41" #&CDS_LOCATION = "X41" &SEC = "1" #&CDS_SEC = "1";
"P1":   PN = "2"  !CDS_PN = "2";
"P2":   PN = "3"  !CDS_PN = "3";
"S1":   PN = "1"  !CDS_PN = "1";
"S2":   PN = "4"  !CDS_PN = "4";
BODY = "TP_TDR_4P_FTS","I16": LOCATION = "X35" #&CDS_LOCATION = "X35" &SEC = "1" #&CDS_SEC = "1";
"P1":   PN = "2"  !CDS_PN = "2";
"P2":   PN = "3"  !CDS_PN = "3";
"S1":   PN = "1"  !CDS_PN = "1";
"S2":   PN = "4"  !CDS_PN = "4";
BODY = "TP_TDR_4P_FTS","I19": LOCATION = "X34" #&CDS_LOCATION = "X34" &SEC = "1" #&CDS_SEC = "1";
"P1":   PN = "2"  !CDS_PN = "2";
"P2":   PN = "3"  !CDS_PN = "3";
"S1":   PN = "1"  !CDS_PN = "1";
"S2":   PN = "4"  !CDS_PN = "4";
BODY = "TP_TDR_4P_FTS","I20": LOCATION = "X33" #&CDS_LOCATION = "X33" &SEC = "1" #&CDS_SEC = "1";
"P1":   PN = "2"  !CDS_PN = "2";
"P2":   PN = "3"  !CDS_PN = "3";
"S1":   PN = "1"  !CDS_PN = "1";
"S2":   PN = "4"  !CDS_PN = "4";
BODY = "TP_TDR_4P_FTS","I21": LOCATION = "X40" #&CDS_LOCATION = "X40" &SEC = "1" #&CDS_SEC = "1";
"P1":   PN = "2"  !CDS_PN = "2";
"P2":   PN = "3"  !CDS_PN = "3";
"S1":   PN = "1"  !CDS_PN = "1";
"S2":   PN = "4"  !CDS_PN = "4";
BODY = "TP_TDR_4P_FTS","I22": LOCATION = "X39" #&CDS_LOCATION = "X39" &SEC = "1" #&CDS_SEC = "1";
"P1":   PN = "2"  !CDS_PN = "2";
"P2":   PN = "3"  !CDS_PN = "3";
"S1":   PN = "1"  !CDS_PN = "1";
"S2":   PN = "4"  !CDS_PN = "4";
DRAWING = "@s9s_mb_2u_lib.s9s_mb_2u(sch_1):page13";
BODY = "Q_RES","I16": LOCATION = "R2" #&CDS_LOCATION = "R2" &SEC = "1" #&CDS_SEC = "1";
"A":   PN = "1"  !CDS_PN = "1";
"B":   PN = "2"  !CDS_PN = "2";
BODY = "Q_RES","I18": LOCATION = "R1" #&CDS_LOCATION = "R1" &SEC = "1" #&CDS_SEC = "1";
"A":   PN = "1"  !CDS_PN = "1";
"B":   PN = "2"  !CDS_PN = "2";
BODY = "Q_RES","I21": LOCATION = "R3" #&CDS_LOCATION = "R3" &SEC = "1" #&CDS_SEC = "1";
"A":   PN = "1"  !CDS_PN = "1";
"B":   PN = "2"  !CDS_PN = "2";
BODY = "Q_RES","I24": LOCATION = "R5" #&CDS_LOCATION = "R5" &SEC = "1" #&CDS_SEC = "1";
"A":   PN = "1"  !CDS_PN = "1";
"B":   PN = "2"  !CDS_PN = "2";
BODY = "Q_RES","I25": LOCATION = "R6" #&CDS_LOCATION = "R6" &SEC = "1" #&CDS_SEC = "1";
"A":   PN = "1"  !CDS_PN = "1";
"B":   PN = "2"  !CDS_PN = "2";
BODY = "Q_RES","I29": LOCATION = "R4" #&CDS_LOCATION = "R4" &SEC = "1" #&CDS_SEC = "1";
"A":   PN = "1"  !CDS_PN = "1";
"B":   PN = "2"  !CDS_PN = "2";
BODY = "SOCKET4677_AZIF0045P001C01CS","I57": LOCATION = "U2" #&CDS_LOCATION = "U2" &SEC = "1" #&CDS_SEC = "1";
"BCLK0_DN":   PN = "AT30"  !CDS_PN = "AT30";
"BCLK0_DP":   PN = "AV30"  !CDS_PN = "AV30";
"BCLK1_DN":   PN = "CY28"  !CDS_PN = "CY28";
"BCLK1_DP":   PN = "CW29"  !CDS_PN = "CW29";
"BCLK2_DN":   PN = "AU29"  !CDS_PN = "AU29";
"BCLK2_DP":   PN = "AV28"  !CDS_PN = "AV28";
"BCLK3_DN":   PN = "CW27"  !CDS_PN = "CW27";
"BCLK3_DP":   PN = "DA27"  !CDS_PN = "DA27";
"BIST_ENABLE":   PN = "AT18"  !CDS_PN = "AT18";
"BMCINIT":   PN = "BN23"  !CDS_PN = "BN23";
"DDR01_RESET_N":   PN = "AU50"  !CDS_PN = "AU50";
"DDR23_RESET_N":   PN = "AV51"  !CDS_PN = "AV51";
"DDR45_RESET_N":   PN = "CY42"  !CDS_PN = "CY42";
"DDR67_RESET_N":   PN = "CY55"  !CDS_PN = "CY55";
"DMIMODE_OVERRIDE":   PN = "AW17"  !CDS_PN = "AW17";
"FRMAGENT":   PN = "AU17"  !CDS_PN = "AU17";
"LEGACY_SKT":   PN = "CY59"  !CDS_PN = "CY59";
"PECI":   PN = "BH24"  !CDS_PN = "BH24";
"PKG_ID0":   PN = "BL64"  !CDS_PN = "BL64";
"PKG_ID1":   PN = "AY63"  !CDS_PN = "AY63";
"PKG_ID2":   PN = "BN64"  !CDS_PN = "BN64";
"PRDY_N":   PN = "BP26"  !CDS_PN = "BP26";
"PREQ_N":   PN = "AV22"  !CDS_PN = "AV22";
"PROC_ID0":   PN = "BG72"  !CDS_PN = "BG72";
"PROC_ID1":   PN = "BH71"  !CDS_PN = "BH71";
"PROCDIS_N":   PN = "DA52"  !CDS_PN = "DA52";
"SAFE_MODE_BOOT":   PN = "AU23"  !CDS_PN = "AU23";
"SOCKET_ID0":   PN = "CW60"  !CDS_PN = "CW60";
"SOCKET_ID1":   PN = "CY61"  !CDS_PN = "CY61";
"SOCKET_ID2":   PN = "CT61"  !CDS_PN = "CT61";
"TCK":   PN = "BT24"  !CDS_PN = "BT24";
"TDI":   PN = "BV24"  !CDS_PN = "BV24";
"TDO":   PN = "BW25"  !CDS_PN = "BW25";
"TMS":   PN = "BR25"  !CDS_PN = "BR25";
"TXT_AGENT":   PN = "BT26"  !CDS_PN = "BT26";
"TXT_PLTEN":   PN = "CT20"  !CDS_PN = "CT20";
"XTAL_CLK_DN":   PN = "CW31"  !CDS_PN = "CW31";
"XTAL_CLK_DP":   PN = "CY32"  !CDS_PN = "CY32";
"DDR0123_SPDSCL":   PN = "BT22"  !CDS_PN = "BT22";
"DDR0123_SPDSDA":   PN = "BY22"  !CDS_PN = "BY22";
"DDR4567_SPDSCL":   PN = "CU17"  !CDS_PN = "CU17";
"DDR4567_SPDSDA":   PN = "CT18"  !CDS_PN = "CT18";
"RSVD72":   PN = "BR23"  !CDS_PN = "BR23";
"RSVD76":   PN = "BY24"  !CDS_PN = "BY24";
"RSVD88":   PN = "CD71"  !CDS_PN = "CD71";
"RSVD91":   PN = "CE70"  !CDS_PN = "CE70";
"RSVD108":   PN = "CJ72"  !CDS_PN = "CJ72";
"RSVD120":   PN = "CL72"  !CDS_PN = "CL72";
"RSVD157":   PN = "D4"  !CDS_PN = "D4";
"RSVD161":   PN = "G5"  !CDS_PN = "G5";
DRAWING = "@s9s_mb_2u_lib.s9s_mb_2u(sch_1):page14";
BODY = "SOCKET4677_AZIF0045P001C01CS","I1": LOCATION = "U2" #&CDS_LOCATION = "U2" &SEC = "2" #&CDS_SEC = "2";
"CATERR_N":   PN = "BP24"  !CDS_PN = "BP24";
"CXPSMBUS_ALERT_N":   PN = "BV26"  !CDS_PN = "BV26";
"CXPSMBUSSCL":   PN = "CA25"  !CDS_PN = "CA25";
"CXPSMBUSSDA":   PN = "BY26"  !CDS_PN = "BY26";
"DDR01_DRAM_PWR_OK":   PN = "A43"  !CDS_PN = "A43";
"DDR23_DRAM_PWR_OK":   PN = "F47"  !CDS_PN = "F47";
"DDR45_DRAM_PWR_OK":   PN = "CY44"  !CDS_PN = "CY44";
"DDR67_DRAM_PWR_OK":   PN = "CW45"  !CDS_PN = "CW45";
"FBRK_N":   PN = "AV57"  !CDS_PN = "AV57";
"MEMHOT_IN_N":   PN = "AU21"  !CDS_PN = "AU21";
"MEMHOT_OUT_N":   PN = "CF26"  !CDS_PN = "CF26";
"MEMTRIP_N":   PN = "AV24"  !CDS_PN = "AV24";
"NMI":   PN = "AV18"  !CDS_PN = "AV18";
"PMDOWN0":   PN = "CW39"  !CDS_PN = "CW39";
"PMDOWN1":   PN = "CP26"  !CDS_PN = "CP26";
"PMDOWN2":   PN = "CM26"  !CDS_PN = "CM26";
"PMDOWN3":   PN = "CD24"  !CDS_PN = "CD24";
"PMDOWN4":   PN = "CV18"  !CDS_PN = "CV18";
"PMDOWN5":   PN = "CE23"  !CDS_PN = "CE23";
"PMDOWN6":   PN = "CC25"  !CDS_PN = "CC25";
"PMDOWN_PCH":   PN = "CY40"  !CDS_PN = "CY40";
"PMFAST_WAKE_N":   PN = "CP20"  !CDS_PN = "CP20";
"PMSYNC0":   PN = "CN25"  !CDS_PN = "CN25";
"PMSYNC1":   PN = "CL25"  !CDS_PN = "CL25";
"PMSYNC2":   PN = "CH26"  !CDS_PN = "CH26";
"PMSYNC3":   PN = "CE25"  !CDS_PN = "CE25";
"PMSYNC4":   PN = "CR19"  !CDS_PN = "CR19";
"PMSYNC5":   PN = "CH24"  !CDS_PN = "CH24";
"PMSYNC6":   PN = "CF24"  !CDS_PN = "CF24";
"PMSYNC_PCH":   PN = "DA39"  !CDS_PN = "DA39";
"PROCHOT_N":   PN = "AU19"  !CDS_PN = "AU19";
"RESET_N":   PN = "BH61"  !CDS_PN = "BH61";
"SKTOCC_N":   PN = "CG66"  !CDS_PN = "CG66";
"SVIDALERT0_N":   PN = "BK26"  !CDS_PN = "BK26";
"SVIDALERT1_N":   PN = "BJ25"  !CDS_PN = "BJ25";
"SVIDCLK0":   PN = "BH26"  !CDS_PN = "BH26";
"SVIDCLK1":   PN = "BF26"  !CDS_PN = "BF26";
"SVIDDATA0":   PN = "BD26"  !CDS_PN = "BD26";
"SVIDDATA1":   PN = "BL25"  !CDS_PN = "BL25";
"TAP_ODT_EN":   PN = "AY20"  !CDS_PN = "AY20";
"THERMTRIP_N":   PN = "BL62"  !CDS_PN = "BL62";
"ERROR_N0":   PN = "BF22"  !CDS_PN = "BF22";
"ERROR_N1":   PN = "AY22"  !CDS_PN = "AY22";
"ERROR_N2":   PN = "BD22"  !CDS_PN = "BD22";
"PIROM_AD0":   PN = "CR70"  !CDS_PN = "CR70";
"PIROM_AD1":   PN = "CT71"  !CDS_PN = "CT71";
"PIROM_AD2":   PN = "CP71"  !CDS_PN = "CP71";
"PIROM_SCL":   PN = "CU70"  !CDS_PN = "CU70";
"PIROM_SDA":   PN = "CM71"  !CDS_PN = "CM71";
"PIROM_SM_WP":   PN = "CR72"  !CDS_PN = "CR72";
"PWRGOOD":   PN = "AV20"  !CDS_PN = "AV20";
"RSVD4":   PN = "AT24"  !CDS_PN = "AT24";
"RSVD6":   PN = "AU25"  !CDS_PN = "AU25";
"RSVD15":   PN = "AV26"  !CDS_PN = "AV26";
"RSVD19":   PN = "AV59"  !CDS_PN = "AV59";
"RSVD27":   PN = "AY26"  !CDS_PN = "AY26";
"RSVD29":   PN = "AY65"  !CDS_PN = "AY65";
"RSVD59":   PN = "BJ70"  !CDS_PN = "BJ70";
"RSVD69":   PN = "BP67"  !CDS_PN = "BP67";
"RSVD70":   PN = "BP69"  !CDS_PN = "BP69";
"RSVD96":   PN = "CH22"  !CDS_PN = "CH22";
"RSVD104":   PN = "CJ62"  !CDS_PN = "CJ62";
"RSVD113":   PN = "CL21"  !CDS_PN = "CL21";
"RSVD116":   PN = "CL64"  !CDS_PN = "CL64";
"RSVD121":   PN = "CM63"  !CDS_PN = "CM63";
"RSVD126":   PN = "CN62"  !CDS_PN = "CN62";
"RSVD132":   PN = "CR23"  !CDS_PN = "CR23";
"RSVD141":   PN = "CV24"  !CDS_PN = "CV24";
"RSVD145":   PN = "CW23"  !CDS_PN = "CW23";
"RSVD146":   PN = "CW25"  !CDS_PN = "CW25";
"RSVD150":   PN = "CW68"  !CDS_PN = "CW68";
BODY = "Q_RES","I59": LOCATION = "R12" #&CDS_LOCATION = "R12" &SEC = "1" #&CDS_SEC = "1";
"A":   PN = "1"  !CDS_PN = "1";
"B":   PN = "2"  !CDS_PN = "2";
BODY = "Q_RES","I60": LOCATION = "R13" #&CDS_LOCATION = "R13" &SEC = "1" #&CDS_SEC = "1";
"A":   PN = "1"  !CDS_PN = "1";
"B":   PN = "2"  !CDS_PN = "2";
BODY = "Q_RES","I61": LOCATION = "R14" #&CDS_LOCATION = "R14" &SEC = "1" #&CDS_SEC = "1";
"A":   PN = "1"  !CDS_PN = "1";
"B":   PN = "2"  !CDS_PN = "2";
BODY = "Q_RES","I62": LOCATION = "R15" #&CDS_LOCATION = "R15" &SEC = "1" #&CDS_SEC = "1";
"A":   PN = "1"  !CDS_PN = "1";
"B":   PN = "2"  !CDS_PN = "2";
BODY = "Q_RES","I63": LOCATION = "R16" #&CDS_LOCATION = "R16" &SEC = "1" #&CDS_SEC = "1";
"A":   PN = "1"  !CDS_PN = "1";
"B":   PN = "2"  !CDS_PN = "2";
BODY = "Q_RES","I64": LOCATION = "R17" #&CDS_LOCATION = "R17" &SEC = "1" #&CDS_SEC = "1";
"A":   PN = "1"  !CDS_PN = "1";
"B":   PN = "2"  !CDS_PN = "2";
BODY = "Q_RES","I66": LOCATION = "R7" #&CDS_LOCATION = "R7" &SEC = "1" #&CDS_SEC = "1";
"A":   PN = "1"  !CDS_PN = "1";
"B":   PN = "2"  !CDS_PN = "2";
BODY = "Q_RES","I78": LOCATION = "R10" #&CDS_LOCATION = "R10" &SEC = "1" #&CDS_SEC = "1";
"A":   PN = "1"  !CDS_PN = "1";
"B":   PN = "2"  !CDS_PN = "2";
BODY = "Q_RES","I79": LOCATION = "R11" #&CDS_LOCATION = "R11" &SEC = "1" #&CDS_SEC = "1";
"A":   PN = "1"  !CDS_PN = "1";
"B":   PN = "2"  !CDS_PN = "2";
BODY = "Q_RES","I90": LOCATION = "R322" #&CDS_LOCATION = "R322" &SEC = "1" #&CDS_SEC = "1";
"A":   PN = "1"  !CDS_PN = "1";
"B":   PN = "2"  !CDS_PN = "2";
BODY = "Q_RES","I93": LOCATION = "R328" #&CDS_LOCATION = "R328" &SEC = "1" #&CDS_SEC = "1";
"A":   PN = "1"  !CDS_PN = "1";
"B":   PN = "2"  !CDS_PN = "2";
BODY = "Q_RES","I94": LOCATION = "R548" #&CDS_LOCATION = "R548" &SEC = "1" #&CDS_SEC = "1";
"A":   PN = "1"  !CDS_PN = "1";
"B":   PN = "2"  !CDS_PN = "2";
BODY = "Q_RES","I98": LOCATION = "R555" #&CDS_LOCATION = "R555" &SEC = "1" #&CDS_SEC = "1";
"A":   PN = "1"  !CDS_PN = "1";
"B":   PN = "2"  !CDS_PN = "2";
BODY = "Q_RES","I100": LOCATION = "R556" #&CDS_LOCATION = "R556" &SEC = "1" #&CDS_SEC = "1";
"A":   PN = "1"  !CDS_PN = "1";
"B":   PN = "2"  !CDS_PN = "2";
BODY = "Q_RES","I109": LOCATION = "R1932" #&CDS_LOCATION = "R1932" &SEC = "1" #&CDS_SEC = "1";
"A":   PN = "1"  !CDS_PN = "1";
"B":   PN = "2"  !CDS_PN = "2";
BODY = "Q_RES","I110": LOCATION = "R1933" #&CDS_LOCATION = "R1933" &SEC = "1" #&CDS_SEC = "1";
"A":   PN = "1"  !CDS_PN = "1";
"B":   PN = "2"  !CDS_PN = "2";
BODY = "Q_RES","I115": LOCATION = "R1959" #&CDS_LOCATION = "R1959" &SEC = "1" #&CDS_SEC = "1";
"A":   PN = "1"  !CDS_PN = "1";
"B":   PN = "2"  !CDS_PN = "2";
BODY = "Q_RES","I117": LOCATION = "R1960" #&CDS_LOCATION = "R1960" &SEC = "1" #&CDS_SEC = "1";
"A":   PN = "1"  !CDS_PN = "1";
"B":   PN = "2"  !CDS_PN = "2";
BODY = "Q_RES","I122": LOCATION = "R2362" #&CDS_LOCATION = "R2362" &SEC = "1" #&CDS_SEC = "1";
"A":   PN = "1"  !CDS_PN = "1";
"B":   PN = "2"  !CDS_PN = "2";
BODY = "Q_RES","I128": LOCATION = "R4089" #&CDS_LOCATION = "R4089" &SEC = "1" #&CDS_SEC = "1";
"A":   PN = "1"  !CDS_PN = "1";
"B":   PN = "2"  !CDS_PN = "2";
DRAWING = "@s9s_mb_2u_lib.s9s_mb_2u(sch_1):page15";
BODY = "SOCKET4677_AZIF0045P001C01CS","I1": LOCATION = "U2" #&CDS_LOCATION = "U2" &SEC = "3" #&CDS_SEC = "3";
"PLT_AUX_PWRGOOD":   PN = "CV20"  !CDS_PN = "CV20";
"SMB_CLK":   PN = "CE64"  !CDS_PN = "CE64";
"SMB_DATA":   PN = "CD63"  !CDS_PN = "CD63";
"CD_INIT_ERROR":   PN = "CY20"  !CDS_PN = "CY20";
"PARTITION_ID0":   PN = "BA70"  !CDS_PN = "BA70";
"PARTITION_ID1":   PN = "AV71"  !CDS_PN = "AV71";
"RSVD11":   PN = "AU62"  !CDS_PN = "AU62";
"RSVD12":   PN = "AU64"  !CDS_PN = "AU64";
"RSVD20":   PN = "AV63"  !CDS_PN = "AV63";
"RSVD23":   PN = "AW19"  !CDS_PN = "AW19";
"RSVD24":   PN = "AW64"  !CDS_PN = "AW64";
"RSVD25":   PN = "AW70"  !CDS_PN = "AW70";
"RSVD28":   PN = "AY61"  !CDS_PN = "AY61";
"RSVD30":   PN = "AY67"  !CDS_PN = "AY67";
"RSVD32":   PN = "BA62"  !CDS_PN = "BA62";
"RSVD33":   PN = "BA66"  !CDS_PN = "BA66";
"RSVD34":   PN = "BA68"  !CDS_PN = "BA68";
"RSVD35":   PN = "BB61"  !CDS_PN = "BB61";
"RSVD36":   PN = "BB67"  !CDS_PN = "BB67";
"RSVD38":   PN = "BC25"  !CDS_PN = "BC25";
"RSVD39":   PN = "BC64"  !CDS_PN = "BC64";
"RSVD40":   PN = "BD61"  !CDS_PN = "BD61";
"RSVD41":   PN = "BD63"  !CDS_PN = "BD63";
"RSVD42":   PN = "BD65"  !CDS_PN = "BD65";
"RSVD47":   PN = "BE25"  !CDS_PN = "BE25";
"RSVD48":   PN = "BE62"  !CDS_PN = "BE62";
"RSVD50":   PN = "BF65"  !CDS_PN = "BF65";
"RSVD52":   PN = "BG62"  !CDS_PN = "BG62";
"RSVD53":   PN = "BG64"  !CDS_PN = "BG64";
"RSVD55":   PN = "BH63"  !CDS_PN = "BH63";
"RSVD56":   PN = "BH65"  !CDS_PN = "BH65";
"RSVD58":   PN = "BJ64"  !CDS_PN = "BJ64";
"RSVD61":   PN = "BK63"  !CDS_PN = "BK63";
"RSVD64":   PN = "BM63"  !CDS_PN = "BM63";
"RSVD86":   PN = "CD65"  !CDS_PN = "CD65";
"RSVD93":   PN = "CF63"  !CDS_PN = "CF63";
"RSVD94":   PN = "CF65"  !CDS_PN = "CF65";
"RSVD98":   PN = "CH63"  !CDS_PN = "CH63";
"RSVD100":   PN = "CH71"  !CDS_PN = "CH71";
"RSVD101":   PN = "CJ21"  !CDS_PN = "CJ21";
"RSVD102":   PN = "CJ23"  !CDS_PN = "CJ23";
"RSVD103":   PN = "CJ25"  !CDS_PN = "CJ25";
"RSVD105":   PN = "CJ66"  !CDS_PN = "CJ66";
"RSVD109":   PN = "CK22"  !CDS_PN = "CK22";
"RSVD110":   PN = "CK24"  !CDS_PN = "CK24";
"RSVD114":   PN = "CL23"  !CDS_PN = "CL23";
"RSVD117":   PN = "CL66"  !CDS_PN = "CL66";
"RSVD123":   PN = "CN21"  !CDS_PN = "CN21";
"RSVD124":   PN = "CN23"  !CDS_PN = "CN23";
"RSVD127":   PN = "CP22"  !CDS_PN = "CP22";
"RSVD128":   PN = "CP24"  !CDS_PN = "CP24";
"RSVD131":   PN = "CR21"  !CDS_PN = "CR21";
"RSVD136":   PN = "CT22"  !CDS_PN = "CT22";
"RSVD137":   PN = "CT24"  !CDS_PN = "CT24";
"RSVD140":   PN = "CV22"  !CDS_PN = "CV22";
"RSVD142":   PN = "CV69"  !CDS_PN = "CV69";
"RSVD143":   PN = "CV71"  !CDS_PN = "CV71";
"RSVD144":   PN = "CW21"  !CDS_PN = "CW21";
"RSVD155":   PN = "CY69"  !CDS_PN = "CY69";
"RSVD156":   PN = "CY71"  !CDS_PN = "CY71";
"TEST_1":   PN = "CJ64"  !CDS_PN = "CJ64";
"TEST_2":   PN = "CK65"  !CDS_PN = "CK65";
"TEST_3":   PN = "CH65"  !CDS_PN = "CH65";
"TEST_5":   PN = "CY22"  !CDS_PN = "CY22";
"TEST_6":   PN = "CF61"  !CDS_PN = "CF61";
"TEST_7":   PN = "AV69"  !CDS_PN = "AV69";
"TEST_8":   PN = "AY69"  !CDS_PN = "AY69";
DRAWING = "@s9s_mb_2u_lib.s9s_mb_2u(sch_1):page16";
BODY = "SOCKET4677_AZIF0045P001C01CS","I1": LOCATION = "U2" #&CDS_LOCATION = "U2" &SEC = "4" #&CDS_SEC = "4";
"MBP0_N":   PN = "BL23"  !CDS_PN = "BL23";
"MBP1_N":   PN = "BN25"  !CDS_PN = "BN25";
"MBP2_N":   PN = "BJ23"  !CDS_PN = "BJ23";
"MBP3_N":   PN = "BK24"  !CDS_PN = "BK24";
"PMAX_TRIGGER_IO":   PN = "BD24"  !CDS_PN = "BD24";
"RMCA_N":   PN = "BH22"  !CDS_PN = "BH22";
"VCCD_HV_SENSE":   PN = "BU11"  !CDS_PN = "BU11";
"VCCFA_EHV_FIVRA_SENSE":   PN = "AY85"  !CDS_PN = "AY85";
"VCCFA_EHV_SENSE":   PN = "AU11"  !CDS_PN = "AU11";
"VCCIN_SENSE":   PN = "BD87"  !CDS_PN = "BD87";
"VCCINFAON_SENSE":   PN = "CA11"  !CDS_PN = "CA11";
"VSS_VCCD_HV_SENSE":   PN = "BN11"  !CDS_PN = "BN11";
"VSS_VCCFA_EHV_FIVRA_SENSE":   PN = "AT85"  !CDS_PN = "AT85";
"VSS_VCCFA_EHV_SENSE":   PN = "BA11"  !CDS_PN = "BA11";
"VSS_VCCIN_SENSE":   PN = "BC90"  !CDS_PN = "BC90";
"VSS_VCCINFAON_SENSE":   PN = "CE11"  !CDS_PN = "CE11";
"RSVD7":   PN = "AU33"  !CDS_PN = "AU33";
"RSVD9":   PN = "AU56"  !CDS_PN = "AU56";
"RSVD10":   PN = "AU58"  !CDS_PN = "AU58";
"RSVD16":   PN = "AV32"  !CDS_PN = "AV32";
"RSVD17":   PN = "AV38"  !CDS_PN = "AV38";
"RSVD18":   PN = "AV40"  !CDS_PN = "AV40";
"RSVD37":   PN = "BC23"  !CDS_PN = "BC23";
"RSVD46":   PN = "BE23"  !CDS_PN = "BE23";
"RSVD49":   PN = "BF24"  !CDS_PN = "BF24";
"RSVD81":   PN = "CC64"  !CDS_PN = "CC64";
"RSVD90":   PN = "CE62"  !CDS_PN = "CE62";
"RSVD125":   PN = "CN60"  !CDS_PN = "CN60";
"RSVD129":   PN = "CP61"  !CDS_PN = "CP61";
"RSVD134":   PN = "CR60"  !CDS_PN = "CR60";
"RSVD139":   PN = "CU62"  !CDS_PN = "CU62";
"RSVD151":   PN = "CY24"  !CDS_PN = "CY24";
"RSVD152":   PN = "CY38"  !CDS_PN = "CY38";
"RSVD153":   PN = "CY49"  !CDS_PN = "CY49";
"RSVD158":   PN = "DA45"  !CDS_PN = "DA45";
"RSVD162":   PN = "H12"  !CDS_PN = "H12";
BODY = "Q_RES","I19": LOCATION = "R22" #&CDS_LOCATION = "R22" &SEC = "1" #&CDS_SEC = "1";
"A":   PN = "1"  !CDS_PN = "1";
"B":   PN = "2"  !CDS_PN = "2";
BODY = "Q_RES","I20": LOCATION = "R23" #&CDS_LOCATION = "R23" &SEC = "1" #&CDS_SEC = "1";
"A":   PN = "1"  !CDS_PN = "1";
"B":   PN = "2"  !CDS_PN = "2";
BODY = "Q_RES","I25": LOCATION = "R24" #&CDS_LOCATION = "R24" &SEC = "1" #&CDS_SEC = "1";
"A":   PN = "1"  !CDS_PN = "1";
"B":   PN = "2"  !CDS_PN = "2";
BODY = "Q_RES","I26": LOCATION = "R25" #&CDS_LOCATION = "R25" &SEC = "1" #&CDS_SEC = "1";
"A":   PN = "1"  !CDS_PN = "1";
"B":   PN = "2"  !CDS_PN = "2";
BODY = "Q_RES","I31": LOCATION = "R20" #&CDS_LOCATION = "R20" &SEC = "1" #&CDS_SEC = "1";
"A":   PN = "1"  !CDS_PN = "1";
"B":   PN = "2"  !CDS_PN = "2";
BODY = "Q_RES","I32": LOCATION = "R21" #&CDS_LOCATION = "R21" &SEC = "1" #&CDS_SEC = "1";
"A":   PN = "1"  !CDS_PN = "1";
"B":   PN = "2"  !CDS_PN = "2";
BODY = "Q_RES","I35": LOCATION = "R18" #&CDS_LOCATION = "R18" &SEC = "1" #&CDS_SEC = "1";
"A":   PN = "1"  !CDS_PN = "1";
"B":   PN = "2"  !CDS_PN = "2";
BODY = "Q_RES","I36": LOCATION = "R19" #&CDS_LOCATION = "R19" &SEC = "1" #&CDS_SEC = "1";
"A":   PN = "1"  !CDS_PN = "1";
"B":   PN = "2"  !CDS_PN = "2";
DRAWING = "@s9s_mb_2u_lib.s9s_mb_2u(sch_1):page17";
BODY = "SOCKET4677_AZIF0045P001C01CS","I1": LOCATION = "U2" #&CDS_LOCATION = "U2" &SEC = "5" #&CDS_SEC = "5";
"RSVD0":   PN = "AC78"  !CDS_PN = "AC78";
"RSVD1":   PN = "AD77"  !CDS_PN = "AD77";
"RSVD21":   PN = "AV65"  !CDS_PN = "AV65";
"RSVD26":   PN = "AY24"  !CDS_PN = "AY24";
"RSVD31":   PN = "BA25"  !CDS_PN = "BA25";
"RSVD43":   PN = "BD71"  !CDS_PN = "BD71";
"RSVD45":   PN = "BE21"  !CDS_PN = "BE21";
"RSVD51":   PN = "BF71"  !CDS_PN = "BF71";
"RSVD54":   PN = "BG78"  !CDS_PN = "BG78";
"RSVD57":   PN = "BJ21"  !CDS_PN = "BJ21";
"RSVD60":   PN = "BK22"  !CDS_PN = "BK22";
"RSVD63":   PN = "BL60"  !CDS_PN = "BL60";
"RSVD65":   PN = "BM65"  !CDS_PN = "BM65";
"RSVD67":   PN = "BP22"  !CDS_PN = "BP22";
"RSVD68":   PN = "BP65"  !CDS_PN = "BP65";
"RSVD71":   PN = "BR21"  !CDS_PN = "BR21";
"RSVD82":   PN = "CC66"  !CDS_PN = "CC66";
"RSVD83":   PN = "CD22"  !CDS_PN = "CD22";
"RSVD84":   PN = "CD26"  !CDS_PN = "CD26";
"RSVD85":   PN = "CD30"  !CDS_PN = "CD30";
"RSVD92":   PN = "CF22"  !CDS_PN = "CF22";
"RSVD99":   PN = "CH69"  !CDS_PN = "CH69";
"RSVD106":   PN = "CJ68"  !CDS_PN = "CJ68";
"RSVD107":   PN = "CJ70"  !CDS_PN = "CJ70";
"RSVD112":   PN = "CK67"  !CDS_PN = "CK67";
"RSVD133":   PN = "CR25"  !CDS_PN = "CR25";
"RSVD138":   PN = "CT26"  !CDS_PN = "CT26";
"RSVD147":   PN = "CW41"  !CDS_PN = "CW41";
"RSVD149":   PN = "CW58"  !CDS_PN = "CW58";
"RSVD154":   PN = "CY57"  !CDS_PN = "CY57";
"RSVD160":   PN = "EG17"  !CDS_PN = "EG17";
"RSVD164":   PN = "U17"  !CDS_PN = "U17";
"RSVD165":   PN = "W17"  !CDS_PN = "W17";
DRAWING = "@s9s_mb_2u_lib.s9s_mb_2u(sch_1):page18";
BODY = "SOCKET4677_AZIF0045P001C01CS","I1": LOCATION = "U2" #&CDS_LOCATION = "U2" &SEC = "6" #&CDS_SEC = "6";
"RSVD8":   PN = "AU52"  !CDS_PN = "AU52";
"RSVD44":   PN = "BD77"  !CDS_PN = "BD77";
"RSVD87":   PN = "CD69"  !CDS_PN = "CD69";
"RSVD95":   PN = "CG60"  !CDS_PN = "CG60";
"RSVD97":   PN = "CH61"  !CDS_PN = "CH61";
"RSVD111":   PN = "CK61"  !CDS_PN = "CK61";
"RSVD115":   PN = "CL60"  !CDS_PN = "CL60";
"RSVD119":   PN = "CL70"  !CDS_PN = "CL70";
"RSVD148":   PN = "CW43"  !CDS_PN = "CW43";
"RSVD159":   PN = "DA70"  !CDS_PN = "DA70";
"RSVD163":   PN = "J13"  !CDS_PN = "J13";
DRAWING = "@s9s_mb_2u_lib.s9s_mb_2u(sch_1):page19";
BODY = "SOCKET4677_AZIF0045P001C01CS","I1": LOCATION = "U2" #&CDS_LOCATION = "U2" &SEC = "7" #&CDS_SEC = "7";
"PTI_DIE000":   PN = "CC29"  !CDS_PN = "CC29";
"PTI_DIE00_STB_0":   PN = "CB30"  !CDS_PN = "CB30";
"PTI_DIE00_STB_1":   PN = "BY28"  !CDS_PN = "BY28";
"PTI_DIE001":   PN = "CD28"  !CDS_PN = "CD28";
"PTI_DIE01_STB_0":   PN = "BF67"  !CDS_PN = "BF67";
"PTI_DIE01_STB_1":   PN = "BK67"  !CDS_PN = "BK67";
"PTI_DIE002":   PN = "CC27"  !CDS_PN = "CC27";
"PTI_DIE003":   PN = "BY30"  !CDS_PN = "BY30";
"PTI_DIE004":   PN = "CA29"  !CDS_PN = "CA29";
"PTI_DIE005":   PN = "BV30"  !CDS_PN = "BV30";
"PTI_DIE006":   PN = "CA27"  !CDS_PN = "CA27";
"PTI_DIE007":   PN = "BV28"  !CDS_PN = "BV28";
"PTI_DIE008":   PN = "BU27"  !CDS_PN = "BU27";
"PTI_DIE009":   PN = "BT28"  !CDS_PN = "BT28";
"PTI_DIE0010":   PN = "BU29"  !CDS_PN = "BU29";
"PTI_DIE010":   PN = "BC70"  !CDS_PN = "BC70";
"PTI_DIE0011":   PN = "BT30"  !CDS_PN = "BT30";
"PTI_DIE011":   PN = "BE70"  !CDS_PN = "BE70";
"PTI_DIE0012":   PN = "BN27"  !CDS_PN = "BN27";
"PTI_DIE012":   PN = "BD69"  !CDS_PN = "BD69";
"PTI_DIE0013":   PN = "BP28"  !CDS_PN = "BP28";
"PTI_DIE013":   PN = "BF69"  !CDS_PN = "BF69";
"PTI_DIE0014":   PN = "BN29"  !CDS_PN = "BN29";
"PTI_DIE014":   PN = "BH69"  !CDS_PN = "BH69";
"PTI_DIE0015":   PN = "BP30"  !CDS_PN = "BP30";
"PTI_DIE015":   PN = "BC68"  !CDS_PN = "BC68";
"PTI_DIE016":   PN = "BG68"  !CDS_PN = "BG68";
"PTI_DIE017":   PN = "BD67"  !CDS_PN = "BD67";
"PTI_DIE018":   PN = "BK69"  !CDS_PN = "BK69";
"PTI_DIE019":   PN = "BM69"  !CDS_PN = "BM69";
"PTI_DIE0110":   PN = "BN68"  !CDS_PN = "BN68";
"PTI_DIE0111":   PN = "BG66"  !CDS_PN = "BG66";
"PTI_DIE0112":   PN = "BJ66"  !CDS_PN = "BJ66";
"PTI_DIE0113":   PN = "BL66"  !CDS_PN = "BL66";
"PTI_DIE0114":   PN = "BM67"  !CDS_PN = "BM67";
"PTI_DIE0115":   PN = "BN66"  !CDS_PN = "BN66";
"UPI0_AC_COUPLING":   PN = "BA23"  !CDS_PN = "BA23";
"UPI1_AC_COUPLING":   PN = "CW19"  !CDS_PN = "CW19";
"UPI2_AC_COUPLING":   PN = "BB65"  !CDS_PN = "BB65";
"UPI3_AC_COUPLING":   PN = "CK71"  !CDS_PN = "CK71";
"RSVD2":   PN = "AN17"  !CDS_PN = "AN17";
"RSVD3":   PN = "AR17"  !CDS_PN = "AR17";
"RSVD5":   PN = "AT67"  !CDS_PN = "AT67";
"RSVD13":   PN = "AU66"  !CDS_PN = "AU66";
"RSVD14":   PN = "AU68"  !CDS_PN = "AU68";
"RSVD22":   PN = "AV67"  !CDS_PN = "AV67";
"RSVD62":   PN = "BL21"  !CDS_PN = "BL21";
"RSVD66":   PN = "BN21"  !CDS_PN = "BN21";
"RSVD73":   PN = "BV22"  !CDS_PN = "BV22";
"RSVD74":   PN = "BW21"  !CDS_PN = "BW21";
"RSVD75":   PN = "BW23"  !CDS_PN = "BW23";
"RSVD77":   PN = "CA21"  !CDS_PN = "CA21";
"RSVD78":   PN = "CA23"  !CDS_PN = "CA23";
"RSVD79":   PN = "CC21"  !CDS_PN = "CC21";
"RSVD80":   PN = "CC23"  !CDS_PN = "CC23";
"RSVD89":   PN = "CE21"  !CDS_PN = "CE21";
"RSVD118":   PN = "CL68"  !CDS_PN = "CL68";
"RSVD122":   PN = "CM69"  !CDS_PN = "CM69";
"RSVD130":   PN = "CP69"  !CDS_PN = "CP69";
"RSVD135":   PN = "CR68"  !CDS_PN = "CR68";
DRAWING = "@s9s_mb_2u_lib.s9s_mb_2u(sch_1):page20";
BODY = "SOCKET4677_AZIF0045P001C01CS","I1": LOCATION = "U2" #&CDS_LOCATION = "U2" &SEC = "8" #&CDS_SEC = "8";
"DDR0_A_RSP0":   PN = "AT42"  !CDS_PN = "AT42";
"DDR0_A_RSP1":   PN = "AU43"  !CDS_PN = "AU43";
"DDR0_ALERT_N":   PN = "AT49"  !CDS_PN = "AT49";
"DDR0_B_RSP0":   PN = "AV44"  !CDS_PN = "AV44";
"DDR0_B_RSP1":   PN = "AV42"  !CDS_PN = "AV42";
"DDR0_CLK_DN0":   PN = "B44"  !CDS_PN = "B44";
"DDR0_CLK_DN1":   PN = "G45"  !CDS_PN = "G45";
"DDR0_CLK_DP0":   PN = "C43"  !CDS_PN = "C43";
"DDR0_CLK_DP1":   PN = "E45"  !CDS_PN = "E45";
"DDR0_SA_CA0":   PN = "A52"  !CDS_PN = "A52";
"DDR0_SA_CA1":   PN = "G52"  !CDS_PN = "G52";
"DDR0_SA_CA2":   PN = "B51"  !CDS_PN = "B51";
"DDR0_SA_CA3":   PN = "F51"  !CDS_PN = "F51";
"DDR0_SA_CA4":   PN = "C50"  !CDS_PN = "C50";
"DDR0_SA_CA5":   PN = "E50"  !CDS_PN = "E50";
"DDR0_SA_CA6":   PN = "C48"  !CDS_PN = "C48";
"DDR0_SA_DQ0":   PN = "B81"  !CDS_PN = "B81";
"DDR0_SA_DQ1":   PN = "B79"  !CDS_PN = "B79";
"DDR0_SA_DQ2":   PN = "M77"  !CDS_PN = "M77";
"DDR0_SA_DQ3":   PN = "G78"  !CDS_PN = "G78";
"DDR0_SA_DQ4":   PN = "C76"  !CDS_PN = "C76";
"DDR0_SA_DQ5":   PN = "D75"  !CDS_PN = "D75";
"DDR0_SA_DQ6":   PN = "G76"  !CDS_PN = "G76";
"DDR0_SA_DQ7":   PN = "F75"  !CDS_PN = "F75";
"DDR0_SA_DQ8":   PN = "K69"  !CDS_PN = "K69";
"DDR0_SA_DQ9":   PN = "J68"  !CDS_PN = "J68";
"DDR0_SA_DQ10":   PN = "M69"  !CDS_PN = "M69";
"DDR0_SA_DQ11":   PN = "N68"  !CDS_PN = "N68";
"DDR0_SA_DQ12":   PN = "J66"  !CDS_PN = "J66";
"DDR0_SA_DQ13":   PN = "K65"  !CDS_PN = "K65";
"DDR0_SA_DQ14":   PN = "N66"  !CDS_PN = "N66";
"DDR0_SA_DQ15":   PN = "M65"  !CDS_PN = "M65";
"DDR0_SA_DQ16":   PN = "B73"  !CDS_PN = "B73";
"DDR0_SA_DQ17":   PN = "E72"  !CDS_PN = "E72";
"DDR0_SA_DQ18":   PN = "D73"  !CDS_PN = "D73";
"DDR0_SA_DQ19":   PN = "F71"  !CDS_PN = "F71";
"DDR0_SA_DQ20":   PN = "B69"  !CDS_PN = "B69";
"DDR0_SA_DQ21":   PN = "C68"  !CDS_PN = "C68";
"DDR0_SA_DQ22":   PN = "F69"  !CDS_PN = "F69";
"DDR0_SA_DQ23":   PN = "E68"  !CDS_PN = "E68";
"DDR0_SA_DQ24":   PN = "C66"  !CDS_PN = "C66";
"DDR0_SA_DQ25":   PN = "B65"  !CDS_PN = "B65";
"DDR0_SA_DQ26":   PN = "E66"  !CDS_PN = "E66";
"DDR0_SA_DQ27":   PN = "F65"  !CDS_PN = "F65";
"DDR0_SA_DQ28":   PN = "B63"  !CDS_PN = "B63";
"DDR0_SA_DQ29":   PN = "C62"  !CDS_PN = "C62";
"DDR0_SA_DQ30":   PN = "F63"  !CDS_PN = "F63";
"DDR0_SA_DQ31":   PN = "E62"  !CDS_PN = "E62";
"DDR0_SA_DQS_DN0":   PN = "B77"  !CDS_PN = "B77";
"DDR0_SA_DQS_DN1":   PN = "H67"  !CDS_PN = "H67";
"DDR0_SA_DQS_DN2":   PN = "B71"  !CDS_PN = "B71";
"DDR0_SA_DQS_DN3":   PN = "A64"  !CDS_PN = "A64";
"DDR0_SA_DQS_DN4":   PN = "A58"  !CDS_PN = "A58";
"DDR0_SA_DQS_DN5":   PN = "H77"  !CDS_PN = "H77";
"DDR0_SA_DQS_DN6":   PN = "P67"  !CDS_PN = "P67";
"DDR0_SA_DQS_DN7":   PN = "G70"  !CDS_PN = "G70";
"DDR0_SA_DQS_DN8":   PN = "G64"  !CDS_PN = "G64";
"DDR0_SA_DQS_DN9":   PN = "G58"  !CDS_PN = "G58";
"DDR0_SA_DQS_DP0":   PN = "D77"  !CDS_PN = "D77";
"DDR0_SA_DQS_DP1":   PN = "K67"  !CDS_PN = "K67";
"DDR0_SA_DQS_DP2":   PN = "C70"  !CDS_PN = "C70";
"DDR0_SA_DQS_DP3":   PN = "C64"  !CDS_PN = "C64";
"DDR0_SA_DQS_DP4":   PN = "C58"  !CDS_PN = "C58";
"DDR0_SA_DQS_DP5":   PN = "F77"  !CDS_PN = "F77";
"DDR0_SA_DQS_DP6":   PN = "M67"  !CDS_PN = "M67";
"DDR0_SA_DQS_DP7":   PN = "E70"  !CDS_PN = "E70";
"DDR0_SA_DQS_DP8":   PN = "E64"  !CDS_PN = "E64";
"DDR0_SA_DQS_DP9":   PN = "E58"  !CDS_PN = "E58";
"DDR0_SA_ECC0":   PN = "C60"  !CDS_PN = "C60";
"DDR0_SA_ECC1":   PN = "B59"  !CDS_PN = "B59";
"DDR0_SA_ECC2":   PN = "E60"  !CDS_PN = "E60";
"DDR0_SA_ECC3":   PN = "F59"  !CDS_PN = "F59";
"DDR0_SA_ECC4":   PN = "B57"  !CDS_PN = "B57";
"DDR0_SA_ECC5":   PN = "C56"  !CDS_PN = "C56";
"DDR0_SA_ECC6":   PN = "F57"  !CDS_PN = "F57";
"DDR0_SA_ECC7":   PN = "E56"  !CDS_PN = "E56";
"DDR0_SA_PAR":   PN = "E48"  !CDS_PN = "E48";
"DDR0_SB_CA0":   PN = "E43"  !CDS_PN = "E43";
"DDR0_SB_CA1":   PN = "F44"  !CDS_PN = "F44";
"DDR0_SB_CA2":   PN = "C41"  !CDS_PN = "C41";
"DDR0_SB_CA3":   PN = "E41"  !CDS_PN = "E41";
"DDR0_SB_CA4":   PN = "B40"  !CDS_PN = "B40";
"DDR0_SB_CA5":   PN = "F40"  !CDS_PN = "F40";
"DDR0_SB_CA6":   PN = "A39"  !CDS_PN = "A39";
"DDR0_SB_DQ0":   PN = "K32"  !CDS_PN = "K32";
"DDR0_SB_DQ1":   PN = "J31"  !CDS_PN = "J31";
"DDR0_SB_DQ2":   PN = "M32"  !CDS_PN = "M32";
"DDR0_SB_DQ3":   PN = "N31"  !CDS_PN = "N31";
"DDR0_SB_DQ4":   PN = "J29"  !CDS_PN = "J29";
"DDR0_SB_DQ5":   PN = "K28"  !CDS_PN = "K28";
"DDR0_SB_DQ6":   PN = "N29"  !CDS_PN = "N29";
"DDR0_SB_DQ7":   PN = "M28"  !CDS_PN = "M28";
"DDR0_SB_DQ8":   PN = "C29"  !CDS_PN = "C29";
"DDR0_SB_DQ9":   PN = "B28"  !CDS_PN = "B28";
"DDR0_SB_DQ10":   PN = "E29"  !CDS_PN = "E29";
"DDR0_SB_DQ11":   PN = "F28"  !CDS_PN = "F28";
"DDR0_SB_DQ12":   PN = "B26"  !CDS_PN = "B26";
"DDR0_SB_DQ13":   PN = "C25"  !CDS_PN = "C25";
"DDR0_SB_DQ14":   PN = "F26"  !CDS_PN = "F26";
"DDR0_SB_DQ15":   PN = "E25"  !CDS_PN = "E25";
"DDR0_SB_DQ16":   PN = "C23"  !CDS_PN = "C23";
"DDR0_SB_DQ17":   PN = "B22"  !CDS_PN = "B22";
"DDR0_SB_DQ18":   PN = "E23"  !CDS_PN = "E23";
"DDR0_SB_DQ19":   PN = "F22"  !CDS_PN = "F22";
"DDR0_SB_DQ20":   PN = "B20"  !CDS_PN = "B20";
"DDR0_SB_DQ21":   PN = "C19"  !CDS_PN = "C19";
"DDR0_SB_DQ22":   PN = "F20"  !CDS_PN = "F20";
"DDR0_SB_DQ23":   PN = "E19"  !CDS_PN = "E19";
"DDR0_SB_DQ24":   PN = "C11"  !CDS_PN = "C11";
"DDR0_SB_DQ25":   PN = "B10"  !CDS_PN = "B10";
"DDR0_SB_DQ26":   PN = "E11"  !CDS_PN = "E11";
"DDR0_SB_DQ27":   PN = "F10"  !CDS_PN = "F10";
"DDR0_SB_DQ28":   PN = "B8"  !CDS_PN = "B8";
"DDR0_SB_DQ29":   PN = "C7"  !CDS_PN = "C7";
"DDR0_SB_DQ30":   PN = "F8"  !CDS_PN = "F8";
"DDR0_SB_DQ31":   PN = "E7"  !CDS_PN = "E7";
"DDR0_SB_DQS_DN0":   PN = "H30"  !CDS_PN = "H30";
"DDR0_SB_DQS_DN1":   PN = "A27"  !CDS_PN = "A27";
"DDR0_SB_DQS_DN2":   PN = "A21"  !CDS_PN = "A21";
"DDR0_SB_DQS_DN3":   PN = "A9"  !CDS_PN = "A9";
"DDR0_SB_DQS_DN4":   PN = "G33"  !CDS_PN = "G33";
"DDR0_SB_DQS_DN5":   PN = "M30"  !CDS_PN = "M30";
"DDR0_SB_DQS_DN6":   PN = "G27"  !CDS_PN = "G27";
"DDR0_SB_DQS_DN7":   PN = "G21"  !CDS_PN = "G21";
"DDR0_SB_DQS_DN8":   PN = "G9"  !CDS_PN = "G9";
"DDR0_SB_DQS_DN9":   PN = "A33"  !CDS_PN = "A33";
"DDR0_SB_DQS_DP0":   PN = "K30"  !CDS_PN = "K30";
"DDR0_SB_DQS_DP1":   PN = "C27"  !CDS_PN = "C27";
"DDR0_SB_DQS_DP2":   PN = "C21"  !CDS_PN = "C21";
"DDR0_SB_DQS_DP3":   PN = "C9"  !CDS_PN = "C9";
"DDR0_SB_DQS_DP4":   PN = "E33"  !CDS_PN = "E33";
"DDR0_SB_DQS_DP5":   PN = "P30"  !CDS_PN = "P30";
"DDR0_SB_DQS_DP6":   PN = "E27"  !CDS_PN = "E27";
"DDR0_SB_DQS_DP7":   PN = "E21"  !CDS_PN = "E21";
"DDR0_SB_DQS_DP8":   PN = "E9"  !CDS_PN = "E9";
"DDR0_SB_DQS_DP9":   PN = "C33"  !CDS_PN = "C33";
"DDR0_SB_ECC0":   PN = "B32"  !CDS_PN = "B32";
"DDR0_SB_ECC1":   PN = "C31"  !CDS_PN = "C31";
"DDR0_SB_ECC2":   PN = "F32"  !CDS_PN = "F32";
"DDR0_SB_ECC3":   PN = "E31"  !CDS_PN = "E31";
"DDR0_SB_ECC4":   PN = "C35"  !CDS_PN = "C35";
"DDR0_SB_ECC5":   PN = "B34"  !CDS_PN = "B34";
"DDR0_SB_ECC6":   PN = "E35"  !CDS_PN = "E35";
"DDR0_SB_ECC7":   PN = "F34"  !CDS_PN = "F34";
"DDR0_SB_PAR":   PN = "G39"  !CDS_PN = "G39";
"DDR0_SA_CS_N0":   PN = "C54"  !CDS_PN = "C54";
"DDR0_SA_CS_N1":   PN = "B53"  !CDS_PN = "B53";
"DDR0_SA_CS_N2":   PN = "E54"  !CDS_PN = "E54";
"DDR0_SA_CS_N3":   PN = "F53"  !CDS_PN = "F53";
"DDR0_SB_CS_N0":   PN = "B38"  !CDS_PN = "B38";
"DDR0_SB_CS_N1":   PN = "C37"  !CDS_PN = "C37";
"DDR0_SB_CS_N2":   PN = "F38"  !CDS_PN = "F38";
"DDR0_SB_CS_N3":   PN = "E37"  !CDS_PN = "E37";
DRAWING = "@s9s_mb_2u_lib.s9s_mb_2u(sch_1):page21";
BODY = "SOCKET4677_AZIF0045P001C01CS","I169": LOCATION = "U2" #&CDS_LOCATION = "U2" &SEC = "9" #&CDS_SEC = "9";
"DDR1_A_RSP0":   PN = "AL48"  !CDS_PN = "AL48";
"DDR1_A_RSP1":   PN = "AK47"  !CDS_PN = "AK47";
"DDR1_ALERT_N":   PN = "AV49"  !CDS_PN = "AV49";
"DDR1_B_RSP0":   PN = "AN48"  !CDS_PN = "AN48";
"DDR1_B_RSP1":   PN = "AP47"  !CDS_PN = "AP47";
"DDR1_CLK_DN0":   PN = "R45"  !CDS_PN = "R45";
"DDR1_CLK_DN1":   PN = "W45"  !CDS_PN = "W45";
"DDR1_CLK_DP0":   PN = "U45"  !CDS_PN = "U45";
"DDR1_CLK_DP1":   PN = "AA45"  !CDS_PN = "AA45";
"DDR1_SA_CA0":   PN = "H49"  !CDS_PN = "H49";
"DDR1_SA_CA1":   PN = "P49"  !CDS_PN = "P49";
"DDR1_SA_CA2":   PN = "J48"  !CDS_PN = "J48";
"DDR1_SA_CA3":   PN = "N48"  !CDS_PN = "N48";
"DDR1_SA_CA4":   PN = "K47"  !CDS_PN = "K47";
"DDR1_SA_CA5":   PN = "M47"  !CDS_PN = "M47";
"DDR1_SA_CA6":   PN = "Y44"  !CDS_PN = "Y44";
"DDR1_SA_DQ0":   PN = "K75"  !CDS_PN = "K75";
"DDR1_SA_DQ1":   PN = "J74"  !CDS_PN = "J74";
"DDR1_SA_DQ2":   PN = "M75"  !CDS_PN = "M75";
"DDR1_SA_DQ3":   PN = "N74"  !CDS_PN = "N74";
"DDR1_SA_DQ4":   PN = "J72"  !CDS_PN = "J72";
"DDR1_SA_DQ5":   PN = "K71"  !CDS_PN = "K71";
"DDR1_SA_DQ6":   PN = "N72"  !CDS_PN = "N72";
"DDR1_SA_DQ7":   PN = "M71"  !CDS_PN = "M71";
"DDR1_SA_DQ8":   PN = "U72"  !CDS_PN = "U72";
"DDR1_SA_DQ9":   PN = "T71"  !CDS_PN = "T71";
"DDR1_SA_DQ10":   PN = "W72"  !CDS_PN = "W72";
"DDR1_SA_DQ11":   PN = "Y71"  !CDS_PN = "Y71";
"DDR1_SA_DQ12":   PN = "T69"  !CDS_PN = "T69";
"DDR1_SA_DQ13":   PN = "U68"  !CDS_PN = "U68";
"DDR1_SA_DQ14":   PN = "Y69"  !CDS_PN = "Y69";
"DDR1_SA_DQ15":   PN = "W68"  !CDS_PN = "W68";
"DDR1_SA_DQ16":   PN = "K63"  !CDS_PN = "K63";
"DDR1_SA_DQ17":   PN = "J62"  !CDS_PN = "J62";
"DDR1_SA_DQ18":   PN = "M63"  !CDS_PN = "M63";
"DDR1_SA_DQ19":   PN = "N62"  !CDS_PN = "N62";
"DDR1_SA_DQ20":   PN = "J60"  !CDS_PN = "J60";
"DDR1_SA_DQ21":   PN = "K59"  !CDS_PN = "K59";
"DDR1_SA_DQ22":   PN = "N60"  !CDS_PN = "N60";
"DDR1_SA_DQ23":   PN = "M59"  !CDS_PN = "M59";
"DDR1_SA_DQ24":   PN = "U60"  !CDS_PN = "U60";
"DDR1_SA_DQ25":   PN = "T59"  !CDS_PN = "T59";
"DDR1_SA_DQ26":   PN = "W60"  !CDS_PN = "W60";
"DDR1_SA_DQ27":   PN = "Y59"  !CDS_PN = "Y59";
"DDR1_SA_DQ28":   PN = "T57"  !CDS_PN = "T57";
"DDR1_SA_DQ29":   PN = "U56"  !CDS_PN = "U56";
"DDR1_SA_DQ30":   PN = "Y57"  !CDS_PN = "Y57";
"DDR1_SA_DQ31":   PN = "W56"  !CDS_PN = "W56";
"DDR1_SA_DQS_DN0":   PN = "H73"  !CDS_PN = "H73";
"DDR1_SA_DQS_DN1":   PN = "R70"  !CDS_PN = "R70";
"DDR1_SA_DQS_DN2":   PN = "H61"  !CDS_PN = "H61";
"DDR1_SA_DQS_DN3":   PN = "R58"  !CDS_PN = "R58";
"DDR1_SA_DQS_DN4":   PN = "H55"  !CDS_PN = "H55";
"DDR1_SA_DQS_DN5":   PN = "M73"  !CDS_PN = "M73";
"DDR1_SA_DQS_DN6":   PN = "AA70"  !CDS_PN = "AA70";
"DDR1_SA_DQS_DN7":   PN = "M61"  !CDS_PN = "M61";
"DDR1_SA_DQS_DN8":   PN = "AA58"  !CDS_PN = "AA58";
"DDR1_SA_DQS_DN9":   PN = "M55"  !CDS_PN = "M55";
"DDR1_SA_DQS_DP0":   PN = "K73"  !CDS_PN = "K73";
"DDR1_SA_DQS_DP1":   PN = "U70"  !CDS_PN = "U70";
"DDR1_SA_DQS_DP2":   PN = "K61"  !CDS_PN = "K61";
"DDR1_SA_DQS_DP3":   PN = "U58"  !CDS_PN = "U58";
"DDR1_SA_DQS_DP4":   PN = "K55"  !CDS_PN = "K55";
"DDR1_SA_DQS_DP5":   PN = "P73"  !CDS_PN = "P73";
"DDR1_SA_DQS_DP6":   PN = "W70"  !CDS_PN = "W70";
"DDR1_SA_DQS_DP7":   PN = "P61"  !CDS_PN = "P61";
"DDR1_SA_DQS_DP8":   PN = "W58"  !CDS_PN = "W58";
"DDR1_SA_DQS_DP9":   PN = "P55"  !CDS_PN = "P55";
"DDR1_SA_ECC0":   PN = "K57"  !CDS_PN = "K57";
"DDR1_SA_ECC1":   PN = "J56"  !CDS_PN = "J56";
"DDR1_SA_ECC2":   PN = "M57"  !CDS_PN = "M57";
"DDR1_SA_ECC3":   PN = "N56"  !CDS_PN = "N56";
"DDR1_SA_ECC4":   PN = "J54"  !CDS_PN = "J54";
"DDR1_SA_ECC5":   PN = "K53"  !CDS_PN = "K53";
"DDR1_SA_ECC6":   PN = "N54"  !CDS_PN = "N54";
"DDR1_SA_ECC7":   PN = "M53"  !CDS_PN = "M53";
"DDR1_SA_PAR":   PN = "W43"  !CDS_PN = "W43";
"DDR1_SB_CA0":   PN = "T44"  !CDS_PN = "T44";
"DDR1_SB_CA1":   PN = "U43"  !CDS_PN = "U43";
"DDR1_SB_CA2":   PN = "K44"  !CDS_PN = "K44";
"DDR1_SB_CA3":   PN = "M44"  !CDS_PN = "M44";
"DDR1_SB_CA4":   PN = "J43"  !CDS_PN = "J43";
"DDR1_SB_CA5":   PN = "N43"  !CDS_PN = "N43";
"DDR1_SB_CA6":   PN = "H42"  !CDS_PN = "H42";
"DDR1_SB_DQ0":   PN = "U29"  !CDS_PN = "U29";
"DDR1_SB_DQ1":   PN = "T28"  !CDS_PN = "T28";
"DDR1_SB_DQ2":   PN = "W29"  !CDS_PN = "W29";
"DDR1_SB_DQ3":   PN = "Y28"  !CDS_PN = "Y28";
"DDR1_SB_DQ4":   PN = "T26"  !CDS_PN = "T26";
"DDR1_SB_DQ5":   PN = "U25"  !CDS_PN = "U25";
"DDR1_SB_DQ6":   PN = "Y26"  !CDS_PN = "Y26";
"DDR1_SB_DQ7":   PN = "W25"  !CDS_PN = "W25";
"DDR1_SB_DQ8":   PN = "K26"  !CDS_PN = "K26";
"DDR1_SB_DQ9":   PN = "J25"  !CDS_PN = "J25";
"DDR1_SB_DQ10":   PN = "M26"  !CDS_PN = "M26";
"DDR1_SB_DQ11":   PN = "N25"  !CDS_PN = "N25";
"DDR1_SB_DQ12":   PN = "J23"  !CDS_PN = "J23";
"DDR1_SB_DQ13":   PN = "K22"  !CDS_PN = "K22";
"DDR1_SB_DQ14":   PN = "N23"  !CDS_PN = "N23";
"DDR1_SB_DQ15":   PN = "M22"  !CDS_PN = "M22";
"DDR1_SB_DQ16":   PN = "K20"  !CDS_PN = "K20";
"DDR1_SB_DQ17":   PN = "J19"  !CDS_PN = "J19";
"DDR1_SB_DQ18":   PN = "M20"  !CDS_PN = "M20";
"DDR1_SB_DQ19":   PN = "N19"  !CDS_PN = "N19";
"DDR1_SB_DQ20":   PN = "J17"  !CDS_PN = "J17";
"DDR1_SB_DQ21":   PN = "K16"  !CDS_PN = "K16";
"DDR1_SB_DQ22":   PN = "N17"  !CDS_PN = "N17";
"DDR1_SB_DQ23":   PN = "M16"  !CDS_PN = "M16";
"DDR1_SB_DQ24":   PN = "C17"  !CDS_PN = "C17";
"DDR1_SB_DQ25":   PN = "B16"  !CDS_PN = "B16";
"DDR1_SB_DQ26":   PN = "E17"  !CDS_PN = "E17";
"DDR1_SB_DQ27":   PN = "F16"  !CDS_PN = "F16";
"DDR1_SB_DQ28":   PN = "C13"  !CDS_PN = "C13";
"DDR1_SB_DQ29":   PN = "E13"  !CDS_PN = "E13";
"DDR1_SB_DQ30":   PN = "B14"  !CDS_PN = "B14";
"DDR1_SB_DQ31":   PN = "F14"  !CDS_PN = "F14";
"DDR1_SB_DQS_DN0":   PN = "R27"  !CDS_PN = "R27";
"DDR1_SB_DQS_DN1":   PN = "H24"  !CDS_PN = "H24";
"DDR1_SB_DQS_DN2":   PN = "H18"  !CDS_PN = "H18";
"DDR1_SB_DQS_DN3":   PN = "A15"  !CDS_PN = "A15";
"DDR1_SB_DQS_DN4":   PN = "P36"  !CDS_PN = "P36";
"DDR1_SB_DQS_DN5":   PN = "W27"  !CDS_PN = "W27";
"DDR1_SB_DQS_DN6":   PN = "M24"  !CDS_PN = "M24";
"DDR1_SB_DQS_DN7":   PN = "M18"  !CDS_PN = "M18";
"DDR1_SB_DQS_DN8":   PN = "E15"  !CDS_PN = "E15";
"DDR1_SB_DQS_DN9":   PN = "K36"  !CDS_PN = "K36";
"DDR1_SB_DQS_DP0":   PN = "U27"  !CDS_PN = "U27";
"DDR1_SB_DQS_DP1":   PN = "K24"  !CDS_PN = "K24";
"DDR1_SB_DQS_DP2":   PN = "K18"  !CDS_PN = "K18";
"DDR1_SB_DQS_DP3":   PN = "C15"  !CDS_PN = "C15";
"DDR1_SB_DQS_DP4":   PN = "M36"  !CDS_PN = "M36";
"DDR1_SB_DQS_DP5":   PN = "AA27"  !CDS_PN = "AA27";
"DDR1_SB_DQS_DP6":   PN = "P24"  !CDS_PN = "P24";
"DDR1_SB_DQS_DP7":   PN = "P18"  !CDS_PN = "P18";
"DDR1_SB_DQS_DP8":   PN = "G15"  !CDS_PN = "G15";
"DDR1_SB_DQS_DP9":   PN = "H36"  !CDS_PN = "H36";
"DDR1_SB_ECC0":   PN = "J35"  !CDS_PN = "J35";
"DDR1_SB_ECC1":   PN = "K34"  !CDS_PN = "K34";
"DDR1_SB_ECC2":   PN = "N35"  !CDS_PN = "N35";
"DDR1_SB_ECC3":   PN = "M34"  !CDS_PN = "M34";
"DDR1_SB_ECC4":   PN = "K38"  !CDS_PN = "K38";
"DDR1_SB_ECC5":   PN = "J37"  !CDS_PN = "J37";
"DDR1_SB_ECC6":   PN = "M38"  !CDS_PN = "M38";
"DDR1_SB_ECC7":   PN = "N37"  !CDS_PN = "N37";
"DDR1_SB_PAR":   PN = "P42"  !CDS_PN = "P42";
"DDR1_SA_CS_N0":   PN = "K51"  !CDS_PN = "K51";
"DDR1_SA_CS_N1":   PN = "J50"  !CDS_PN = "J50";
"DDR1_SA_CS_N2":   PN = "M51"  !CDS_PN = "M51";
"DDR1_SA_CS_N3":   PN = "N50"  !CDS_PN = "N50";
"DDR1_SB_CS_N0":   PN = "J41"  !CDS_PN = "J41";
"DDR1_SB_CS_N1":   PN = "K40"  !CDS_PN = "K40";
"DDR1_SB_CS_N2":   PN = "N41"  !CDS_PN = "N41";
"DDR1_SB_CS_N3":   PN = "M40"  !CDS_PN = "M40";
DRAWING = "@s9s_mb_2u_lib.s9s_mb_2u(sch_1):page22";
BODY = "SOCKET4677_AZIF0045P001C01CS","I169": LOCATION = "U2" #&CDS_LOCATION = "U2" &SEC = "10" #&CDS_SEC = "10";
"DDR2_A_RSP0":   PN = "AC48"  !CDS_PN = "AC48";
"DDR2_A_RSP1":   PN = "AD47"  !CDS_PN = "AD47";
"DDR2_ALERT_N":   PN = "AT47"  !CDS_PN = "AT47";
"DDR2_B_RSP0":   PN = "AG48"  !CDS_PN = "AG48";
"DDR2_B_RSP1":   PN = "AF47"  !CDS_PN = "AF47";
"DDR2_CLK_DN0":   PN = "AB49"  !CDS_PN = "AB49";
"DDR2_CLK_DN1":   PN = "AF49"  !CDS_PN = "AF49";
"DDR2_CLK_DP0":   PN = "AD49"  !CDS_PN = "AD49";
"DDR2_CLK_DP1":   PN = "AH49"  !CDS_PN = "AH49";
"DDR2_SA_CA0":   PN = "R52"  !CDS_PN = "R52";
"DDR2_SA_CA1":   PN = "AA52"  !CDS_PN = "AA52";
"DDR2_SA_CA2":   PN = "T51"  !CDS_PN = "T51";
"DDR2_SA_CA3":   PN = "Y51"  !CDS_PN = "Y51";
"DDR2_SA_CA4":   PN = "U50"  !CDS_PN = "U50";
"DDR2_SA_CA5":   PN = "W50"  !CDS_PN = "W50";
"DDR2_SA_CA6":   PN = "U48"  !CDS_PN = "U48";
"DDR2_SA_DQ0":   PN = "U78"  !CDS_PN = "U78";
"DDR2_SA_DQ1":   PN = "T77"  !CDS_PN = "T77";
"DDR2_SA_DQ2":   PN = "W78"  !CDS_PN = "W78";
"DDR2_SA_DQ3":   PN = "Y77"  !CDS_PN = "Y77";
"DDR2_SA_DQ4":   PN = "T75"  !CDS_PN = "T75";
"DDR2_SA_DQ5":   PN = "U74"  !CDS_PN = "U74";
"DDR2_SA_DQ6":   PN = "Y75"  !CDS_PN = "Y75";
"DDR2_SA_DQ7":   PN = "W74"  !CDS_PN = "W74";
"DDR2_SA_DQ8":   PN = "AD69"  !CDS_PN = "AD69";
"DDR2_SA_DQ9":   PN = "AC68"  !CDS_PN = "AC68";
"DDR2_SA_DQ10":   PN = "AF69"  !CDS_PN = "AF69";
"DDR2_SA_DQ11":   PN = "AG68"  !CDS_PN = "AG68";
"DDR2_SA_DQ12":   PN = "AC66"  !CDS_PN = "AC66";
"DDR2_SA_DQ13":   PN = "AD65"  !CDS_PN = "AD65";
"DDR2_SA_DQ14":   PN = "AG66"  !CDS_PN = "AG66";
"DDR2_SA_DQ15":   PN = "AF65"  !CDS_PN = "AF65";
"DDR2_SA_DQ16":   PN = "U66"  !CDS_PN = "U66";
"DDR2_SA_DQ17":   PN = "T65"  !CDS_PN = "T65";
"DDR2_SA_DQ18":   PN = "W66"  !CDS_PN = "W66";
"DDR2_SA_DQ19":   PN = "Y65"  !CDS_PN = "Y65";
"DDR2_SA_DQ20":   PN = "T63"  !CDS_PN = "T63";
"DDR2_SA_DQ21":   PN = "U62"  !CDS_PN = "U62";
"DDR2_SA_DQ22":   PN = "Y63"  !CDS_PN = "Y63";
"DDR2_SA_DQ23":   PN = "W62"  !CDS_PN = "W62";
"DDR2_SA_DQ24":   PN = "AD63"  !CDS_PN = "AD63";
"DDR2_SA_DQ25":   PN = "AC62"  !CDS_PN = "AC62";
"DDR2_SA_DQ26":   PN = "AF63"  !CDS_PN = "AF63";
"DDR2_SA_DQ27":   PN = "AG62"  !CDS_PN = "AG62";
"DDR2_SA_DQ28":   PN = "AC60"  !CDS_PN = "AC60";
"DDR2_SA_DQ29":   PN = "AD59"  !CDS_PN = "AD59";
"DDR2_SA_DQ30":   PN = "AG60"  !CDS_PN = "AG60";
"DDR2_SA_DQ31":   PN = "AF59"  !CDS_PN = "AF59";
"DDR2_SA_DQS_DN0":   PN = "R76"  !CDS_PN = "R76";
"DDR2_SA_DQS_DN1":   PN = "AB67"  !CDS_PN = "AB67";
"DDR2_SA_DQS_DN2":   PN = "R64"  !CDS_PN = "R64";
"DDR2_SA_DQS_DN3":   PN = "AB61"  !CDS_PN = "AB61";
"DDR2_SA_DQS_DN4":   PN = "AD55"  !CDS_PN = "AD55";
"DDR2_SA_DQS_DN5":   PN = "W76"  !CDS_PN = "W76";
"DDR2_SA_DQS_DN6":   PN = "AH67"  !CDS_PN = "AH67";
"DDR2_SA_DQS_DN7":   PN = "AA64"  !CDS_PN = "AA64";
"DDR2_SA_DQS_DN8":   PN = "AF61"  !CDS_PN = "AF61";
"DDR2_SA_DQS_DN9":   PN = "AH55"  !CDS_PN = "AH55";
"DDR2_SA_DQS_DP0":   PN = "U76"  !CDS_PN = "U76";
"DDR2_SA_DQS_DP1":   PN = "AD67"  !CDS_PN = "AD67";
"DDR2_SA_DQS_DP2":   PN = "U64"  !CDS_PN = "U64";
"DDR2_SA_DQS_DP3":   PN = "AD61"  !CDS_PN = "AD61";
"DDR2_SA_DQS_DP4":   PN = "AB55"  !CDS_PN = "AB55";
"DDR2_SA_DQS_DP5":   PN = "AA76"  !CDS_PN = "AA76";
"DDR2_SA_DQS_DP6":   PN = "AF67"  !CDS_PN = "AF67";
"DDR2_SA_DQS_DP7":   PN = "W64"  !CDS_PN = "W64";
"DDR2_SA_DQS_DP8":   PN = "AH61"  !CDS_PN = "AH61";
"DDR2_SA_DQS_DP9":   PN = "AF55"  !CDS_PN = "AF55";
"DDR2_SA_ECC0":   PN = "AD57"  !CDS_PN = "AD57";
"DDR2_SA_ECC1":   PN = "AC56"  !CDS_PN = "AC56";
"DDR2_SA_ECC2":   PN = "AF57"  !CDS_PN = "AF57";
"DDR2_SA_ECC3":   PN = "AG56"  !CDS_PN = "AG56";
"DDR2_SA_ECC4":   PN = "AC54"  !CDS_PN = "AC54";
"DDR2_SA_ECC5":   PN = "AD53"  !CDS_PN = "AD53";
"DDR2_SA_ECC6":   PN = "AG54"  !CDS_PN = "AG54";
"DDR2_SA_ECC7":   PN = "AF53"  !CDS_PN = "AF53";
"DDR2_SA_PAR":   PN = "T47"  !CDS_PN = "T47";
"DDR2_SB_CA0":   PN = "W48"  !CDS_PN = "W48";
"DDR2_SB_CA1":   PN = "Y47"  !CDS_PN = "Y47";
"DDR2_SB_CA2":   PN = "U41"  !CDS_PN = "U41";
"DDR2_SB_CA3":   PN = "W41"  !CDS_PN = "W41";
"DDR2_SB_CA4":   PN = "T40"  !CDS_PN = "T40";
"DDR2_SB_CA5":   PN = "Y40"  !CDS_PN = "Y40";
"DDR2_SB_CA6":   PN = "R39"  !CDS_PN = "R39";
"DDR2_SB_DQ0":   PN = "AD38"  !CDS_PN = "AD38";
"DDR2_SB_DQ1":   PN = "AC37"  !CDS_PN = "AC37";
"DDR2_SB_DQ2":   PN = "AF38"  !CDS_PN = "AF38";
"DDR2_SB_DQ3":   PN = "AG37"  !CDS_PN = "AG37";
"DDR2_SB_DQ4":   PN = "AC35"  !CDS_PN = "AC35";
"DDR2_SB_DQ5":   PN = "AD34"  !CDS_PN = "AD34";
"DDR2_SB_DQ6":   PN = "AG35"  !CDS_PN = "AG35";
"DDR2_SB_DQ7":   PN = "AF34"  !CDS_PN = "AF34";
"DDR2_SB_DQ8":   PN = "AD32"  !CDS_PN = "AD32";
"DDR2_SB_DQ9":   PN = "AC31"  !CDS_PN = "AC31";
"DDR2_SB_DQ10":   PN = "AF32"  !CDS_PN = "AF32";
"DDR2_SB_DQ11":   PN = "AG31"  !CDS_PN = "AG31";
"DDR2_SB_DQ12":   PN = "AC29"  !CDS_PN = "AC29";
"DDR2_SB_DQ13":   PN = "AD28"  !CDS_PN = "AD28";
"DDR2_SB_DQ14":   PN = "AG29"  !CDS_PN = "AG29";
"DDR2_SB_DQ15":   PN = "AF28"  !CDS_PN = "AF28";
"DDR2_SB_DQ16":   PN = "U23"  !CDS_PN = "U23";
"DDR2_SB_DQ17":   PN = "T22"  !CDS_PN = "T22";
"DDR2_SB_DQ18":   PN = "W23"  !CDS_PN = "W23";
"DDR2_SB_DQ19":   PN = "Y22"  !CDS_PN = "Y22";
"DDR2_SB_DQ20":   PN = "T20"  !CDS_PN = "T20";
"DDR2_SB_DQ21":   PN = "U19"  !CDS_PN = "U19";
"DDR2_SB_DQ22":   PN = "Y20"  !CDS_PN = "Y20";
"DDR2_SB_DQ23":   PN = "W19"  !CDS_PN = "W19";
"DDR2_SB_DQ24":   PN = "AD20"  !CDS_PN = "AD20";
"DDR2_SB_DQ25":   PN = "AC19"  !CDS_PN = "AC19";
"DDR2_SB_DQ26":   PN = "AF20"  !CDS_PN = "AF20";
"DDR2_SB_DQ27":   PN = "AG19"  !CDS_PN = "AG19";
"DDR2_SB_DQ28":   PN = "AA17"  !CDS_PN = "AA17";
"DDR2_SB_DQ29":   PN = "AG17"  !CDS_PN = "AG17";
"DDR2_SB_DQ30":   PN = "AC17"  !CDS_PN = "AC17";
"DDR2_SB_DQ31":   PN = "AJ17"  !CDS_PN = "AJ17";
"DDR2_SB_DQS_DN0":   PN = "AB36"  !CDS_PN = "AB36";
"DDR2_SB_DQS_DN1":   PN = "AB30"  !CDS_PN = "AB30";
"DDR2_SB_DQS_DN2":   PN = "R21"  !CDS_PN = "R21";
"DDR2_SB_DQS_DN3":   PN = "AB18"  !CDS_PN = "AB18";
"DDR2_SB_DQS_DN4":   PN = "W33"  !CDS_PN = "W33";
"DDR2_SB_DQS_DN5":   PN = "AF36"  !CDS_PN = "AF36";
"DDR2_SB_DQS_DN6":   PN = "AF30"  !CDS_PN = "AF30";
"DDR2_SB_DQS_DN7":   PN = "W21"  !CDS_PN = "W21";
"DDR2_SB_DQS_DN8":   PN = "AF18"  !CDS_PN = "AF18";
"DDR2_SB_DQS_DN9":   PN = "R33"  !CDS_PN = "R33";
"DDR2_SB_DQS_DP0":   PN = "AD36"  !CDS_PN = "AD36";
"DDR2_SB_DQS_DP1":   PN = "AD30"  !CDS_PN = "AD30";
"DDR2_SB_DQS_DP2":   PN = "U21"  !CDS_PN = "U21";
"DDR2_SB_DQS_DP3":   PN = "AD18"  !CDS_PN = "AD18";
"DDR2_SB_DQS_DP4":   PN = "AA33"  !CDS_PN = "AA33";
"DDR2_SB_DQS_DP5":   PN = "AH36"  !CDS_PN = "AH36";
"DDR2_SB_DQS_DP6":   PN = "AH30"  !CDS_PN = "AH30";
"DDR2_SB_DQS_DP7":   PN = "AA21"  !CDS_PN = "AA21";
"DDR2_SB_DQS_DP8":   PN = "AH18"  !CDS_PN = "AH18";
"DDR2_SB_DQS_DP9":   PN = "U33"  !CDS_PN = "U33";
"DDR2_SB_ECC0":   PN = "T32"  !CDS_PN = "T32";
"DDR2_SB_ECC1":   PN = "U31"  !CDS_PN = "U31";
"DDR2_SB_ECC2":   PN = "Y32"  !CDS_PN = "Y32";
"DDR2_SB_ECC3":   PN = "W31"  !CDS_PN = "W31";
"DDR2_SB_ECC4":   PN = "U35"  !CDS_PN = "U35";
"DDR2_SB_ECC5":   PN = "T34"  !CDS_PN = "T34";
"DDR2_SB_ECC6":   PN = "W35"  !CDS_PN = "W35";
"DDR2_SB_ECC7":   PN = "Y34"  !CDS_PN = "Y34";
"DDR2_SB_PAR":   PN = "AA39"  !CDS_PN = "AA39";
"DDR2_SA_CS_N0":   PN = "U54"  !CDS_PN = "U54";
"DDR2_SA_CS_N1":   PN = "T53"  !CDS_PN = "T53";
"DDR2_SA_CS_N2":   PN = "W54"  !CDS_PN = "W54";
"DDR2_SA_CS_N3":   PN = "Y53"  !CDS_PN = "Y53";
"DDR2_SB_CS_N0":   PN = "T38"  !CDS_PN = "T38";
"DDR2_SB_CS_N1":   PN = "U37"  !CDS_PN = "U37";
"DDR2_SB_CS_N2":   PN = "Y38"  !CDS_PN = "Y38";
"DDR2_SB_CS_N3":   PN = "W37"  !CDS_PN = "W37";
DRAWING = "@s9s_mb_2u_lib.s9s_mb_2u(sch_1):page23";
BODY = "SOCKET4677_AZIF0045P001C01CS","I169": LOCATION = "U2" #&CDS_LOCATION = "U2" &SEC = "11" #&CDS_SEC = "11";
"DDR3_A_RSP0":   PN = "AD51"  !CDS_PN = "AD51";
"DDR3_A_RSP1":   PN = "AC50"  !CDS_PN = "AC50";
"DDR3_ALERT_N":   PN = "AV47"  !CDS_PN = "AV47";
"DDR3_B_RSP0":   PN = "AF51"  !CDS_PN = "AF51";
"DDR3_B_RSP1":   PN = "AG50"  !CDS_PN = "AG50";
"DDR3_CLK_DN0":   PN = "AJ45"  !CDS_PN = "AJ45";
"DDR3_CLK_DN1":   PN = "AN45"  !CDS_PN = "AN45";
"DDR3_CLK_DP0":   PN = "AL45"  !CDS_PN = "AL45";
"DDR3_CLK_DP1":   PN = "AR45"  !CDS_PN = "AR45";
"DDR3_SA_CA0":   PN = "AJ52"  !CDS_PN = "AJ52";
"DDR3_SA_CA1":   PN = "AR52"  !CDS_PN = "AR52";
"DDR3_SA_CA2":   PN = "AK51"  !CDS_PN = "AK51";
"DDR3_SA_CA3":   PN = "AP51"  !CDS_PN = "AP51";
"DDR3_SA_CA4":   PN = "AL50"  !CDS_PN = "AL50";
"DDR3_SA_CA5":   PN = "AN50"  !CDS_PN = "AN50";
"DDR3_SA_CA6":   PN = "AN43"  !CDS_PN = "AN43";
"DDR3_SA_DQ0":   PN = "AD75"  !CDS_PN = "AD75";
"DDR3_SA_DQ1":   PN = "AC74"  !CDS_PN = "AC74";
"DDR3_SA_DQ2":   PN = "AF75"  !CDS_PN = "AF75";
"DDR3_SA_DQ3":   PN = "AG74"  !CDS_PN = "AG74";
"DDR3_SA_DQ4":   PN = "AC72"  !CDS_PN = "AC72";
"DDR3_SA_DQ5":   PN = "AD71"  !CDS_PN = "AD71";
"DDR3_SA_DQ6":   PN = "AG72"  !CDS_PN = "AG72";
"DDR3_SA_DQ7":   PN = "AF71"  !CDS_PN = "AF71";
"DDR3_SA_DQ8":   PN = "AL78"  !CDS_PN = "AL78";
"DDR3_SA_DQ9":   PN = "AK77"  !CDS_PN = "AK77";
"DDR3_SA_DQ10":   PN = "AN78"  !CDS_PN = "AN78";
"DDR3_SA_DQ11":   PN = "AP77"  !CDS_PN = "AP77";
"DDR3_SA_DQ12":   PN = "AK75"  !CDS_PN = "AK75";
"DDR3_SA_DQ13":   PN = "AL74"  !CDS_PN = "AL74";
"DDR3_SA_DQ14":   PN = "AP75"  !CDS_PN = "AP75";
"DDR3_SA_DQ15":   PN = "AN74"  !CDS_PN = "AN74";
"DDR3_SA_DQ16":   PN = "AL72"  !CDS_PN = "AL72";
"DDR3_SA_DQ17":   PN = "AK71"  !CDS_PN = "AK71";
"DDR3_SA_DQ18":   PN = "AN72"  !CDS_PN = "AN72";
"DDR3_SA_DQ19":   PN = "AP71"  !CDS_PN = "AP71";
"DDR3_SA_DQ20":   PN = "AK69"  !CDS_PN = "AK69";
"DDR3_SA_DQ21":   PN = "AL68"  !CDS_PN = "AL68";
"DDR3_SA_DQ22":   PN = "AP69"  !CDS_PN = "AP69";
"DDR3_SA_DQ23":   PN = "AN68"  !CDS_PN = "AN68";
"DDR3_SA_DQ24":   PN = "AL66"  !CDS_PN = "AL66";
"DDR3_SA_DQ25":   PN = "AK65"  !CDS_PN = "AK65";
"DDR3_SA_DQ26":   PN = "AN66"  !CDS_PN = "AN66";
"DDR3_SA_DQ27":   PN = "AP65"  !CDS_PN = "AP65";
"DDR3_SA_DQ28":   PN = "AK63"  !CDS_PN = "AK63";
"DDR3_SA_DQ29":   PN = "AL62"  !CDS_PN = "AL62";
"DDR3_SA_DQ30":   PN = "AP63"  !CDS_PN = "AP63";
"DDR3_SA_DQ31":   PN = "AN62"  !CDS_PN = "AN62";
"DDR3_SA_DQS_DN0":   PN = "AB73"  !CDS_PN = "AB73";
"DDR3_SA_DQS_DN1":   PN = "AJ76"  !CDS_PN = "AJ76";
"DDR3_SA_DQS_DN2":   PN = "AJ70"  !CDS_PN = "AJ70";
"DDR3_SA_DQS_DN3":   PN = "AJ64"  !CDS_PN = "AJ64";
"DDR3_SA_DQS_DN4":   PN = "AJ58"  !CDS_PN = "AJ58";
"DDR3_SA_DQS_DN5":   PN = "AH73"  !CDS_PN = "AH73";
"DDR3_SA_DQS_DN6":   PN = "AN76"  !CDS_PN = "AN76";
"DDR3_SA_DQS_DN7":   PN = "AN70"  !CDS_PN = "AN70";
"DDR3_SA_DQS_DN8":   PN = "AN64"  !CDS_PN = "AN64";
"DDR3_SA_DQS_DN9":   PN = "AN58"  !CDS_PN = "AN58";
"DDR3_SA_DQS_DP0":   PN = "AD73"  !CDS_PN = "AD73";
"DDR3_SA_DQS_DP1":   PN = "AL76"  !CDS_PN = "AL76";
"DDR3_SA_DQS_DP2":   PN = "AL70"  !CDS_PN = "AL70";
"DDR3_SA_DQS_DP3":   PN = "AL64"  !CDS_PN = "AL64";
"DDR3_SA_DQS_DP4":   PN = "AL58"  !CDS_PN = "AL58";
"DDR3_SA_DQS_DP5":   PN = "AF73"  !CDS_PN = "AF73";
"DDR3_SA_DQS_DP6":   PN = "AR76"  !CDS_PN = "AR76";
"DDR3_SA_DQS_DP7":   PN = "AR70"  !CDS_PN = "AR70";
"DDR3_SA_DQS_DP8":   PN = "AR64"  !CDS_PN = "AR64";
"DDR3_SA_DQS_DP9":   PN = "AR58"  !CDS_PN = "AR58";
"DDR3_SA_ECC0":   PN = "AL60"  !CDS_PN = "AL60";
"DDR3_SA_ECC1":   PN = "AK59"  !CDS_PN = "AK59";
"DDR3_SA_ECC2":   PN = "AN60"  !CDS_PN = "AN60";
"DDR3_SA_ECC3":   PN = "AP59"  !CDS_PN = "AP59";
"DDR3_SA_ECC4":   PN = "AK57"  !CDS_PN = "AK57";
"DDR3_SA_ECC5":   PN = "AL56"  !CDS_PN = "AL56";
"DDR3_SA_ECC6":   PN = "AP57"  !CDS_PN = "AP57";
"DDR3_SA_ECC7":   PN = "AN56"  !CDS_PN = "AN56";
"DDR3_SA_PAR":   PN = "AP44"  !CDS_PN = "AP44";
"DDR3_SB_CA0":   PN = "AK44"  !CDS_PN = "AK44";
"DDR3_SB_CA1":   PN = "AL43"  !CDS_PN = "AL43";
"DDR3_SB_CA2":   PN = "AD44"  !CDS_PN = "AD44";
"DDR3_SB_CA3":   PN = "AF44"  !CDS_PN = "AF44";
"DDR3_SB_CA4":   PN = "AC43"  !CDS_PN = "AC43";
"DDR3_SB_CA5":   PN = "AG43"  !CDS_PN = "AG43";
"DDR3_SB_CA6":   PN = "AB42"  !CDS_PN = "AB42";
"DDR3_SB_DQ0":   PN = "AL35"  !CDS_PN = "AL35";
"DDR3_SB_DQ1":   PN = "AK34"  !CDS_PN = "AK34";
"DDR3_SB_DQ2":   PN = "AN35"  !CDS_PN = "AN35";
"DDR3_SB_DQ3":   PN = "AP34"  !CDS_PN = "AP34";
"DDR3_SB_DQ4":   PN = "AK32"  !CDS_PN = "AK32";
"DDR3_SB_DQ5":   PN = "AL31"  !CDS_PN = "AL31";
"DDR3_SB_DQ6":   PN = "AP32"  !CDS_PN = "AP32";
"DDR3_SB_DQ7":   PN = "AN31"  !CDS_PN = "AN31";
"DDR3_SB_DQ8":   PN = "AL29"  !CDS_PN = "AL29";
"DDR3_SB_DQ9":   PN = "AK28"  !CDS_PN = "AK28";
"DDR3_SB_DQ10":   PN = "AN29"  !CDS_PN = "AN29";
"DDR3_SB_DQ11":   PN = "AP28"  !CDS_PN = "AP28";
"DDR3_SB_DQ12":   PN = "AK26"  !CDS_PN = "AK26";
"DDR3_SB_DQ13":   PN = "AL25"  !CDS_PN = "AL25";
"DDR3_SB_DQ14":   PN = "AP26"  !CDS_PN = "AP26";
"DDR3_SB_DQ15":   PN = "AN25"  !CDS_PN = "AN25";
"DDR3_SB_DQ16":   PN = "AD26"  !CDS_PN = "AD26";
"DDR3_SB_DQ17":   PN = "AC25"  !CDS_PN = "AC25";
"DDR3_SB_DQ18":   PN = "AF26"  !CDS_PN = "AF26";
"DDR3_SB_DQ19":   PN = "AG25"  !CDS_PN = "AG25";
"DDR3_SB_DQ20":   PN = "AC23"  !CDS_PN = "AC23";
"DDR3_SB_DQ21":   PN = "AD22"  !CDS_PN = "AD22";
"DDR3_SB_DQ22":   PN = "AG23"  !CDS_PN = "AG23";
"DDR3_SB_DQ23":   PN = "AF22"  !CDS_PN = "AF22";
"DDR3_SB_DQ24":   PN = "AL23"  !CDS_PN = "AL23";
"DDR3_SB_DQ25":   PN = "AK22"  !CDS_PN = "AK22";
"DDR3_SB_DQ26":   PN = "AN23"  !CDS_PN = "AN23";
"DDR3_SB_DQ27":   PN = "AP22"  !CDS_PN = "AP22";
"DDR3_SB_DQ28":   PN = "AK20"  !CDS_PN = "AK20";
"DDR3_SB_DQ29":   PN = "AL19"  !CDS_PN = "AL19";
"DDR3_SB_DQ30":   PN = "AP20"  !CDS_PN = "AP20";
"DDR3_SB_DQ31":   PN = "AN19"  !CDS_PN = "AN19";
"DDR3_SB_DQS_DN0":   PN = "AJ33"  !CDS_PN = "AJ33";
"DDR3_SB_DQS_DN1":   PN = "AJ27"  !CDS_PN = "AJ27";
"DDR3_SB_DQS_DN2":   PN = "AB24"  !CDS_PN = "AB24";
"DDR3_SB_DQS_DN3":   PN = "AJ21"  !CDS_PN = "AJ21";
"DDR3_SB_DQS_DN4":   PN = "AR39"  !CDS_PN = "AR39";
"DDR3_SB_DQS_DN5":   PN = "AN33"  !CDS_PN = "AN33";
"DDR3_SB_DQS_DN6":   PN = "AN27"  !CDS_PN = "AN27";
"DDR3_SB_DQS_DN7":   PN = "AF24"  !CDS_PN = "AF24";
"DDR3_SB_DQS_DN8":   PN = "AN21"  !CDS_PN = "AN21";
"DDR3_SB_DQS_DN9":   PN = "AJ39"  !CDS_PN = "AJ39";
"DDR3_SB_DQS_DP0":   PN = "AL33"  !CDS_PN = "AL33";
"DDR3_SB_DQS_DP1":   PN = "AL27"  !CDS_PN = "AL27";
"DDR3_SB_DQS_DP2":   PN = "AD24"  !CDS_PN = "AD24";
"DDR3_SB_DQS_DP3":   PN = "AL21"  !CDS_PN = "AL21";
"DDR3_SB_DQS_DP4":   PN = "AN39"  !CDS_PN = "AN39";
"DDR3_SB_DQS_DP5":   PN = "AR33"  !CDS_PN = "AR33";
"DDR3_SB_DQS_DP6":   PN = "AR27"  !CDS_PN = "AR27";
"DDR3_SB_DQS_DP7":   PN = "AH24"  !CDS_PN = "AH24";
"DDR3_SB_DQS_DP8":   PN = "AR21"  !CDS_PN = "AR21";
"DDR3_SB_DQS_DP9":   PN = "AL39"  !CDS_PN = "AL39";
"DDR3_SB_ECC0":   PN = "AK38"  !CDS_PN = "AK38";
"DDR3_SB_ECC1":   PN = "AL37"  !CDS_PN = "AL37";
"DDR3_SB_ECC2":   PN = "AP38"  !CDS_PN = "AP38";
"DDR3_SB_ECC3":   PN = "AN37"  !CDS_PN = "AN37";
"DDR3_SB_ECC4":   PN = "AL41"  !CDS_PN = "AL41";
"DDR3_SB_ECC5":   PN = "AK40"  !CDS_PN = "AK40";
"DDR3_SB_ECC6":   PN = "AN41"  !CDS_PN = "AN41";
"DDR3_SB_ECC7":   PN = "AP40"  !CDS_PN = "AP40";
"DDR3_SB_PAR":   PN = "AH42"  !CDS_PN = "AH42";
"DDR3_SA_CS_N0":   PN = "AL54"  !CDS_PN = "AL54";
"DDR3_SA_CS_N1":   PN = "AK53"  !CDS_PN = "AK53";
"DDR3_SA_CS_N2":   PN = "AN54"  !CDS_PN = "AN54";
"DDR3_SA_CS_N3":   PN = "AP53"  !CDS_PN = "AP53";
"DDR3_SB_CS_N0":   PN = "AC41"  !CDS_PN = "AC41";
"DDR3_SB_CS_N1":   PN = "AG41"  !CDS_PN = "AG41";
"DDR3_SB_CS_N2":   PN = "AF40"  !CDS_PN = "AF40";
"DDR3_SB_CS_N3":   PN = "AD40"  !CDS_PN = "AD40";
DRAWING = "@s9s_mb_2u_lib.s9s_mb_2u(sch_1):page24";
BODY = "SOCKET4677_AZIF0045P001C01CS","I169": LOCATION = "U2" #&CDS_LOCATION = "U2" &SEC = "12" #&CDS_SEC = "12";
"DDR4_A_RSP0":   PN = "DD44"  !CDS_PN = "DD44";
"DDR4_A_RSP1":   PN = "DC43"  !CDS_PN = "DC43";
"DDR4_ALERT_N":   PN = "CY47"  !CDS_PN = "CY47";
"DDR4_B_RSP0":   PN = "DF44"  !CDS_PN = "DF44";
"DDR4_B_RSP1":   PN = "DG43"  !CDS_PN = "DG43";
"DDR4_CLK_DN0":   PN = "EJ45"  !CDS_PN = "EJ45";
"DDR4_CLK_DN1":   PN = "EE45"  !CDS_PN = "EE45";
"DDR4_CLK_DP0":   PN = "EG45"  !CDS_PN = "EG45";
"DDR4_CLK_DP1":   PN = "EC45"  !CDS_PN = "EC45";
"DDR4_SA_CA0":   PN = "EP49"  !CDS_PN = "EP49";
"DDR4_SA_CA1":   PN = "ET49"  !CDS_PN = "ET49";
"DDR4_SA_CA2":   PN = "EK49"  !CDS_PN = "EK49";
"DDR4_SA_CA3":   PN = "EL48"  !CDS_PN = "EL48";
"DDR4_SA_CA4":   PN = "EM47"  !CDS_PN = "EM47";
"DDR4_SA_CA5":   PN = "EP47"  !CDS_PN = "EP47";
"DDR4_SA_CA6":   PN = "ED44"  !CDS_PN = "ED44";
"DDR4_SA_DQ0":   PN = "EL78"  !CDS_PN = "EL78";
"DDR4_SA_DQ1":   PN = "EM77"  !CDS_PN = "EM77";
"DDR4_SA_DQ2":   PN = "EP79"  !CDS_PN = "EP79";
"DDR4_SA_DQ3":   PN = "ER76"  !CDS_PN = "ER76";
"DDR4_SA_DQ4":   PN = "EL74"  !CDS_PN = "EL74";
"DDR4_SA_DQ5":   PN = "EK73"  !CDS_PN = "EK73";
"DDR4_SA_DQ6":   PN = "EP73"  !CDS_PN = "EP73";
"DDR4_SA_DQ7":   PN = "ER72"  !CDS_PN = "ER72";
"DDR4_SA_DQ8":   PN = "EE72"  !CDS_PN = "EE72";
"DDR4_SA_DQ9":   PN = "ED71"  !CDS_PN = "ED71";
"DDR4_SA_DQ10":   PN = "EG72"  !CDS_PN = "EG72";
"DDR4_SA_DQ11":   PN = "EH71"  !CDS_PN = "EH71";
"DDR4_SA_DQ12":   PN = "ED69"  !CDS_PN = "ED69";
"DDR4_SA_DQ13":   PN = "EE68"  !CDS_PN = "EE68";
"DDR4_SA_DQ14":   PN = "EH69"  !CDS_PN = "EH69";
"DDR4_SA_DQ15":   PN = "EG68"  !CDS_PN = "EG68";
"DDR4_SA_DQ16":   PN = "EM71"  !CDS_PN = "EM71";
"DDR4_SA_DQ17":   PN = "EM69"  !CDS_PN = "EM69";
"DDR4_SA_DQ18":   PN = "EN70"  !CDS_PN = "EN70";
"DDR4_SA_DQ19":   PN = "ER68"  !CDS_PN = "ER68";
"DDR4_SA_DQ20":   PN = "ER66"  !CDS_PN = "ER66";
"DDR4_SA_DQ21":   PN = "EM65"  !CDS_PN = "EM65";
"DDR4_SA_DQ22":   PN = "EL66"  !CDS_PN = "EL66";
"DDR4_SA_DQ23":   PN = "EP65"  !CDS_PN = "EP65";
"DDR4_SA_DQ24":   PN = "EM63"  !CDS_PN = "EM63";
"DDR4_SA_DQ25":   PN = "EL62"  !CDS_PN = "EL62";
"DDR4_SA_DQ26":   PN = "EP63"  !CDS_PN = "EP63";
"DDR4_SA_DQ27":   PN = "ER62"  !CDS_PN = "ER62";
"DDR4_SA_DQ28":   PN = "EL60"  !CDS_PN = "EL60";
"DDR4_SA_DQ29":   PN = "EM59"  !CDS_PN = "EM59";
"DDR4_SA_DQ30":   PN = "ER60"  !CDS_PN = "ER60";
"DDR4_SA_DQ31":   PN = "EP59"  !CDS_PN = "EP59";
"DDR4_SA_DQS_DN0":   PN = "EP75"  !CDS_PN = "EP75";
"DDR4_SA_DQS_DN1":   PN = "EC70"  !CDS_PN = "EC70";
"DDR4_SA_DQS_DN2":   PN = "EK67"  !CDS_PN = "EK67";
"DDR4_SA_DQS_DN3":   PN = "EK61"  !CDS_PN = "EK61";
"DDR4_SA_DQS_DN4":   PN = "EM55"  !CDS_PN = "EM55";
"DDR4_SA_DQS_DN5":   PN = "EM75"  !CDS_PN = "EM75";
"DDR4_SA_DQS_DN6":   PN = "EJ70"  !CDS_PN = "EJ70";
"DDR4_SA_DQS_DN7":   PN = "EN68"  !CDS_PN = "EN68";
"DDR4_SA_DQS_DN8":   PN = "ET61"  !CDS_PN = "ET61";
"DDR4_SA_DQS_DN9":   PN = "ET55"  !CDS_PN = "ET55";
"DDR4_SA_DQS_DP0":   PN = "EN76"  !CDS_PN = "EN76";
"DDR4_SA_DQS_DP1":   PN = "EE70"  !CDS_PN = "EE70";
"DDR4_SA_DQS_DP2":   PN = "EL68"  !CDS_PN = "EL68";
"DDR4_SA_DQS_DP3":   PN = "EM61"  !CDS_PN = "EM61";
"DDR4_SA_DQS_DP4":   PN = "EK55"  !CDS_PN = "EK55";
"DDR4_SA_DQS_DP5":   PN = "EN74"  !CDS_PN = "EN74";
"DDR4_SA_DQS_DP6":   PN = "EG70"  !CDS_PN = "EG70";
"DDR4_SA_DQS_DP7":   PN = "EM67"  !CDS_PN = "EM67";
"DDR4_SA_DQS_DP8":   PN = "EP61"  !CDS_PN = "EP61";
"DDR4_SA_DQS_DP9":   PN = "EP55"  !CDS_PN = "EP55";
"DDR4_SA_ECC0":   PN = "EM57"  !CDS_PN = "EM57";
"DDR4_SA_ECC1":   PN = "EL56"  !CDS_PN = "EL56";
"DDR4_SA_ECC2":   PN = "EP57"  !CDS_PN = "EP57";
"DDR4_SA_ECC3":   PN = "ER56"  !CDS_PN = "ER56";
"DDR4_SA_ECC4":   PN = "EL54"  !CDS_PN = "EL54";
"DDR4_SA_ECC5":   PN = "EM53"  !CDS_PN = "EM53";
"DDR4_SA_ECC6":   PN = "ER54"  !CDS_PN = "ER54";
"DDR4_SA_ECC7":   PN = "EP53"  !CDS_PN = "EP53";
"DDR4_SA_PAR":   PN = "EE43"  !CDS_PN = "EE43";
"DDR4_SB_CA0":   PN = "EG43"  !CDS_PN = "EG43";
"DDR4_SB_CA1":   PN = "EH44"  !CDS_PN = "EH44";
"DDR4_SB_CA2":   PN = "EM44"  !CDS_PN = "EM44";
"DDR4_SB_CA3":   PN = "EP44"  !CDS_PN = "EP44";
"DDR4_SB_CA4":   PN = "EL43"  !CDS_PN = "EL43";
"DDR4_SB_CA5":   PN = "ET42"  !CDS_PN = "ET42";
"DDR4_SB_CA6":   PN = "EK42"  !CDS_PN = "EK42";
"DDR4_SB_DQ0":   PN = "EE29"  !CDS_PN = "EE29";
"DDR4_SB_DQ1":   PN = "ED28"  !CDS_PN = "ED28";
"DDR4_SB_DQ2":   PN = "EG29"  !CDS_PN = "EG29";
"DDR4_SB_DQ3":   PN = "EH28"  !CDS_PN = "EH28";
"DDR4_SB_DQ4":   PN = "ED26"  !CDS_PN = "ED26";
"DDR4_SB_DQ5":   PN = "EE25"  !CDS_PN = "EE25";
"DDR4_SB_DQ6":   PN = "EH26"  !CDS_PN = "EH26";
"DDR4_SB_DQ7":   PN = "EG25"  !CDS_PN = "EG25";
"DDR4_SB_DQ8":   PN = "EM32"  !CDS_PN = "EM32";
"DDR4_SB_DQ9":   PN = "EL31"  !CDS_PN = "EL31";
"DDR4_SB_DQ10":   PN = "EP32"  !CDS_PN = "EP32";
"DDR4_SB_DQ11":   PN = "ER31"  !CDS_PN = "ER31";
"DDR4_SB_DQ12":   PN = "EL29"  !CDS_PN = "EL29";
"DDR4_SB_DQ13":   PN = "EM28"  !CDS_PN = "EM28";
"DDR4_SB_DQ14":   PN = "ER29"  !CDS_PN = "ER29";
"DDR4_SB_DQ15":   PN = "EP28"  !CDS_PN = "EP28";
"DDR4_SB_DQ16":   PN = "EM26"  !CDS_PN = "EM26";
"DDR4_SB_DQ17":   PN = "EL25"  !CDS_PN = "EL25";
"DDR4_SB_DQ18":   PN = "EP26"  !CDS_PN = "EP26";
"DDR4_SB_DQ19":   PN = "ER25"  !CDS_PN = "ER25";
"DDR4_SB_DQ20":   PN = "EL23"  !CDS_PN = "EL23";
"DDR4_SB_DQ21":   PN = "EM22"  !CDS_PN = "EM22";
"DDR4_SB_DQ22":   PN = "ER23"  !CDS_PN = "ER23";
"DDR4_SB_DQ23":   PN = "EP22"  !CDS_PN = "EP22";
"DDR4_SB_DQ24":   PN = "EM20"  !CDS_PN = "EM20";
"DDR4_SB_DQ25":   PN = "EL19"  !CDS_PN = "EL19";
"DDR4_SB_DQ26":   PN = "EP20"  !CDS_PN = "EP20";
"DDR4_SB_DQ27":   PN = "ER19"  !CDS_PN = "ER19";
"DDR4_SB_DQ28":   PN = "EL17"  !CDS_PN = "EL17";
"DDR4_SB_DQ29":   PN = "EM16"  !CDS_PN = "EM16";
"DDR4_SB_DQ30":   PN = "ER17"  !CDS_PN = "ER17";
"DDR4_SB_DQ31":   PN = "EP16"  !CDS_PN = "EP16";
"DDR4_SB_DQS_DN0":   PN = "EE27"  !CDS_PN = "EE27";
"DDR4_SB_DQS_DN1":   PN = "EK30"  !CDS_PN = "EK30";
"DDR4_SB_DQS_DN2":   PN = "EK24"  !CDS_PN = "EK24";
"DDR4_SB_DQS_DN3":   PN = "EK18"  !CDS_PN = "EK18";
"DDR4_SB_DQS_DN4":   PN = "ET36"  !CDS_PN = "ET36";
"DDR4_SB_DQS_DN5":   PN = "EJ27"  !CDS_PN = "EJ27";
"DDR4_SB_DQS_DN6":   PN = "ET30"  !CDS_PN = "ET30";
"DDR4_SB_DQS_DN7":   PN = "ET24"  !CDS_PN = "ET24";
"DDR4_SB_DQS_DN8":   PN = "ET18"  !CDS_PN = "ET18";
"DDR4_SB_DQS_DN9":   PN = "EK36"  !CDS_PN = "EK36";
"DDR4_SB_DQS_DP0":   PN = "EC27"  !CDS_PN = "EC27";
"DDR4_SB_DQS_DP1":   PN = "EM30"  !CDS_PN = "EM30";
"DDR4_SB_DQS_DP2":   PN = "EM24"  !CDS_PN = "EM24";
"DDR4_SB_DQS_DP3":   PN = "EM18"  !CDS_PN = "EM18";
"DDR4_SB_DQS_DP4":   PN = "EP36"  !CDS_PN = "EP36";
"DDR4_SB_DQS_DP5":   PN = "EG27"  !CDS_PN = "EG27";
"DDR4_SB_DQS_DP6":   PN = "EP30"  !CDS_PN = "EP30";
"DDR4_SB_DQS_DP7":   PN = "EP24"  !CDS_PN = "EP24";
"DDR4_SB_DQS_DP8":   PN = "EP18"  !CDS_PN = "EP18";
"DDR4_SB_DQS_DP9":   PN = "EM36"  !CDS_PN = "EM36";
"DDR4_SB_ECC0":   PN = "EL35"  !CDS_PN = "EL35";
"DDR4_SB_ECC1":   PN = "EM34"  !CDS_PN = "EM34";
"DDR4_SB_ECC2":   PN = "ER35"  !CDS_PN = "ER35";
"DDR4_SB_ECC3":   PN = "EP34"  !CDS_PN = "EP34";
"DDR4_SB_ECC4":   PN = "EM38"  !CDS_PN = "EM38";
"DDR4_SB_ECC5":   PN = "EL37"  !CDS_PN = "EL37";
"DDR4_SB_ECC6":   PN = "EP38"  !CDS_PN = "EP38";
"DDR4_SB_ECC7":   PN = "ER37"  !CDS_PN = "ER37";
"DDR4_SB_PAR":   PN = "EP42"  !CDS_PN = "EP42";
"DDR4_SA_CS_N0":   PN = "EP51"  !CDS_PN = "EP51";
"DDR4_SA_CS_N1":   PN = "ET51"  !CDS_PN = "ET51";
"DDR4_SA_CS_N2":   PN = "EM51"  !CDS_PN = "EM51";
"DDR4_SA_CS_N3":   PN = "EL50"  !CDS_PN = "EL50";
"DDR4_SB_CS_N0":   PN = "EP40"  !CDS_PN = "EP40";
"DDR4_SB_CS_N1":   PN = "ET40"  !CDS_PN = "ET40";
"DDR4_SB_CS_N2":   PN = "EM40"  !CDS_PN = "EM40";
"DDR4_SB_CS_N3":   PN = "EL41"  !CDS_PN = "EL41";
DRAWING = "@s9s_mb_2u_lib.s9s_mb_2u(sch_1):page25";
BODY = "SOCKET4677_AZIF0045P001C01CS","I169": LOCATION = "U2" #&CDS_LOCATION = "U2" &SEC = "13" #&CDS_SEC = "13";
"DDR5_A_RSP0":   PN = "DN48"  !CDS_PN = "DN48";
"DDR5_A_RSP1":   PN = "DP47"  !CDS_PN = "DP47";
"DDR5_ALERT_N":   PN = "CW48"  !CDS_PN = "CW48";
"DDR5_B_RSP0":   PN = "DL48"  !CDS_PN = "DL48";
"DDR5_B_RSP1":   PN = "DK47"  !CDS_PN = "DK47";
"DDR5_CLK_DN0":   PN = "DY49"  !CDS_PN = "DY49";
"DDR5_CLK_DN1":   PN = "DV49"  !CDS_PN = "DV49";
"DDR5_CLK_DP0":   PN = "EB49"  !CDS_PN = "EB49";
"DDR5_CLK_DP1":   PN = "DT49"  !CDS_PN = "DT49";
"DDR5_SA_CA0":   PN = "EC52"  !CDS_PN = "EC52";
"DDR5_SA_CA1":   PN = "EJ52"  !CDS_PN = "EJ52";
"DDR5_SA_CA2":   PN = "ED51"  !CDS_PN = "ED51";
"DDR5_SA_CA3":   PN = "EH51"  !CDS_PN = "EH51";
"DDR5_SA_CA4":   PN = "EE50"  !CDS_PN = "EE50";
"DDR5_SA_CA5":   PN = "EG50"  !CDS_PN = "EG50";
"DDR5_SA_CA6":   PN = "DY51"  !CDS_PN = "DY51";
"DDR5_SA_DQ0":   PN = "EB77"  !CDS_PN = "EB77";
"DDR5_SA_DQ1":   PN = "EH77"  !CDS_PN = "EH77";
"DDR5_SA_DQ2":   PN = "ED77"  !CDS_PN = "ED77";
"DDR5_SA_DQ3":   PN = "EG78"  !CDS_PN = "EG78";
"DDR5_SA_DQ4":   PN = "ED75"  !CDS_PN = "ED75";
"DDR5_SA_DQ5":   PN = "EE74"  !CDS_PN = "EE74";
"DDR5_SA_DQ6":   PN = "EH75"  !CDS_PN = "EH75";
"DDR5_SA_DQ7":   PN = "EG74"  !CDS_PN = "EG74";
"DDR5_SA_DQ8":   PN = "DV69"  !CDS_PN = "DV69";
"DDR5_SA_DQ9":   PN = "DU68"  !CDS_PN = "DU68";
"DDR5_SA_DQ10":   PN = "DY69"  !CDS_PN = "DY69";
"DDR5_SA_DQ11":   PN = "EA68"  !CDS_PN = "EA68";
"DDR5_SA_DQ12":   PN = "DU66"  !CDS_PN = "DU66";
"DDR5_SA_DQ13":   PN = "DV65"  !CDS_PN = "DV65";
"DDR5_SA_DQ14":   PN = "EA66"  !CDS_PN = "EA66";
"DDR5_SA_DQ15":   PN = "DY65"  !CDS_PN = "DY65";
"DDR5_SA_DQ16":   PN = "EE66"  !CDS_PN = "EE66";
"DDR5_SA_DQ17":   PN = "ED65"  !CDS_PN = "ED65";
"DDR5_SA_DQ18":   PN = "EG66"  !CDS_PN = "EG66";
"DDR5_SA_DQ19":   PN = "EH65"  !CDS_PN = "EH65";
"DDR5_SA_DQ20":   PN = "ED63"  !CDS_PN = "ED63";
"DDR5_SA_DQ21":   PN = "EE62"  !CDS_PN = "EE62";
"DDR5_SA_DQ22":   PN = "EH63"  !CDS_PN = "EH63";
"DDR5_SA_DQ23":   PN = "EG62"  !CDS_PN = "EG62";
"DDR5_SA_DQ24":   PN = "DV57"  !CDS_PN = "DV57";
"DDR5_SA_DQ25":   PN = "DU56"  !CDS_PN = "DU56";
"DDR5_SA_DQ26":   PN = "DY57"  !CDS_PN = "DY57";
"DDR5_SA_DQ27":   PN = "EA56"  !CDS_PN = "EA56";
"DDR5_SA_DQ28":   PN = "DU54"  !CDS_PN = "DU54";
"DDR5_SA_DQ29":   PN = "DV53"  !CDS_PN = "DV53";
"DDR5_SA_DQ30":   PN = "EA54"  !CDS_PN = "EA54";
"DDR5_SA_DQ31":   PN = "DY53"  !CDS_PN = "DY53";
"DDR5_SA_DQS_DN0":   PN = "EE76"  !CDS_PN = "EE76";
"DDR5_SA_DQS_DN1":   PN = "DT67"  !CDS_PN = "DT67";
"DDR5_SA_DQS_DN2":   PN = "EC64"  !CDS_PN = "EC64";
"DDR5_SA_DQS_DN3":   PN = "DV55"  !CDS_PN = "DV55";
"DDR5_SA_DQS_DN4":   PN = "EE58"  !CDS_PN = "EE58";
"DDR5_SA_DQS_DN5":   PN = "EJ76"  !CDS_PN = "EJ76";
"DDR5_SA_DQS_DN6":   PN = "EB67"  !CDS_PN = "EB67";
"DDR5_SA_DQS_DN7":   PN = "EJ64"  !CDS_PN = "EJ64";
"DDR5_SA_DQS_DN8":   PN = "EB55"  !CDS_PN = "EB55";
"DDR5_SA_DQS_DN9":   PN = "EJ58"  !CDS_PN = "EJ58";
"DDR5_SA_DQS_DP0":   PN = "EC76"  !CDS_PN = "EC76";
"DDR5_SA_DQS_DP1":   PN = "DV67"  !CDS_PN = "DV67";
"DDR5_SA_DQS_DP2":   PN = "EE64"  !CDS_PN = "EE64";
"DDR5_SA_DQS_DP3":   PN = "DT55"  !CDS_PN = "DT55";
"DDR5_SA_DQS_DP4":   PN = "EC58"  !CDS_PN = "EC58";
"DDR5_SA_DQS_DP5":   PN = "EG76"  !CDS_PN = "EG76";
"DDR5_SA_DQS_DP6":   PN = "DY67"  !CDS_PN = "DY67";
"DDR5_SA_DQS_DP7":   PN = "EG64"  !CDS_PN = "EG64";
"DDR5_SA_DQS_DP8":   PN = "DY55"  !CDS_PN = "DY55";
"DDR5_SA_DQS_DP9":   PN = "EG58"  !CDS_PN = "EG58";
"DDR5_SA_ECC0":   PN = "EE60"  !CDS_PN = "EE60";
"DDR5_SA_ECC1":   PN = "ED59"  !CDS_PN = "ED59";
"DDR5_SA_ECC2":   PN = "EG60"  !CDS_PN = "EG60";
"DDR5_SA_ECC3":   PN = "EH59"  !CDS_PN = "EH59";
"DDR5_SA_ECC4":   PN = "ED57"  !CDS_PN = "ED57";
"DDR5_SA_ECC5":   PN = "EE56"  !CDS_PN = "EE56";
"DDR5_SA_ECC6":   PN = "EH57"  !CDS_PN = "EH57";
"DDR5_SA_ECC7":   PN = "EG56"  !CDS_PN = "EG56";
"DDR5_SA_PAR":   PN = "EA50"  !CDS_PN = "EA50";
"DDR5_SB_CA0":   PN = "DV51"  !CDS_PN = "DV51";
"DDR5_SB_CA1":   PN = "DU50"  !CDS_PN = "DU50";
"DDR5_SB_CA2":   PN = "EE41"  !CDS_PN = "EE41";
"DDR5_SB_CA3":   PN = "EG41"  !CDS_PN = "EG41";
"DDR5_SB_CA4":   PN = "ED40"  !CDS_PN = "ED40";
"DDR5_SB_CA5":   PN = "EH40"  !CDS_PN = "EH40";
"DDR5_SB_CA6":   PN = "EC39"  !CDS_PN = "EC39";
"DDR5_SB_DQ0":   PN = "DV32"  !CDS_PN = "DV32";
"DDR5_SB_DQ1":   PN = "DU31"  !CDS_PN = "DU31";
"DDR5_SB_DQ2":   PN = "DY32"  !CDS_PN = "DY32";
"DDR5_SB_DQ3":   PN = "EA31"  !CDS_PN = "EA31";
"DDR5_SB_DQ4":   PN = "DU29"  !CDS_PN = "DU29";
"DDR5_SB_DQ5":   PN = "DV28"  !CDS_PN = "DV28";
"DDR5_SB_DQ6":   PN = "EA29"  !CDS_PN = "EA29";
"DDR5_SB_DQ7":   PN = "DY28"  !CDS_PN = "DY28";
"DDR5_SB_DQ8":   PN = "EE23"  !CDS_PN = "EE23";
"DDR5_SB_DQ9":   PN = "ED22"  !CDS_PN = "ED22";
"DDR5_SB_DQ10":   PN = "EG23"  !CDS_PN = "EG23";
"DDR5_SB_DQ11":   PN = "EH22"  !CDS_PN = "EH22";
"DDR5_SB_DQ12":   PN = "ED20"  !CDS_PN = "ED20";
"DDR5_SB_DQ13":   PN = "EE19"  !CDS_PN = "EE19";
"DDR5_SB_DQ14":   PN = "EH20"  !CDS_PN = "EH20";
"DDR5_SB_DQ15":   PN = "EG19"  !CDS_PN = "EG19";
"DDR5_SB_DQ16":   PN = "EM14"  !CDS_PN = "EM14";
"DDR5_SB_DQ17":   PN = "EL13"  !CDS_PN = "EL13";
"DDR5_SB_DQ18":   PN = "EP14"  !CDS_PN = "EP14";
"DDR5_SB_DQ19":   PN = "ER13"  !CDS_PN = "ER13";
"DDR5_SB_DQ20":   PN = "EL11"  !CDS_PN = "EL11";
"DDR5_SB_DQ21":   PN = "EM10"  !CDS_PN = "EM10";
"DDR5_SB_DQ22":   PN = "ER11"  !CDS_PN = "ER11";
"DDR5_SB_DQ23":   PN = "EP10"  !CDS_PN = "EP10";
"DDR5_SB_DQ24":   PN = "DV20"  !CDS_PN = "DV20";
"DDR5_SB_DQ25":   PN = "DU19"  !CDS_PN = "DU19";
"DDR5_SB_DQ26":   PN = "DY20"  !CDS_PN = "DY20";
"DDR5_SB_DQ27":   PN = "EA19"  !CDS_PN = "EA19";
"DDR5_SB_DQ28":   PN = "EA17"  !CDS_PN = "EA17";
"DDR5_SB_DQ29":   PN = "DU17"  !CDS_PN = "DU17";
"DDR5_SB_DQ30":   PN = "EC17"  !CDS_PN = "EC17";
"DDR5_SB_DQ31":   PN = "DR17"  !CDS_PN = "DR17";
"DDR5_SB_DQS_DN0":   PN = "DV30"  !CDS_PN = "DV30";
"DDR5_SB_DQS_DN1":   PN = "EE21"  !CDS_PN = "EE21";
"DDR5_SB_DQS_DN2":   PN = "EM12"  !CDS_PN = "EM12";
"DDR5_SB_DQS_DN3":   PN = "DT18"  !CDS_PN = "DT18";
"DDR5_SB_DQS_DN4":   PN = "EJ33"  !CDS_PN = "EJ33";
"DDR5_SB_DQS_DN5":   PN = "EB30"  !CDS_PN = "EB30";
"DDR5_SB_DQS_DN6":   PN = "EJ21"  !CDS_PN = "EJ21";
"DDR5_SB_DQS_DN7":   PN = "ET12"  !CDS_PN = "ET12";
"DDR5_SB_DQS_DN8":   PN = "DY18"  !CDS_PN = "DY18";
"DDR5_SB_DQS_DN9":   PN = "EE33"  !CDS_PN = "EE33";
"DDR5_SB_DQS_DP0":   PN = "DT30"  !CDS_PN = "DT30";
"DDR5_SB_DQS_DP1":   PN = "EC21"  !CDS_PN = "EC21";
"DDR5_SB_DQS_DP2":   PN = "EK12"  !CDS_PN = "EK12";
"DDR5_SB_DQS_DP3":   PN = "DV18"  !CDS_PN = "DV18";
"DDR5_SB_DQS_DP4":   PN = "EG33"  !CDS_PN = "EG33";
"DDR5_SB_DQS_DP5":   PN = "DY30"  !CDS_PN = "DY30";
"DDR5_SB_DQS_DP6":   PN = "EG21"  !CDS_PN = "EG21";
"DDR5_SB_DQS_DP7":   PN = "EP12"  !CDS_PN = "EP12";
"DDR5_SB_DQS_DP8":   PN = "EB18"  !CDS_PN = "EB18";
"DDR5_SB_DQS_DP9":   PN = "EC33"  !CDS_PN = "EC33";
"DDR5_SB_ECC0":   PN = "ED32"  !CDS_PN = "ED32";
"DDR5_SB_ECC1":   PN = "EE31"  !CDS_PN = "EE31";
"DDR5_SB_ECC2":   PN = "EH32"  !CDS_PN = "EH32";
"DDR5_SB_ECC3":   PN = "EG31"  !CDS_PN = "EG31";
"DDR5_SB_ECC4":   PN = "EE35"  !CDS_PN = "EE35";
"DDR5_SB_ECC5":   PN = "ED34"  !CDS_PN = "ED34";
"DDR5_SB_ECC6":   PN = "EG35"  !CDS_PN = "EG35";
"DDR5_SB_ECC7":   PN = "EH34"  !CDS_PN = "EH34";
"DDR5_SB_PAR":   PN = "EJ39"  !CDS_PN = "EJ39";
"DDR5_SA_CS_N0":   PN = "EG54"  !CDS_PN = "EG54";
"DDR5_SA_CS_N1":   PN = "EH53"  !CDS_PN = "EH53";
"DDR5_SA_CS_N2":   PN = "EE54"  !CDS_PN = "EE54";
"DDR5_SA_CS_N3":   PN = "ED53"  !CDS_PN = "ED53";
"DDR5_SB_CS_N0":   PN = "EH38"  !CDS_PN = "EH38";
"DDR5_SB_CS_N1":   PN = "EG37"  !CDS_PN = "EG37";
"DDR5_SB_CS_N2":   PN = "ED38"  !CDS_PN = "ED38";
"DDR5_SB_CS_N3":   PN = "EE37"  !CDS_PN = "EE37";
DRAWING = "@s9s_mb_2u_lib.s9s_mb_2u(sch_1):page26";
BODY = "SOCKET4677_AZIF0045P001C01CS","I169": LOCATION = "U2" #&CDS_LOCATION = "U2" &SEC = "14" #&CDS_SEC = "14";
"DDR6_A_RSP0":   PN = "EA48"  !CDS_PN = "EA48";
"DDR6_A_RSP1":   PN = "DY47"  !CDS_PN = "DY47";
"DDR6_ALERT_N":   PN = "CW50"  !CDS_PN = "CW50";
"DDR6_B_RSP0":   PN = "DU48"  !CDS_PN = "DU48";
"DDR6_B_RSP1":   PN = "DV47"  !CDS_PN = "DV47";
"DDR6_CLK_DN0":   PN = "DR45"  !CDS_PN = "DR45";
"DDR6_CLK_DN1":   PN = "DL45"  !CDS_PN = "DL45";
"DDR6_CLK_DP0":   PN = "DN45"  !CDS_PN = "DN45";
"DDR6_CLK_DP1":   PN = "DJ45"  !CDS_PN = "DJ45";
"DDR6_SA_CA0":   PN = "DJ52"  !CDS_PN = "DJ52";
"DDR6_SA_CA1":   PN = "DR52"  !CDS_PN = "DR52";
"DDR6_SA_CA2":   PN = "DK51"  !CDS_PN = "DK51";
"DDR6_SA_CA3":   PN = "DP51"  !CDS_PN = "DP51";
"DDR6_SA_CA4":   PN = "DL50"  !CDS_PN = "DL50";
"DDR6_SA_CA5":   PN = "DN50"  !CDS_PN = "DN50";
"DDR6_SA_CA6":   PN = "DK44"  !CDS_PN = "DK44";
"DDR6_SA_DQ0":   PN = "DV75"  !CDS_PN = "DV75";
"DDR6_SA_DQ1":   PN = "DU74"  !CDS_PN = "DU74";
"DDR6_SA_DQ2":   PN = "DY75"  !CDS_PN = "DY75";
"DDR6_SA_DQ3":   PN = "EA74"  !CDS_PN = "EA74";
"DDR6_SA_DQ4":   PN = "DU72"  !CDS_PN = "DU72";
"DDR6_SA_DQ5":   PN = "DV71"  !CDS_PN = "DV71";
"DDR6_SA_DQ6":   PN = "EA72"  !CDS_PN = "EA72";
"DDR6_SA_DQ7":   PN = "DY71"  !CDS_PN = "DY71";
"DDR6_SA_DQ8":   PN = "DL72"  !CDS_PN = "DL72";
"DDR6_SA_DQ9":   PN = "DK71"  !CDS_PN = "DK71";
"DDR6_SA_DQ10":   PN = "DN72"  !CDS_PN = "DN72";
"DDR6_SA_DQ11":   PN = "DP71"  !CDS_PN = "DP71";
"DDR6_SA_DQ12":   PN = "DK69"  !CDS_PN = "DK69";
"DDR6_SA_DQ13":   PN = "DL68"  !CDS_PN = "DL68";
"DDR6_SA_DQ14":   PN = "DP69"  !CDS_PN = "DP69";
"DDR6_SA_DQ15":   PN = "DN68"  !CDS_PN = "DN68";
"DDR6_SA_DQ16":   PN = "DV63"  !CDS_PN = "DV63";
"DDR6_SA_DQ17":   PN = "DU62"  !CDS_PN = "DU62";
"DDR6_SA_DQ18":   PN = "DY63"  !CDS_PN = "DY63";
"DDR6_SA_DQ19":   PN = "EA62"  !CDS_PN = "EA62";
"DDR6_SA_DQ20":   PN = "DU60"  !CDS_PN = "DU60";
"DDR6_SA_DQ21":   PN = "DV59"  !CDS_PN = "DV59";
"DDR6_SA_DQ22":   PN = "EA60"  !CDS_PN = "EA60";
"DDR6_SA_DQ23":   PN = "DY59"  !CDS_PN = "DY59";
"DDR6_SA_DQ24":   PN = "DL66"  !CDS_PN = "DL66";
"DDR6_SA_DQ25":   PN = "DK65"  !CDS_PN = "DK65";
"DDR6_SA_DQ26":   PN = "DN66"  !CDS_PN = "DN66";
"DDR6_SA_DQ27":   PN = "DP65"  !CDS_PN = "DP65";
"DDR6_SA_DQ28":   PN = "DK63"  !CDS_PN = "DK63";
"DDR6_SA_DQ29":   PN = "DL62"  !CDS_PN = "DL62";
"DDR6_SA_DQ30":   PN = "DP63"  !CDS_PN = "DP63";
"DDR6_SA_DQ31":   PN = "DN62"  !CDS_PN = "DN62";
"DDR6_SA_DQS_DN0":   PN = "DV73"  !CDS_PN = "DV73";
"DDR6_SA_DQS_DN1":   PN = "DJ70"  !CDS_PN = "DJ70";
"DDR6_SA_DQS_DN2":   PN = "DT61"  !CDS_PN = "DT61";
"DDR6_SA_DQS_DN3":   PN = "DL64"  !CDS_PN = "DL64";
"DDR6_SA_DQS_DN4":   PN = "DL58"  !CDS_PN = "DL58";
"DDR6_SA_DQS_DN5":   PN = "EB73"  !CDS_PN = "EB73";
"DDR6_SA_DQS_DN6":   PN = "DR70"  !CDS_PN = "DR70";
"DDR6_SA_DQS_DN7":   PN = "EB61"  !CDS_PN = "EB61";
"DDR6_SA_DQS_DN8":   PN = "DR64"  !CDS_PN = "DR64";
"DDR6_SA_DQS_DN9":   PN = "DR58"  !CDS_PN = "DR58";
"DDR6_SA_DQS_DP0":   PN = "DT73"  !CDS_PN = "DT73";
"DDR6_SA_DQS_DP1":   PN = "DL70"  !CDS_PN = "DL70";
"DDR6_SA_DQS_DP2":   PN = "DV61"  !CDS_PN = "DV61";
"DDR6_SA_DQS_DP3":   PN = "DJ64"  !CDS_PN = "DJ64";
"DDR6_SA_DQS_DP4":   PN = "DJ58"  !CDS_PN = "DJ58";
"DDR6_SA_DQS_DP5":   PN = "DY73"  !CDS_PN = "DY73";
"DDR6_SA_DQS_DP6":   PN = "DN70"  !CDS_PN = "DN70";
"DDR6_SA_DQS_DP7":   PN = "DY61"  !CDS_PN = "DY61";
"DDR6_SA_DQS_DP8":   PN = "DN64"  !CDS_PN = "DN64";
"DDR6_SA_DQS_DP9":   PN = "DN58"  !CDS_PN = "DN58";
"DDR6_SA_ECC0":   PN = "DL60"  !CDS_PN = "DL60";
"DDR6_SA_ECC1":   PN = "DK59"  !CDS_PN = "DK59";
"DDR6_SA_ECC2":   PN = "DN60"  !CDS_PN = "DN60";
"DDR6_SA_ECC3":   PN = "DP59"  !CDS_PN = "DP59";
"DDR6_SA_ECC4":   PN = "DK57"  !CDS_PN = "DK57";
"DDR6_SA_ECC5":   PN = "DL56"  !CDS_PN = "DL56";
"DDR6_SA_ECC6":   PN = "DP57"  !CDS_PN = "DP57";
"DDR6_SA_ECC7":   PN = "DN56"  !CDS_PN = "DN56";
"DDR6_SA_PAR":   PN = "DL43"  !CDS_PN = "DL43";
"DDR6_SB_CA0":   PN = "DN43"  !CDS_PN = "DN43";
"DDR6_SB_CA1":   PN = "DP44"  !CDS_PN = "DP44";
"DDR6_SB_CA2":   PN = "DV44"  !CDS_PN = "DV44";
"DDR6_SB_CA3":   PN = "DY44"  !CDS_PN = "DY44";
"DDR6_SB_CA4":   PN = "DU43"  !CDS_PN = "DU43";
"DDR6_SB_CA5":   PN = "EA43"  !CDS_PN = "EA43";
"DDR6_SB_CA6":   PN = "DT42"  !CDS_PN = "DT42";
"DDR6_SB_DQ0":   PN = "DL35"  !CDS_PN = "DL35";
"DDR6_SB_DQ1":   PN = "DK34"  !CDS_PN = "DK34";
"DDR6_SB_DQ2":   PN = "DN35"  !CDS_PN = "DN35";
"DDR6_SB_DQ3":   PN = "DP34"  !CDS_PN = "DP34";
"DDR6_SB_DQ4":   PN = "DK32"  !CDS_PN = "DK32";
"DDR6_SB_DQ5":   PN = "DL31"  !CDS_PN = "DL31";
"DDR6_SB_DQ6":   PN = "DP32"  !CDS_PN = "DP32";
"DDR6_SB_DQ7":   PN = "DN31"  !CDS_PN = "DN31";
"DDR6_SB_DQ8":   PN = "DN29"  !CDS_PN = "DN29";
"DDR6_SB_DQ9":   PN = "DK28"  !CDS_PN = "DK28";
"DDR6_SB_DQ10":   PN = "DL29"  !CDS_PN = "DL29";
"DDR6_SB_DQ11":   PN = "DP28"  !CDS_PN = "DP28";
"DDR6_SB_DQ12":   PN = "DK26"  !CDS_PN = "DK26";
"DDR6_SB_DQ13":   PN = "DL25"  !CDS_PN = "DL25";
"DDR6_SB_DQ14":   PN = "DP26"  !CDS_PN = "DP26";
"DDR6_SB_DQ15":   PN = "DN25"  !CDS_PN = "DN25";
"DDR6_SB_DQ16":   PN = "DV26"  !CDS_PN = "DV26";
"DDR6_SB_DQ17":   PN = "DU25"  !CDS_PN = "DU25";
"DDR6_SB_DQ18":   PN = "DY26"  !CDS_PN = "DY26";
"DDR6_SB_DQ19":   PN = "EA25"  !CDS_PN = "EA25";
"DDR6_SB_DQ20":   PN = "DU23"  !CDS_PN = "DU23";
"DDR6_SB_DQ21":   PN = "DV22"  !CDS_PN = "DV22";
"DDR6_SB_DQ22":   PN = "EA23"  !CDS_PN = "EA23";
"DDR6_SB_DQ23":   PN = "DY22"  !CDS_PN = "DY22";
"DDR6_SB_DQ24":   PN = "EK8"  !CDS_PN = "EK8";
"DDR6_SB_DQ25":   PN = "EH8"  !CDS_PN = "EH8";
"DDR6_SB_DQ26":   PN = "EP8"  !CDS_PN = "EP8";
"DDR6_SB_DQ27":   PN = "ET8"  !CDS_PN = "ET8";
"DDR6_SB_DQ28":   PN = "EK6"  !CDS_PN = "EK6";
"DDR6_SB_DQ29":   PN = "EJ5"  !CDS_PN = "EJ5";
"DDR6_SB_DQ30":   PN = "EP4"  !CDS_PN = "EP4";
"DDR6_SB_DQ31":   PN = "EM4"  !CDS_PN = "EM4";
"DDR6_SB_DQS_DN0":   PN = "DJ33"  !CDS_PN = "DJ33";
"DDR6_SB_DQS_DN1":   PN = "DJ27"  !CDS_PN = "DJ27";
"DDR6_SB_DQS_DN2":   PN = "DV24"  !CDS_PN = "DV24";
"DDR6_SB_DQS_DN3":   PN = "EP6"  !CDS_PN = "EP6";
"DDR6_SB_DQS_DN4":   PN = "EB36"  !CDS_PN = "EB36";
"DDR6_SB_DQS_DN5":   PN = "DR33"  !CDS_PN = "DR33";
"DDR6_SB_DQS_DN6":   PN = "DN27"  !CDS_PN = "DN27";
"DDR6_SB_DQS_DN7":   PN = "EB24"  !CDS_PN = "EB24";
"DDR6_SB_DQS_DN8":   PN = "EM6"  !CDS_PN = "EM6";
"DDR6_SB_DQS_DN9":   PN = "DV36"  !CDS_PN = "DV36";
"DDR6_SB_DQS_DP0":   PN = "DL33"  !CDS_PN = "DL33";
"DDR6_SB_DQS_DP1":   PN = "DL27"  !CDS_PN = "DL27";
"DDR6_SB_DQS_DP2":   PN = "DT24"  !CDS_PN = "DT24";
"DDR6_SB_DQS_DP3":   PN = "EN7"  !CDS_PN = "EN7";
"DDR6_SB_DQS_DP4":   PN = "DY36"  !CDS_PN = "DY36";
"DDR6_SB_DQS_DP5":   PN = "DN33"  !CDS_PN = "DN33";
"DDR6_SB_DQS_DP6":   PN = "DR27"  !CDS_PN = "DR27";
"DDR6_SB_DQS_DP7":   PN = "DY24"  !CDS_PN = "DY24";
"DDR6_SB_DQS_DP8":   PN = "EN5"  !CDS_PN = "EN5";
"DDR6_SB_DQS_DP9":   PN = "DT36"  !CDS_PN = "DT36";
"DDR6_SB_ECC0":   PN = "DU35"  !CDS_PN = "DU35";
"DDR6_SB_ECC1":   PN = "DV34"  !CDS_PN = "DV34";
"DDR6_SB_ECC2":   PN = "EA35"  !CDS_PN = "EA35";
"DDR6_SB_ECC3":   PN = "DY34"  !CDS_PN = "DY34";
"DDR6_SB_ECC4":   PN = "DV38"  !CDS_PN = "DV38";
"DDR6_SB_ECC5":   PN = "DU37"  !CDS_PN = "DU37";
"DDR6_SB_ECC6":   PN = "DY38"  !CDS_PN = "DY38";
"DDR6_SB_ECC7":   PN = "EA37"  !CDS_PN = "EA37";
"DDR6_SB_PAR":   PN = "EB42"  !CDS_PN = "EB42";
"DDR6_SA_CS_N0":   PN = "DN54"  !CDS_PN = "DN54";
"DDR6_SA_CS_N1":   PN = "DP53"  !CDS_PN = "DP53";
"DDR6_SA_CS_N2":   PN = "DL54"  !CDS_PN = "DL54";
"DDR6_SA_CS_N3":   PN = "DK53"  !CDS_PN = "DK53";
"DDR6_SB_CS_N0":   PN = "EA41"  !CDS_PN = "EA41";
"DDR6_SB_CS_N1":   PN = "DY40"  !CDS_PN = "DY40";
"DDR6_SB_CS_N2":   PN = "DU41"  !CDS_PN = "DU41";
"DDR6_SB_CS_N3":   PN = "DV40"  !CDS_PN = "DV40";
DRAWING = "@s9s_mb_2u_lib.s9s_mb_2u(sch_1):page27";
BODY = "SOCKET4677_AZIF0045P001C01CS","I169": LOCATION = "U2" #&CDS_LOCATION = "U2" &SEC = "15" #&CDS_SEC = "15";
"DDR7_A_RSP0":   PN = "EG48"  !CDS_PN = "EG48";
"DDR7_A_RSP1":   PN = "EH47"  !CDS_PN = "EH47";
"DDR7_ALERT_N":   PN = "CY51"  !CDS_PN = "CY51";
"DDR7_B_RSP0":   PN = "EE48"  !CDS_PN = "EE48";
"DDR7_B_RSP1":   PN = "ED47"  !CDS_PN = "ED47";
"DDR7_CLK_DN0":   PN = "DH42"  !CDS_PN = "DH42";
"DDR7_CLK_DN1":   PN = "DD42"  !CDS_PN = "DD42";
"DDR7_CLK_DP0":   PN = "DF42"  !CDS_PN = "DF42";
"DDR7_CLK_DP1":   PN = "DB42"  !CDS_PN = "DB42";
"DDR7_SA_CA0":   PN = "DB49"  !CDS_PN = "DB49";
"DDR7_SA_CA1":   PN = "DH49"  !CDS_PN = "DH49";
"DDR7_SA_CA2":   PN = "DC48"  !CDS_PN = "DC48";
"DDR7_SA_CA3":   PN = "DG48"  !CDS_PN = "DG48";
"DDR7_SA_CA4":   PN = "DD47"  !CDS_PN = "DD47";
"DDR7_SA_CA5":   PN = "DF47"  !CDS_PN = "DF47";
"DDR7_SA_CA6":   PN = "DC41"  !CDS_PN = "DC41";
"DDR7_SA_DQ0":   PN = "DY79"  !CDS_PN = "DY79";
"DDR7_SA_DQ1":   PN = "DT77"  !CDS_PN = "DT77";
"DDR7_SA_DQ2":   PN = "DW78"  !CDS_PN = "DW78";
"DDR7_SA_DQ3":   PN = "DP77"  !CDS_PN = "DP77";
"DDR7_SA_DQ4":   PN = "DK75"  !CDS_PN = "DK75";
"DDR7_SA_DQ5":   PN = "DL74"  !CDS_PN = "DL74";
"DDR7_SA_DQ6":   PN = "DP75"  !CDS_PN = "DP75";
"DDR7_SA_DQ7":   PN = "DN74"  !CDS_PN = "DN74";
"DDR7_SA_DQ8":   PN = "DD75"  !CDS_PN = "DD75";
"DDR7_SA_DQ9":   PN = "DC74"  !CDS_PN = "DC74";
"DDR7_SA_DQ10":   PN = "DF75"  !CDS_PN = "DF75";
"DDR7_SA_DQ11":   PN = "DG74"  !CDS_PN = "DG74";
"DDR7_SA_DQ12":   PN = "DC72"  !CDS_PN = "DC72";
"DDR7_SA_DQ13":   PN = "DD71"  !CDS_PN = "DD71";
"DDR7_SA_DQ14":   PN = "DG72"  !CDS_PN = "DG72";
"DDR7_SA_DQ15":   PN = "DF71"  !CDS_PN = "DF71";
"DDR7_SA_DQ16":   PN = "DD69"  !CDS_PN = "DD69";
"DDR7_SA_DQ17":   PN = "DC68"  !CDS_PN = "DC68";
"DDR7_SA_DQ18":   PN = "DF69"  !CDS_PN = "DF69";
"DDR7_SA_DQ19":   PN = "DG68"  !CDS_PN = "DG68";
"DDR7_SA_DQ20":   PN = "DC66"  !CDS_PN = "DC66";
"DDR7_SA_DQ21":   PN = "DD65"  !CDS_PN = "DD65";
"DDR7_SA_DQ22":   PN = "DG66"  !CDS_PN = "DG66";
"DDR7_SA_DQ23":   PN = "DF65"  !CDS_PN = "DF65";
"DDR7_SA_DQ24":   PN = "DD63"  !CDS_PN = "DD63";
"DDR7_SA_DQ25":   PN = "DC62"  !CDS_PN = "DC62";
"DDR7_SA_DQ26":   PN = "DF63"  !CDS_PN = "DF63";
"DDR7_SA_DQ27":   PN = "DG62"  !CDS_PN = "DG62";
"DDR7_SA_DQ28":   PN = "DC60"  !CDS_PN = "DC60";
"DDR7_SA_DQ29":   PN = "DD59"  !CDS_PN = "DD59";
"DDR7_SA_DQ30":   PN = "DG60"  !CDS_PN = "DG60";
"DDR7_SA_DQ31":   PN = "DF59"  !CDS_PN = "DF59";
"DDR7_SA_DQS_DN0":   PN = "DJ76"  !CDS_PN = "DJ76";
"DDR7_SA_DQS_DN1":   PN = "DB73"  !CDS_PN = "DB73";
"DDR7_SA_DQS_DN2":   PN = "DD67"  !CDS_PN = "DD67";
"DDR7_SA_DQS_DN3":   PN = "DD61"  !CDS_PN = "DD61";
"DDR7_SA_DQS_DN4":   PN = "DD55"  !CDS_PN = "DD55";
"DDR7_SA_DQS_DN5":   PN = "DR76"  !CDS_PN = "DR76";
"DDR7_SA_DQS_DN6":   PN = "DH73"  !CDS_PN = "DH73";
"DDR7_SA_DQS_DN7":   PN = "DH67"  !CDS_PN = "DH67";
"DDR7_SA_DQS_DN8":   PN = "DH61"  !CDS_PN = "DH61";
"DDR7_SA_DQS_DN9":   PN = "DH55"  !CDS_PN = "DH55";
"DDR7_SA_DQS_DP0":   PN = "DL76"  !CDS_PN = "DL76";
"DDR7_SA_DQS_DP1":   PN = "DD73"  !CDS_PN = "DD73";
"DDR7_SA_DQS_DP2":   PN = "DB67"  !CDS_PN = "DB67";
"DDR7_SA_DQS_DP3":   PN = "DB61"  !CDS_PN = "DB61";
"DDR7_SA_DQS_DP4":   PN = "DB55"  !CDS_PN = "DB55";
"DDR7_SA_DQS_DP5":   PN = "DN76"  !CDS_PN = "DN76";
"DDR7_SA_DQS_DP6":   PN = "DF73"  !CDS_PN = "DF73";
"DDR7_SA_DQS_DP7":   PN = "DF67"  !CDS_PN = "DF67";
"DDR7_SA_DQS_DP8":   PN = "DF61"  !CDS_PN = "DF61";
"DDR7_SA_DQS_DP9":   PN = "DF55"  !CDS_PN = "DF55";
"DDR7_SA_ECC0":   PN = "DD57"  !CDS_PN = "DD57";
"DDR7_SA_ECC1":   PN = "DC56"  !CDS_PN = "DC56";
"DDR7_SA_ECC2":   PN = "DF57"  !CDS_PN = "DF57";
"DDR7_SA_ECC3":   PN = "DG56"  !CDS_PN = "DG56";
"DDR7_SA_ECC4":   PN = "DC54"  !CDS_PN = "DC54";
"DDR7_SA_ECC5":   PN = "DD53"  !CDS_PN = "DD53";
"DDR7_SA_ECC6":   PN = "DG54"  !CDS_PN = "DG54";
"DDR7_SA_ECC7":   PN = "DF53"  !CDS_PN = "DF53";
"DDR7_SA_PAR":   PN = "DD40"  !CDS_PN = "DD40";
"DDR7_SB_CA0":   PN = "DF40"  !CDS_PN = "DF40";
"DDR7_SB_CA1":   PN = "DG41"  !CDS_PN = "DG41";
"DDR7_SB_CA2":   PN = "DL41"  !CDS_PN = "DL41";
"DDR7_SB_CA3":   PN = "DN41"  !CDS_PN = "DN41";
"DDR7_SB_CA4":   PN = "DK40"  !CDS_PN = "DK40";
"DDR7_SB_CA5":   PN = "DP40"  !CDS_PN = "DP40";
"DDR7_SB_CA6":   PN = "DJ39"  !CDS_PN = "DJ39";
"DDR7_SB_DQ0":   PN = "DD32"  !CDS_PN = "DD32";
"DDR7_SB_DQ1":   PN = "DC31"  !CDS_PN = "DC31";
"DDR7_SB_DQ2":   PN = "DF32"  !CDS_PN = "DF32";
"DDR7_SB_DQ3":   PN = "DG31"  !CDS_PN = "DG31";
"DDR7_SB_DQ4":   PN = "DC29"  !CDS_PN = "DC29";
"DDR7_SB_DQ5":   PN = "DF28"  !CDS_PN = "DF28";
"DDR7_SB_DQ6":   PN = "DG29"  !CDS_PN = "DG29";
"DDR7_SB_DQ7":   PN = "DD28"  !CDS_PN = "DD28";
"DDR7_SB_DQ8":   PN = "DD26"  !CDS_PN = "DD26";
"DDR7_SB_DQ9":   PN = "DC25"  !CDS_PN = "DC25";
"DDR7_SB_DQ10":   PN = "DF26"  !CDS_PN = "DF26";
"DDR7_SB_DQ11":   PN = "DG25"  !CDS_PN = "DG25";
"DDR7_SB_DQ12":   PN = "DC23"  !CDS_PN = "DC23";
"DDR7_SB_DQ13":   PN = "DD22"  !CDS_PN = "DD22";
"DDR7_SB_DQ14":   PN = "DG23"  !CDS_PN = "DG23";
"DDR7_SB_DQ15":   PN = "DF22"  !CDS_PN = "DF22";
"DDR7_SB_DQ16":   PN = "DL23"  !CDS_PN = "DL23";
"DDR7_SB_DQ17":   PN = "DK22"  !CDS_PN = "DK22";
"DDR7_SB_DQ18":   PN = "DN23"  !CDS_PN = "DN23";
"DDR7_SB_DQ19":   PN = "DP22"  !CDS_PN = "DP22";
"DDR7_SB_DQ20":   PN = "DK20"  !CDS_PN = "DK20";
"DDR7_SB_DQ21":   PN = "DL19"  !CDS_PN = "DL19";
"DDR7_SB_DQ22":   PN = "DP20"  !CDS_PN = "DP20";
"DDR7_SB_DQ23":   PN = "DN19"  !CDS_PN = "DN19";
"DDR7_SB_DQ24":   PN = "DD20"  !CDS_PN = "DD20";
"DDR7_SB_DQ25":   PN = "DC19"  !CDS_PN = "DC19";
"DDR7_SB_DQ26":   PN = "DF20"  !CDS_PN = "DF20";
"DDR7_SB_DQ27":   PN = "DG19"  !CDS_PN = "DG19";
"DDR7_SB_DQ28":   PN = "DG17"  !CDS_PN = "DG17";
"DDR7_SB_DQ29":   PN = "DA17"  !CDS_PN = "DA17";
"DDR7_SB_DQ30":   PN = "DJ17"  !CDS_PN = "DJ17";
"DDR7_SB_DQ31":   PN = "DC17"  !CDS_PN = "DC17";
"DDR7_SB_DQS_DN0":   PN = "DD30"  !CDS_PN = "DD30";
"DDR7_SB_DQS_DN1":   PN = "DD24"  !CDS_PN = "DD24";
"DDR7_SB_DQS_DN2":   PN = "DL21"  !CDS_PN = "DL21";
"DDR7_SB_DQS_DN3":   PN = "DB18"  !CDS_PN = "DB18";
"DDR7_SB_DQS_DN4":   PN = "DH36"  !CDS_PN = "DH36";
"DDR7_SB_DQS_DN5":   PN = "DH30"  !CDS_PN = "DH30";
"DDR7_SB_DQS_DN6":   PN = "DH24"  !CDS_PN = "DH24";
"DDR7_SB_DQS_DN7":   PN = "DR21"  !CDS_PN = "DR21";
"DDR7_SB_DQS_DN8":   PN = "DF18"  !CDS_PN = "DF18";
"DDR7_SB_DQS_DN9":   PN = "DD36"  !CDS_PN = "DD36";
"DDR7_SB_DQS_DP0":   PN = "DB30"  !CDS_PN = "DB30";
"DDR7_SB_DQS_DP1":   PN = "DB24"  !CDS_PN = "DB24";
"DDR7_SB_DQS_DP2":   PN = "DJ21"  !CDS_PN = "DJ21";
"DDR7_SB_DQS_DP3":   PN = "DD18"  !CDS_PN = "DD18";
"DDR7_SB_DQS_DP4":   PN = "DF36"  !CDS_PN = "DF36";
"DDR7_SB_DQS_DP5":   PN = "DF30"  !CDS_PN = "DF30";
"DDR7_SB_DQS_DP6":   PN = "DF24"  !CDS_PN = "DF24";
"DDR7_SB_DQS_DP7":   PN = "DN21"  !CDS_PN = "DN21";
"DDR7_SB_DQS_DP8":   PN = "DH18"  !CDS_PN = "DH18";
"DDR7_SB_DQS_DP9":   PN = "DB36"  !CDS_PN = "DB36";
"DDR7_SB_ECC0":   PN = "DC35"  !CDS_PN = "DC35";
"DDR7_SB_ECC1":   PN = "DD34"  !CDS_PN = "DD34";
"DDR7_SB_ECC2":   PN = "DG35"  !CDS_PN = "DG35";
"DDR7_SB_ECC3":   PN = "DF34"  !CDS_PN = "DF34";
"DDR7_SB_ECC4":   PN = "DF38"  !CDS_PN = "DF38";
"DDR7_SB_ECC5":   PN = "DG37"  !CDS_PN = "DG37";
"DDR7_SB_ECC6":   PN = "DD38"  !CDS_PN = "DD38";
"DDR7_SB_ECC7":   PN = "DC37"  !CDS_PN = "DC37";
"DDR7_SB_PAR":   PN = "DR39"  !CDS_PN = "DR39";
"DDR7_SA_CS_N0":   PN = "DF51"  !CDS_PN = "DF51";
"DDR7_SA_CS_N1":   PN = "DG50"  !CDS_PN = "DG50";
"DDR7_SA_CS_N2":   PN = "DD51"  !CDS_PN = "DD51";
"DDR7_SA_CS_N3":   PN = "DC50"  !CDS_PN = "DC50";
"DDR7_SB_CS_N0":   PN = "DL37"  !CDS_PN = "DL37";
"DDR7_SB_CS_N1":   PN = "DN37"  !CDS_PN = "DN37";
"DDR7_SB_CS_N2":   PN = "DK38"  !CDS_PN = "DK38";
"DDR7_SB_CS_N3":   PN = "DP38"  !CDS_PN = "DP38";
DRAWING = "@s9s_mb_2u_lib.s9s_mb_2u(sch_1):page28";
BODY = "SOCKET4677_AZIF0045P001C01CS","I169": LOCATION = "U2" #&CDS_LOCATION = "U2" &SEC = "16" #&CDS_SEC = "16";
"DMI_RX_DN0":   PN = "BB18"  !CDS_PN = "BB18";
"DMI_RX_DN1":   PN = "BE17"  !CDS_PN = "BE17";
"DMI_RX_DN2":   PN = "BF18"  !CDS_PN = "BF18";
"DMI_RX_DN3":   PN = "BJ17"  !CDS_PN = "BJ17";
"DMI_RX_DN4":   PN = "BK18"  !CDS_PN = "BK18";
"DMI_RX_DN5":   PN = "BN17"  !CDS_PN = "BN17";
"DMI_RX_DN6":   PN = "BP18"  !CDS_PN = "BP18";
"DMI_RX_DN7":   PN = "BU17"  !CDS_PN = "BU17";
"DMI_RX_DP0":   PN = "BC19"  !CDS_PN = "BC19";
"DMI_RX_DP1":   PN = "BD18"  !CDS_PN = "BD18";
"DMI_RX_DP2":   PN = "BG19"  !CDS_PN = "BG19";
"DMI_RX_DP3":   PN = "BH18"  !CDS_PN = "BH18";
"DMI_RX_DP4":   PN = "BL19"  !CDS_PN = "BL19";
"DMI_RX_DP5":   PN = "BM18"  !CDS_PN = "BM18";
"DMI_RX_DP6":   PN = "BR19"  !CDS_PN = "BR19";
"DMI_RX_DP7":   PN = "BT18"  !CDS_PN = "BT18";
"DMI_TX_DN0":   PN = "BW19"  !CDS_PN = "BW19";
"DMI_TX_DN1":   PN = "CA17"  !CDS_PN = "CA17";
"DMI_TX_DN2":   PN = "CB18"  !CDS_PN = "CB18";
"DMI_TX_DN3":   PN = "CE17"  !CDS_PN = "CE17";
"DMI_TX_DN4":   PN = "CF18"  !CDS_PN = "CF18";
"DMI_TX_DN5":   PN = "CJ17"  !CDS_PN = "CJ17";
"DMI_TX_DN6":   PN = "CK18"  !CDS_PN = "CK18";
"DMI_TX_DN7":   PN = "CN17"  !CDS_PN = "CN17";
"DMI_TX_DP0":   PN = "CA19"  !CDS_PN = "CA19";
"DMI_TX_DP1":   PN = "BY18"  !CDS_PN = "BY18";
"DMI_TX_DP2":   PN = "CC19"  !CDS_PN = "CC19";
"DMI_TX_DP3":   PN = "CD18"  !CDS_PN = "CD18";
"DMI_TX_DP4":   PN = "CG19"  !CDS_PN = "CG19";
"DMI_TX_DP5":   PN = "CH18"  !CDS_PN = "CH18";
"DMI_TX_DP6":   PN = "CL19"  !CDS_PN = "CL19";
"DMI_TX_DP7":   PN = "CM18"  !CDS_PN = "CM18";
DRAWING = "@s9s_mb_2u_lib.s9s_mb_2u(sch_1):page29";
BODY = "SOCKET4677_AZIF0045P001C01CS","I37": LOCATION = "U2" #&CDS_LOCATION = "U2" &SEC = "17" #&CDS_SEC = "17";
"PE0_RX_DN0":   PN = "K10"  !CDS_PN = "K10";
"PE0_RX_DN1":   PN = "M10"  !CDS_PN = "M10";
"PE0_RX_DN2":   PN = "P10"  !CDS_PN = "P10";
"PE0_RX_DN3":   PN = "T10"  !CDS_PN = "T10";
"PE0_RX_DN4":   PN = "V10"  !CDS_PN = "V10";
"PE0_RX_DN5":   PN = "AA9"  !CDS_PN = "AA9";
"PE0_RX_DN6":   PN = "AB10"  !CDS_PN = "AB10";
"PE0_RX_DN7":   PN = "AE9"  !CDS_PN = "AE9";
"PE0_RX_DN8":   PN = "AF10"  !CDS_PN = "AF10";
"PE0_RX_DN9":   PN = "AJ9"  !CDS_PN = "AJ9";
"PE0_RX_DN10":   PN = "AK10"  !CDS_PN = "AK10";
"PE0_RX_DN11":   PN = "AM10"  !CDS_PN = "AM10";
"PE0_RX_DN12":   PN = "AP10"  !CDS_PN = "AP10";
"PE0_RX_DN13":   PN = "AU9"  !CDS_PN = "AU9";
"PE0_RX_DN14":   PN = "AV10"  !CDS_PN = "AV10";
"PE0_RX_DN15":   PN = "BA9"  !CDS_PN = "BA9";
"PE0_RX_DP0":   PN = "L11"  !CDS_PN = "L11";
"PE0_RX_DP1":   PN = "N9"  !CDS_PN = "N9";
"PE0_RX_DP2":   PN = "R11"  !CDS_PN = "R11";
"PE0_RX_DP3":   PN = "U9"  !CDS_PN = "U9";
"PE0_RX_DP4":   PN = "W11"  !CDS_PN = "W11";
"PE0_RX_DP5":   PN = "Y10"  !CDS_PN = "Y10";
"PE0_RX_DP6":   PN = "AC11"  !CDS_PN = "AC11";
"PE0_RX_DP7":   PN = "AD10"  !CDS_PN = "AD10";
"PE0_RX_DP8":   PN = "AG11"  !CDS_PN = "AG11";
"PE0_RX_DP9":   PN = "AH10"  !CDS_PN = "AH10";
"PE0_RX_DP10":   PN = "AL11"  !CDS_PN = "AL11";
"PE0_RX_DP11":   PN = "AN9"  !CDS_PN = "AN9";
"PE0_RX_DP12":   PN = "AR11"  !CDS_PN = "AR11";
"PE0_RX_DP13":   PN = "AT10"  !CDS_PN = "AT10";
"PE0_RX_DP14":   PN = "AW11"  !CDS_PN = "AW11";
"PE0_RX_DP15":   PN = "AY10"  !CDS_PN = "AY10";
"PE0_TX_DN0":   PN = "N13"  !CDS_PN = "N13";
"PE0_TX_DN1":   PN = "P14"  !CDS_PN = "P14";
"PE0_TX_DN2":   PN = "U13"  !CDS_PN = "U13";
"PE0_TX_DN3":   PN = "V14"  !CDS_PN = "V14";
"PE0_TX_DN4":   PN = "AA13"  !CDS_PN = "AA13";
"PE0_TX_DN5":   PN = "AB14"  !CDS_PN = "AB14";
"PE0_TX_DN6":   PN = "AE13"  !CDS_PN = "AE13";
"PE0_TX_DN7":   PN = "AF14"  !CDS_PN = "AF14";
"PE0_TX_DN8":   PN = "AJ13"  !CDS_PN = "AJ13";
"PE0_TX_DN9":   PN = "AK14"  !CDS_PN = "AK14";
"PE0_TX_DN10":   PN = "AN13"  !CDS_PN = "AN13";
"PE0_TX_DN11":   PN = "AP14"  !CDS_PN = "AP14";
"PE0_TX_DN12":   PN = "AU13"  !CDS_PN = "AU13";
"PE0_TX_DN13":   PN = "AV14"  !CDS_PN = "AV14";
"PE0_TX_DN14":   PN = "BA13"  !CDS_PN = "BA13";
"PE0_TX_DN15":   PN = "BB14"  !CDS_PN = "BB14";
"PE0_TX_DP0":   PN = "M14"  !CDS_PN = "M14";
"PE0_TX_DP1":   PN = "R15"  !CDS_PN = "R15";
"PE0_TX_DP2":   PN = "T14"  !CDS_PN = "T14";
"PE0_TX_DP3":   PN = "W15"  !CDS_PN = "W15";
"PE0_TX_DP4":   PN = "Y14"  !CDS_PN = "Y14";
"PE0_TX_DP5":   PN = "AC15"  !CDS_PN = "AC15";
"PE0_TX_DP6":   PN = "AD14"  !CDS_PN = "AD14";
"PE0_TX_DP7":   PN = "AG15"  !CDS_PN = "AG15";
"PE0_TX_DP8":   PN = "AH14"  !CDS_PN = "AH14";
"PE0_TX_DP9":   PN = "AL15"  !CDS_PN = "AL15";
"PE0_TX_DP10":   PN = "AM14"  !CDS_PN = "AM14";
"PE0_TX_DP11":   PN = "AR15"  !CDS_PN = "AR15";
"PE0_TX_DP12":   PN = "AT14"  !CDS_PN = "AT14";
"PE0_TX_DP13":   PN = "AW15"  !CDS_PN = "AW15";
"PE0_TX_DP14":   PN = "AY14"  !CDS_PN = "AY14";
"PE0_TX_DP15":   PN = "BC15"  !CDS_PN = "BC15";
BODY = "SOCKET4677_AZIF0045P001C01CS","I176": LOCATION = "U2" #&CDS_LOCATION = "U2" &SEC = "18" #&CDS_SEC = "18";
"PE1_RX_DN0":   PN = "CP10"  !CDS_PN = "CP10";
"PE1_RX_DN1":   PN = "CL11"  !CDS_PN = "CL11";
"PE1_RX_DN2":   PN = "CK10"  !CDS_PN = "CK10";
"PE1_RX_DN3":   PN = "CG11"  !CDS_PN = "CG11";
"PE1_RX_DN4":   PN = "CF10"  !CDS_PN = "CF10";
"PE1_RX_DN5":   PN = "CC11"  !CDS_PN = "CC11";
"PE1_RX_DN6":   PN = "CB10"  !CDS_PN = "CB10";
"PE1_RX_DN7":   PN = "BW11"  !CDS_PN = "BW11";
"PE1_RX_DN8":   PN = "BV10"  !CDS_PN = "BV10";
"PE1_RX_DN9":   PN = "BR11"  !CDS_PN = "BR11";
"PE1_RX_DN10":   PN = "BP10"  !CDS_PN = "BP10";
"PE1_RX_DN11":   PN = "BL11"  !CDS_PN = "BL11";
"PE1_RX_DN12":   PN = "BK10"  !CDS_PN = "BK10";
"PE1_RX_DN13":   PN = "BG11"  !CDS_PN = "BG11";
"PE1_RX_DN14":   PN = "BF10"  !CDS_PN = "BF10";
"PE1_RX_DN15":   PN = "BC11"  !CDS_PN = "BC11";
"PE1_RX_DP0":   PN = "CN9"  !CDS_PN = "CN9";
"PE1_RX_DP1":   PN = "CM10"  !CDS_PN = "CM10";
"PE1_RX_DP2":   PN = "CJ9"  !CDS_PN = "CJ9";
"PE1_RX_DP3":   PN = "CH10"  !CDS_PN = "CH10";
"PE1_RX_DP4":   PN = "CE9"  !CDS_PN = "CE9";
"PE1_RX_DP5":   PN = "CD10"  !CDS_PN = "CD10";
"PE1_RX_DP6":   PN = "CA9"  !CDS_PN = "CA9";
"PE1_RX_DP7":   PN = "BY10"  !CDS_PN = "BY10";
"PE1_RX_DP8":   PN = "BU9"  !CDS_PN = "BU9";
"PE1_RX_DP9":   PN = "BT10"  !CDS_PN = "BT10";
"PE1_RX_DP10":   PN = "BN9"  !CDS_PN = "BN9";
"PE1_RX_DP11":   PN = "BM10"  !CDS_PN = "BM10";
"PE1_RX_DP12":   PN = "BJ9"  !CDS_PN = "BJ9";
"PE1_RX_DP13":   PN = "BH10"  !CDS_PN = "BH10";
"PE1_RX_DP14":   PN = "BE9"  !CDS_PN = "BE9";
"PE1_RX_DP15":   PN = "BD10"  !CDS_PN = "BD10";
"PE1_TX_DN0":   PN = "CP14"  !CDS_PN = "CP14";
"PE1_TX_DN1":   PN = "CN13"  !CDS_PN = "CN13";
"PE1_TX_DN2":   PN = "CK14"  !CDS_PN = "CK14";
"PE1_TX_DN3":   PN = "CJ13"  !CDS_PN = "CJ13";
"PE1_TX_DN4":   PN = "CF14"  !CDS_PN = "CF14";
"PE1_TX_DN5":   PN = "CE13"  !CDS_PN = "CE13";
"PE1_TX_DN6":   PN = "CB14"  !CDS_PN = "CB14";
"PE1_TX_DN7":   PN = "CA13"  !CDS_PN = "CA13";
"PE1_TX_DN8":   PN = "BV14"  !CDS_PN = "BV14";
"PE1_TX_DN9":   PN = "BU13"  !CDS_PN = "BU13";
"PE1_TX_DN10":   PN = "BP14"  !CDS_PN = "BP14";
"PE1_TX_DN11":   PN = "BN13"  !CDS_PN = "BN13";
"PE1_TX_DN12":   PN = "BK14"  !CDS_PN = "BK14";
"PE1_TX_DN13":   PN = "BJ13"  !CDS_PN = "BJ13";
"PE1_TX_DN14":   PN = "BF14"  !CDS_PN = "BF14";
"PE1_TX_DN15":   PN = "BE13"  !CDS_PN = "BE13";
"PE1_TX_DP0":   PN = "CR15"  !CDS_PN = "CR15";
"PE1_TX_DP1":   PN = "CM14"  !CDS_PN = "CM14";
"PE1_TX_DP2":   PN = "CL15"  !CDS_PN = "CL15";
"PE1_TX_DP3":   PN = "CH14"  !CDS_PN = "CH14";
"PE1_TX_DP4":   PN = "CG15"  !CDS_PN = "CG15";
"PE1_TX_DP5":   PN = "CD14"  !CDS_PN = "CD14";
"PE1_TX_DP6":   PN = "CC15"  !CDS_PN = "CC15";
"PE1_TX_DP7":   PN = "BY14"  !CDS_PN = "BY14";
"PE1_TX_DP8":   PN = "BW15"  !CDS_PN = "BW15";
"PE1_TX_DP9":   PN = "BT14"  !CDS_PN = "BT14";
"PE1_TX_DP10":   PN = "BR15"  !CDS_PN = "BR15";
"PE1_TX_DP11":   PN = "BM14"  !CDS_PN = "BM14";
"PE1_TX_DP12":   PN = "BL15"  !CDS_PN = "BL15";
"PE1_TX_DP13":   PN = "BH14"  !CDS_PN = "BH14";
"PE1_TX_DP14":   PN = "BG15"  !CDS_PN = "BG15";
"PE1_TX_DP15":   PN = "BD14"  !CDS_PN = "BD14";
DRAWING = "@s9s_mb_2u_lib.s9s_mb_2u(sch_1):page30";
BODY = "SOCKET4677_AZIF0045P001C01CS","I139": LOCATION = "U2" #&CDS_LOCATION = "U2" &SEC = "19" #&CDS_SEC = "19";
"PE2_RX_DN0":   PN = "CU9"  !CDS_PN = "CU9";
"PE2_RX_DN1":   PN = "CY10"  !CDS_PN = "CY10";
"PE2_RX_DN2":   PN = "DA9"  !CDS_PN = "DA9";
"PE2_RX_DN3":   PN = "DD10"  !CDS_PN = "DD10";
"PE2_RX_DN4":   PN = "DE9"  !CDS_PN = "DE9";
"PE2_RX_DN5":   PN = "DH10"  !CDS_PN = "DH10";
"PE2_RX_DN6":   PN = "DJ9"  !CDS_PN = "DJ9";
"PE2_RX_DN7":   PN = "DM10"  !CDS_PN = "DM10";
"PE2_RX_DN8":   PN = "DN9"  !CDS_PN = "DN9";
"PE2_RX_DN9":   PN = "DT10"  !CDS_PN = "DT10";
"PE2_RX_DN10":   PN = "DU9"  !CDS_PN = "DU9";
"PE2_RX_DN11":   PN = "DY10"  !CDS_PN = "DY10";
"PE2_RX_DN12":   PN = "EA9"  !CDS_PN = "EA9";
"PE2_RX_DN13":   PN = "ED10"  !CDS_PN = "ED10";
"PE2_RX_DN14":   PN = "EE9"  !CDS_PN = "EE9";
"PE2_RX_DN15":   PN = "EH10"  !CDS_PN = "EH10";
"PE2_RX_DP0":   PN = "CV10"  !CDS_PN = "CV10";
"PE2_RX_DP1":   PN = "CW11"  !CDS_PN = "CW11";
"PE2_RX_DP2":   PN = "DB10"  !CDS_PN = "DB10";
"PE2_RX_DP3":   PN = "DC11"  !CDS_PN = "DC11";
"PE2_RX_DP4":   PN = "DF10"  !CDS_PN = "DF10";
"PE2_RX_DP5":   PN = "DG11"  !CDS_PN = "DG11";
"PE2_RX_DP6":   PN = "DK10"  !CDS_PN = "DK10";
"PE2_RX_DP7":   PN = "DL11"  !CDS_PN = "DL11";
"PE2_RX_DP8":   PN = "DP10"  !CDS_PN = "DP10";
"PE2_RX_DP9":   PN = "DR11"  !CDS_PN = "DR11";
"PE2_RX_DP10":   PN = "DV10"  !CDS_PN = "DV10";
"PE2_RX_DP11":   PN = "DW11"  !CDS_PN = "DW11";
"PE2_RX_DP12":   PN = "EB10"  !CDS_PN = "EB10";
"PE2_RX_DP13":   PN = "EC11"  !CDS_PN = "EC11";
"PE2_RX_DP14":   PN = "EF10"  !CDS_PN = "EF10";
"PE2_RX_DP15":   PN = "EG11"  !CDS_PN = "EG11";
"PE2_TX_DN0":   PN = "CU13"  !CDS_PN = "CU13";
"PE2_TX_DN1":   PN = "CV14"  !CDS_PN = "CV14";
"PE2_TX_DN2":   PN = "DA13"  !CDS_PN = "DA13";
"PE2_TX_DN3":   PN = "DB14"  !CDS_PN = "DB14";
"PE2_TX_DN4":   PN = "DE13"  !CDS_PN = "DE13";
"PE2_TX_DN5":   PN = "DF14"  !CDS_PN = "DF14";
"PE2_TX_DN6":   PN = "DJ13"  !CDS_PN = "DJ13";
"PE2_TX_DN7":   PN = "DK14"  !CDS_PN = "DK14";
"PE2_TX_DN8":   PN = "DN13"  !CDS_PN = "DN13";
"PE2_TX_DN9":   PN = "DP14"  !CDS_PN = "DP14";
"PE2_TX_DN10":   PN = "DU13"  !CDS_PN = "DU13";
"PE2_TX_DN11":   PN = "DV14"  !CDS_PN = "DV14";
"PE2_TX_DN12":   PN = "EA13"  !CDS_PN = "EA13";
"PE2_TX_DN13":   PN = "EB14"  !CDS_PN = "EB14";
"PE2_TX_DN14":   PN = "EE13"  !CDS_PN = "EE13";
"PE2_TX_DN15":   PN = "EF14"  !CDS_PN = "EF14";
"PE2_TX_DP0":   PN = "CT14"  !CDS_PN = "CT14";
"PE2_TX_DP1":   PN = "CW15"  !CDS_PN = "CW15";
"PE2_TX_DP2":   PN = "CY14"  !CDS_PN = "CY14";
"PE2_TX_DP3":   PN = "DC15"  !CDS_PN = "DC15";
"PE2_TX_DP4":   PN = "DD14"  !CDS_PN = "DD14";
"PE2_TX_DP5":   PN = "DG15"  !CDS_PN = "DG15";
"PE2_TX_DP6":   PN = "DH14"  !CDS_PN = "DH14";
"PE2_TX_DP7":   PN = "DL15"  !CDS_PN = "DL15";
"PE2_TX_DP8":   PN = "DM14"  !CDS_PN = "DM14";
"PE2_TX_DP9":   PN = "DR15"  !CDS_PN = "DR15";
"PE2_TX_DP10":   PN = "DT14"  !CDS_PN = "DT14";
"PE2_TX_DP11":   PN = "DW15"  !CDS_PN = "DW15";
"PE2_TX_DP12":   PN = "DY14"  !CDS_PN = "DY14";
"PE2_TX_DP13":   PN = "EC15"  !CDS_PN = "EC15";
"PE2_TX_DP14":   PN = "ED14"  !CDS_PN = "ED14";
"PE2_TX_DP15":   PN = "EG15"  !CDS_PN = "EG15";
BODY = "SOCKET4677_AZIF0045P001C01CS","I140": LOCATION = "U2" #&CDS_LOCATION = "U2" &SEC = "20" #&CDS_SEC = "20";
"PE3_RX_DN0":   PN = "EH89"  !CDS_PN = "EH89";
"PE3_RX_DN1":   PN = "ED91"  !CDS_PN = "ED91";
"PE3_RX_DN2":   PN = "EC90"  !CDS_PN = "EC90";
"PE3_RX_DN3":   PN = "DY91"  !CDS_PN = "DY91";
"PE3_RX_DN4":   PN = "DV89"  !CDS_PN = "DV89";
"PE3_RX_DN5":   PN = "DU90"  !CDS_PN = "DU90";
"PE3_RX_DN6":   PN = "DP89"  !CDS_PN = "DP89";
"PE3_RX_DN7":   PN = "DN90"  !CDS_PN = "DN90";
"PE3_RX_DN8":   PN = "DL90"  !CDS_PN = "DL90";
"PE3_RX_DN9":   PN = "DH91"  !CDS_PN = "DH91";
"PE3_RX_DN10":   PN = "DG90"  !CDS_PN = "DG90";
"PE3_RX_DN11":   PN = "DD91"  !CDS_PN = "DD91";
"PE3_RX_DN12":   PN = "DB89"  !CDS_PN = "DB89";
"PE3_RX_DN13":   PN = "DA90"  !CDS_PN = "DA90";
"PE3_RX_DN14":   PN = "CV89"  !CDS_PN = "CV89";
"PE3_RX_DN15":   PN = "CU90"  !CDS_PN = "CU90";
"PE3_RX_DP0":   PN = "EJ90"  !CDS_PN = "EJ90";
"PE3_RX_DP1":   PN = "EE90"  !CDS_PN = "EE90";
"PE3_RX_DP2":   PN = "EB89"  !CDS_PN = "EB89";
"PE3_RX_DP3":   PN = "EA90"  !CDS_PN = "EA90";
"PE3_RX_DP4":   PN = "DW90"  !CDS_PN = "DW90";
"PE3_RX_DP5":   PN = "DT91"  !CDS_PN = "DT91";
"PE3_RX_DP6":   PN = "DR90"  !CDS_PN = "DR90";
"PE3_RX_DP7":   PN = "DM91"  !CDS_PN = "DM91";
"PE3_RX_DP8":   PN = "DK89"  !CDS_PN = "DK89";
"PE3_RX_DP9":   PN = "DJ90"  !CDS_PN = "DJ90";
"PE3_RX_DP10":   PN = "DF89"  !CDS_PN = "DF89";
"PE3_RX_DP11":   PN = "DE90"  !CDS_PN = "DE90";
"PE3_RX_DP12":   PN = "DC90"  !CDS_PN = "DC90";
"PE3_RX_DP13":   PN = "CY91"  !CDS_PN = "CY91";
"PE3_RX_DP14":   PN = "CW90"  !CDS_PN = "CW90";
"PE3_RX_DP15":   PN = "CT91"  !CDS_PN = "CT91";
"PE3_TX_DN0":   PN = "EE86"  !CDS_PN = "EE86";
"PE3_TX_DN1":   PN = "EB85"  !CDS_PN = "EB85";
"PE3_TX_DN2":   PN = "DY87"  !CDS_PN = "DY87";
"PE3_TX_DN3":   PN = "DV85"  !CDS_PN = "DV85";
"PE3_TX_DN4":   PN = "DT87"  !CDS_PN = "DT87";
"PE3_TX_DN5":   PN = "DP85"  !CDS_PN = "DP85";
"PE3_TX_DN6":   PN = "DM87"  !CDS_PN = "DM87";
"PE3_TX_DN7":   PN = "DK85"  !CDS_PN = "DK85";
"PE3_TX_DN8":   PN = "DH87"  !CDS_PN = "DH87";
"PE3_TX_DN9":   PN = "DF85"  !CDS_PN = "DF85";
"PE3_TX_DN10":   PN = "DD87"  !CDS_PN = "DD87";
"PE3_TX_DN11":   PN = "DB85"  !CDS_PN = "DB85";
"PE3_TX_DN12":   PN = "CY87"  !CDS_PN = "CY87";
"PE3_TX_DN13":   PN = "CV85"  !CDS_PN = "CV85";
"PE3_TX_DN14":   PN = "CT87"  !CDS_PN = "CT87";
"PE3_TX_DN15":   PN = "CP85"  !CDS_PN = "CP85";
"PE3_TX_DP0":   PN = "ED87"  !CDS_PN = "ED87";
"PE3_TX_DP1":   PN = "EC86"  !CDS_PN = "EC86";
"PE3_TX_DP2":   PN = "EA86"  !CDS_PN = "EA86";
"PE3_TX_DP3":   PN = "DW86"  !CDS_PN = "DW86";
"PE3_TX_DP4":   PN = "DU86"  !CDS_PN = "DU86";
"PE3_TX_DP5":   PN = "DR86"  !CDS_PN = "DR86";
"PE3_TX_DP6":   PN = "DN86"  !CDS_PN = "DN86";
"PE3_TX_DP7":   PN = "DL86"  !CDS_PN = "DL86";
"PE3_TX_DP8":   PN = "DJ86"  !CDS_PN = "DJ86";
"PE3_TX_DP9":   PN = "DG86"  !CDS_PN = "DG86";
"PE3_TX_DP10":   PN = "DE86"  !CDS_PN = "DE86";
"PE3_TX_DP11":   PN = "DC86"  !CDS_PN = "DC86";
"PE3_TX_DP12":   PN = "DA86"  !CDS_PN = "DA86";
"PE3_TX_DP13":   PN = "CW86"  !CDS_PN = "CW86";
"PE3_TX_DP14":   PN = "CU86"  !CDS_PN = "CU86";
"PE3_TX_DP15":   PN = "CR86"  !CDS_PN = "CR86";
DRAWING = "@s9s_mb_2u_lib.s9s_mb_2u(sch_1):page31";
BODY = "SOCKET4677_AZIF0045P001C01CS","I139": LOCATION = "U2" #&CDS_LOCATION = "U2" &SEC = "21" #&CDS_SEC = "21";
"PE4_RX_DN0":   PN = "J90"  !CDS_PN = "J90";
"PE4_RX_DN1":   PN = "P89"  !CDS_PN = "P89";
"PE4_RX_DN2":   PN = "T91"  !CDS_PN = "T91";
"PE4_RX_DN3":   PN = "V89"  !CDS_PN = "V89";
"PE4_RX_DN4":   PN = "Y91"  !CDS_PN = "Y91";
"PE4_RX_DN5":   PN = "AB89"  !CDS_PN = "AB89";
"PE4_RX_DN6":   PN = "AD91"  !CDS_PN = "AD91";
"PE4_RX_DN7":   PN = "AF89"  !CDS_PN = "AF89";
"PE4_RX_DN8":   PN = "AH91"  !CDS_PN = "AH91";
"PE4_RX_DN9":   PN = "AK89"  !CDS_PN = "AK89";
"PE4_RX_DN10":   PN = "AM91"  !CDS_PN = "AM91";
"PE4_RX_DN11":   PN = "AP89"  !CDS_PN = "AP89";
"PE4_RX_DN12":   PN = "AT91"  !CDS_PN = "AT91";
"PE4_RX_DN13":   PN = "AV89"  !CDS_PN = "AV89";
"PE4_RX_DN14":   PN = "AY91"  !CDS_PN = "AY91";
"PE4_RX_DN15":   PN = "BB89"  !CDS_PN = "BB89";
"PE4_RX_DP0":   PN = "K89"  !CDS_PN = "K89";
"PE4_RX_DP1":   PN = "N90"  !CDS_PN = "N90";
"PE4_RX_DP2":   PN = "R90"  !CDS_PN = "R90";
"PE4_RX_DP3":   PN = "U90"  !CDS_PN = "U90";
"PE4_RX_DP4":   PN = "W90"  !CDS_PN = "W90";
"PE4_RX_DP5":   PN = "AA90"  !CDS_PN = "AA90";
"PE4_RX_DP6":   PN = "AC90"  !CDS_PN = "AC90";
"PE4_RX_DP7":   PN = "AE90"  !CDS_PN = "AE90";
"PE4_RX_DP8":   PN = "AG90"  !CDS_PN = "AG90";
"PE4_RX_DP9":   PN = "AJ90"  !CDS_PN = "AJ90";
"PE4_RX_DP10":   PN = "AL90"  !CDS_PN = "AL90";
"PE4_RX_DP11":   PN = "AN90"  !CDS_PN = "AN90";
"PE4_RX_DP12":   PN = "AR90"  !CDS_PN = "AR90";
"PE4_RX_DP13":   PN = "AU90"  !CDS_PN = "AU90";
"PE4_RX_DP14":   PN = "AW90"  !CDS_PN = "AW90";
"PE4_RX_DP15":   PN = "BA90"  !CDS_PN = "BA90";
"PE4_TX_DN0":   PN = "L86"  !CDS_PN = "L86";
"PE4_TX_DN1":   PN = "P85"  !CDS_PN = "P85";
"PE4_TX_DN2":   PN = "R86"  !CDS_PN = "R86";
"PE4_TX_DN3":   PN = "U86"  !CDS_PN = "U86";
"PE4_TX_DN4":   PN = "W86"  !CDS_PN = "W86";
"PE4_TX_DN5":   PN = "AA86"  !CDS_PN = "AA86";
"PE4_TX_DN6":   PN = "AC86"  !CDS_PN = "AC86";
"PE4_TX_DN7":   PN = "AE86"  !CDS_PN = "AE86";
"PE4_TX_DN8":   PN = "AG86"  !CDS_PN = "AG86";
"PE4_TX_DN9":   PN = "AJ86"  !CDS_PN = "AJ86";
"PE4_TX_DN10":   PN = "AL86"  !CDS_PN = "AL86";
"PE4_TX_DN11":   PN = "AP85"  !CDS_PN = "AP85";
"PE4_TX_DN12":   PN = "AR86"  !CDS_PN = "AR86";
"PE4_TX_DN13":   PN = "AU86"  !CDS_PN = "AU86";
"PE4_TX_DN14":   PN = "AW86"  !CDS_PN = "AW86";
"PE4_TX_DN15":   PN = "BA86"  !CDS_PN = "BA86";
"PE4_TX_DP0":   PN = "M87"  !CDS_PN = "M87";
"PE4_TX_DP1":   PN = "N86"  !CDS_PN = "N86";
"PE4_TX_DP2":   PN = "T87"  !CDS_PN = "T87";
"PE4_TX_DP3":   PN = "V85"  !CDS_PN = "V85";
"PE4_TX_DP4":   PN = "Y87"  !CDS_PN = "Y87";
"PE4_TX_DP5":   PN = "AB85"  !CDS_PN = "AB85";
"PE4_TX_DP6":   PN = "AD87"  !CDS_PN = "AD87";
"PE4_TX_DP7":   PN = "AF85"  !CDS_PN = "AF85";
"PE4_TX_DP8":   PN = "AH87"  !CDS_PN = "AH87";
"PE4_TX_DP9":   PN = "AK85"  !CDS_PN = "AK85";
"PE4_TX_DP10":   PN = "AM87"  !CDS_PN = "AM87";
"PE4_TX_DP11":   PN = "AN86"  !CDS_PN = "AN86";
"PE4_TX_DP12":   PN = "AT87"  !CDS_PN = "AT87";
"PE4_TX_DP13":   PN = "AV85"  !CDS_PN = "AV85";
"PE4_TX_DP14":   PN = "AY87"  !CDS_PN = "AY87";
"PE4_TX_DP15":   PN = "BB85"  !CDS_PN = "BB85";
DRAWING = "@s9s_mb_2u_lib.s9s_mb_2u(sch_1):page32";
BODY = "SOCKET4677_AZIF0045P001C01CS","I70": LOCATION = "U2" #&CDS_LOCATION = "U2" &SEC = "22" #&CDS_SEC = "22";
"UPI0_RX_DN0":   PN = "K6"  !CDS_PN = "K6";
"UPI0_RX_DN1":   PN = "N5"  !CDS_PN = "N5";
"UPI0_RX_DN2":   PN = "P6"  !CDS_PN = "P6";
"UPI0_RX_DN3":   PN = "U5"  !CDS_PN = "U5";
"UPI0_RX_DN4":   PN = "V6"  !CDS_PN = "V6";
"UPI0_RX_DN5":   PN = "AA5"  !CDS_PN = "AA5";
"UPI0_RX_DN6":   PN = "AB6"  !CDS_PN = "AB6";
"UPI0_RX_DN7":   PN = "AE5"  !CDS_PN = "AE5";
"UPI0_RX_DN8":   PN = "AF6"  !CDS_PN = "AF6";
"UPI0_RX_DN9":   PN = "AH6"  !CDS_PN = "AH6";
"UPI0_RX_DN10":   PN = "AK6"  !CDS_PN = "AK6";
"UPI0_RX_DN11":   PN = "AN5"  !CDS_PN = "AN5";
"UPI0_RX_DN12":   PN = "AP6"  !CDS_PN = "AP6";
"UPI0_RX_DN13":   PN = "AU5"  !CDS_PN = "AU5";
"UPI0_RX_DN14":   PN = "AV6"  !CDS_PN = "AV6";
"UPI0_RX_DN15":   PN = "BA5"  !CDS_PN = "BA5";
"UPI0_RX_DN16":   PN = "BB6"  !CDS_PN = "BB6";
"UPI0_RX_DN17":   PN = "BE5"  !CDS_PN = "BE5";
"UPI0_RX_DN18":   PN = "BF6"  !CDS_PN = "BF6";
"UPI0_RX_DN19":   PN = "BJ5"  !CDS_PN = "BJ5";
"UPI0_RX_DN20":   PN = "BK6"  !CDS_PN = "BK6";
"UPI0_RX_DN21":   PN = "BN5"  !CDS_PN = "BN5";
"UPI0_RX_DN22":   PN = "BR7"  !CDS_PN = "BR7";
"UPI0_RX_DN23":   PN = "BU5"  !CDS_PN = "BU5";
"UPI0_RX_DP0":   PN = "L7"  !CDS_PN = "L7";
"UPI0_RX_DP1":   PN = "M6"  !CDS_PN = "M6";
"UPI0_RX_DP2":   PN = "R7"  !CDS_PN = "R7";
"UPI0_RX_DP3":   PN = "T6"  !CDS_PN = "T6";
"UPI0_RX_DP4":   PN = "W7"  !CDS_PN = "W7";
"UPI0_RX_DP5":   PN = "Y6"  !CDS_PN = "Y6";
"UPI0_RX_DP6":   PN = "AC7"  !CDS_PN = "AC7";
"UPI0_RX_DP7":   PN = "AD6"  !CDS_PN = "AD6";
"UPI0_RX_DP8":   PN = "AG7"  !CDS_PN = "AG7";
"UPI0_RX_DP9":   PN = "AJ5"  !CDS_PN = "AJ5";
"UPI0_RX_DP10":   PN = "AL7"  !CDS_PN = "AL7";
"UPI0_RX_DP11":   PN = "AM6"  !CDS_PN = "AM6";
"UPI0_RX_DP12":   PN = "AR7"  !CDS_PN = "AR7";
"UPI0_RX_DP13":   PN = "AT6"  !CDS_PN = "AT6";
"UPI0_RX_DP14":   PN = "AW7"  !CDS_PN = "AW7";
"UPI0_RX_DP15":   PN = "AY6"  !CDS_PN = "AY6";
"UPI0_RX_DP16":   PN = "BC7"  !CDS_PN = "BC7";
"UPI0_RX_DP17":   PN = "BD6"  !CDS_PN = "BD6";
"UPI0_RX_DP18":   PN = "BG7"  !CDS_PN = "BG7";
"UPI0_RX_DP19":   PN = "BH6"  !CDS_PN = "BH6";
"UPI0_RX_DP20":   PN = "BL7"  !CDS_PN = "BL7";
"UPI0_RX_DP21":   PN = "BM6"  !CDS_PN = "BM6";
"UPI0_RX_DP22":   PN = "BP6"  !CDS_PN = "BP6";
"UPI0_RX_DP23":   PN = "BT6"  !CDS_PN = "BT6";
"UPI0_TX_DN0":   PN = "K4"  !CDS_PN = "K4";
"UPI0_TX_DN1":   PN = "M2"  !CDS_PN = "M2";
"UPI0_TX_DN2":   PN = "N1"  !CDS_PN = "N1";
"UPI0_TX_DN3":   PN = "T2"  !CDS_PN = "T2";
"UPI0_TX_DN4":   PN = "U1"  !CDS_PN = "U1";
"UPI0_TX_DN5":   PN = "Y2"  !CDS_PN = "Y2";
"UPI0_TX_DN6":   PN = "AA1"  !CDS_PN = "AA1";
"UPI0_TX_DN7":   PN = "AD2"  !CDS_PN = "AD2";
"UPI0_TX_DN8":   PN = "AF2"  !CDS_PN = "AF2";
"UPI0_TX_DN9":   PN = "AH2"  !CDS_PN = "AH2";
"UPI0_TX_DN10":   PN = "AK2"  !CDS_PN = "AK2";
"UPI0_TX_DN11":   PN = "AM2"  !CDS_PN = "AM2";
"UPI0_TX_DN12":   PN = "AP2"  !CDS_PN = "AP2";
"UPI0_TX_DN13":   PN = "AT2"  !CDS_PN = "AT2";
"UPI0_TX_DN14":   PN = "AU1"  !CDS_PN = "AU1";
"UPI0_TX_DN15":   PN = "AY2"  !CDS_PN = "AY2";
"UPI0_TX_DN16":   PN = "BB2"  !CDS_PN = "BB2";
"UPI0_TX_DN17":   PN = "BD2"  !CDS_PN = "BD2";
"UPI0_TX_DN18":   PN = "BF2"  !CDS_PN = "BF2";
"UPI0_TX_DN19":   PN = "BH2"  !CDS_PN = "BH2";
"UPI0_TX_DN20":   PN = "BK2"  !CDS_PN = "BK2";
"UPI0_TX_DN21":   PN = "BM2"  !CDS_PN = "BM2";
"UPI0_TX_DN22":   PN = "BR3"  !CDS_PN = "BR3";
"UPI0_TX_DN23":   PN = "BT2"  !CDS_PN = "BT2";
"UPI0_TX_DP0":   PN = "J3"  !CDS_PN = "J3";
"UPI0_TX_DP1":   PN = "L3"  !CDS_PN = "L3";
"UPI0_TX_DP2":   PN = "P2"  !CDS_PN = "P2";
"UPI0_TX_DP3":   PN = "R3"  !CDS_PN = "R3";
"UPI0_TX_DP4":   PN = "V2"  !CDS_PN = "V2";
"UPI0_TX_DP5":   PN = "W3"  !CDS_PN = "W3";
"UPI0_TX_DP6":   PN = "AB2"  !CDS_PN = "AB2";
"UPI0_TX_DP7":   PN = "AC3"  !CDS_PN = "AC3";
"UPI0_TX_DP8":   PN = "AE1"  !CDS_PN = "AE1";
"UPI0_TX_DP9":   PN = "AG3"  !CDS_PN = "AG3";
"UPI0_TX_DP10":   PN = "AJ1"  !CDS_PN = "AJ1";
"UPI0_TX_DP11":   PN = "AL3"  !CDS_PN = "AL3";
"UPI0_TX_DP12":   PN = "AN1"  !CDS_PN = "AN1";
"UPI0_TX_DP13":   PN = "AR3"  !CDS_PN = "AR3";
"UPI0_TX_DP14":   PN = "AV2"  !CDS_PN = "AV2";
"UPI0_TX_DP15":   PN = "AW3"  !CDS_PN = "AW3";
"UPI0_TX_DP16":   PN = "BA1"  !CDS_PN = "BA1";
"UPI0_TX_DP17":   PN = "BC3"  !CDS_PN = "BC3";
"UPI0_TX_DP18":   PN = "BE1"  !CDS_PN = "BE1";
"UPI0_TX_DP19":   PN = "BG3"  !CDS_PN = "BG3";
"UPI0_TX_DP20":   PN = "BJ1"  !CDS_PN = "BJ1";
"UPI0_TX_DP21":   PN = "BL3"  !CDS_PN = "BL3";
"UPI0_TX_DP22":   PN = "BN3"  !CDS_PN = "BN3";
"UPI0_TX_DP23":   PN = "BU3"  !CDS_PN = "BU3";
DRAWING = "@s9s_mb_2u_lib.s9s_mb_2u(sch_1):page33";
BODY = "SOCKET4677_AZIF0045P001C01CS","I102": LOCATION = "U2" #&CDS_LOCATION = "U2" &SEC = "23" #&CDS_SEC = "23";
"UPI1_RX_DN0":   PN = "EH2"  !CDS_PN = "EH2";
"UPI1_RX_DN1":   PN = "EE3"  !CDS_PN = "EE3";
"UPI1_RX_DN2":   PN = "ED2"  !CDS_PN = "ED2";
"UPI1_RX_DN3":   PN = "EA1"  !CDS_PN = "EA1";
"UPI1_RX_DN4":   PN = "DY2"  !CDS_PN = "DY2";
"UPI1_RX_DN5":   PN = "DU1"  !CDS_PN = "DU1";
"UPI1_RX_DN6":   PN = "DT2"  !CDS_PN = "DT2";
"UPI1_RX_DN7":   PN = "DN1"  !CDS_PN = "DN1";
"UPI1_RX_DN8":   PN = "DL3"  !CDS_PN = "DL3";
"UPI1_RX_DN9":   PN = "DJ1"  !CDS_PN = "DJ1";
"UPI1_RX_DN10":   PN = "DG3"  !CDS_PN = "DG3";
"UPI1_RX_DN11":   PN = "DE1"  !CDS_PN = "DE1";
"UPI1_RX_DN12":   PN = "DD2"  !CDS_PN = "DD2";
"UPI1_RX_DN13":   PN = "DB2"  !CDS_PN = "DB2";
"UPI1_RX_DN14":   PN = "CY2"  !CDS_PN = "CY2";
"UPI1_RX_DN15":   PN = "CV2"  !CDS_PN = "CV2";
"UPI1_RX_DN16":   PN = "CR3"  !CDS_PN = "CR3";
"UPI1_RX_DN17":   PN = "CN1"  !CDS_PN = "CN1";
"UPI1_RX_DN18":   PN = "CL3"  !CDS_PN = "CL3";
"UPI1_RX_DN19":   PN = "CJ1"  !CDS_PN = "CJ1";
"UPI1_RX_DN20":   PN = "CH2"  !CDS_PN = "CH2";
"UPI1_RX_DN21":   PN = "CF2"  !CDS_PN = "CF2";
"UPI1_RX_DN22":   PN = "CD2"  !CDS_PN = "CD2";
"UPI1_RX_DN23":   PN = "CB2"  !CDS_PN = "CB2";
"UPI1_RX_DP0":   PN = "EJ3"  !CDS_PN = "EJ3";
"UPI1_RX_DP1":   PN = "EG3"  !CDS_PN = "EG3";
"UPI1_RX_DP2":   PN = "EC3"  !CDS_PN = "EC3";
"UPI1_RX_DP3":   PN = "EB2"  !CDS_PN = "EB2";
"UPI1_RX_DP4":   PN = "DW3"  !CDS_PN = "DW3";
"UPI1_RX_DP5":   PN = "DV2"  !CDS_PN = "DV2";
"UPI1_RX_DP6":   PN = "DR3"  !CDS_PN = "DR3";
"UPI1_RX_DP7":   PN = "DP2"  !CDS_PN = "DP2";
"UPI1_RX_DP8":   PN = "DM2"  !CDS_PN = "DM2";
"UPI1_RX_DP9":   PN = "DK2"  !CDS_PN = "DK2";
"UPI1_RX_DP10":   PN = "DH2"  !CDS_PN = "DH2";
"UPI1_RX_DP11":   PN = "DF2"  !CDS_PN = "DF2";
"UPI1_RX_DP12":   PN = "DC3"  !CDS_PN = "DC3";
"UPI1_RX_DP13":   PN = "DA1"  !CDS_PN = "DA1";
"UPI1_RX_DP14":   PN = "CW3"  !CDS_PN = "CW3";
"UPI1_RX_DP15":   PN = "CU1"  !CDS_PN = "CU1";
"UPI1_RX_DP16":   PN = "CT2"  !CDS_PN = "CT2";
"UPI1_RX_DP17":   PN = "CP2"  !CDS_PN = "CP2";
"UPI1_RX_DP18":   PN = "CM2"  !CDS_PN = "CM2";
"UPI1_RX_DP19":   PN = "CK2"  !CDS_PN = "CK2";
"UPI1_RX_DP20":   PN = "CG3"  !CDS_PN = "CG3";
"UPI1_RX_DP21":   PN = "CE1"  !CDS_PN = "CE1";
"UPI1_RX_DP22":   PN = "CC3"  !CDS_PN = "CC3";
"UPI1_RX_DP23":   PN = "BY2"  !CDS_PN = "BY2";
"UPI1_TX_DN0":   PN = "EF6"  !CDS_PN = "EF6";
"UPI1_TX_DN1":   PN = "EC7"  !CDS_PN = "EC7";
"UPI1_TX_DN2":   PN = "EB6"  !CDS_PN = "EB6";
"UPI1_TX_DN3":   PN = "DY6"  !CDS_PN = "DY6";
"UPI1_TX_DN4":   PN = "DV6"  !CDS_PN = "DV6";
"UPI1_TX_DN5":   PN = "DT6"  !CDS_PN = "DT6";
"UPI1_TX_DN6":   PN = "DP6"  !CDS_PN = "DP6";
"UPI1_TX_DN7":   PN = "DL7"  !CDS_PN = "DL7";
"UPI1_TX_DN8":   PN = "DK6"  !CDS_PN = "DK6";
"UPI1_TX_DN9":   PN = "DH6"  !CDS_PN = "DH6";
"UPI1_TX_DN10":   PN = "DE5"  !CDS_PN = "DE5";
"UPI1_TX_DN11":   PN = "DD6"  !CDS_PN = "DD6";
"UPI1_TX_DN12":   PN = "DA5"  !CDS_PN = "DA5";
"UPI1_TX_DN13":   PN = "CY6"  !CDS_PN = "CY6";
"UPI1_TX_DN14":   PN = "CU5"  !CDS_PN = "CU5";
"UPI1_TX_DN15":   PN = "CT6"  !CDS_PN = "CT6";
"UPI1_TX_DN16":   PN = "CN5"  !CDS_PN = "CN5";
"UPI1_TX_DN17":   PN = "CM6"  !CDS_PN = "CM6";
"UPI1_TX_DN18":   PN = "CJ5"  !CDS_PN = "CJ5";
"UPI1_TX_DN19":   PN = "CH6"  !CDS_PN = "CH6";
"UPI1_TX_DN20":   PN = "CE5"  !CDS_PN = "CE5";
"UPI1_TX_DN21":   PN = "CD6"  !CDS_PN = "CD6";
"UPI1_TX_DN22":   PN = "CA5"  !CDS_PN = "CA5";
"UPI1_TX_DN23":   PN = "BY6"  !CDS_PN = "BY6";
"UPI1_TX_DP0":   PN = "EE5"  !CDS_PN = "EE5";
"UPI1_TX_DP1":   PN = "ED6"  !CDS_PN = "ED6";
"UPI1_TX_DP2":   PN = "EA5"  !CDS_PN = "EA5";
"UPI1_TX_DP3":   PN = "DW7"  !CDS_PN = "DW7";
"UPI1_TX_DP4":   PN = "DU5"  !CDS_PN = "DU5";
"UPI1_TX_DP5":   PN = "DR7"  !CDS_PN = "DR7";
"UPI1_TX_DP6":   PN = "DN5"  !CDS_PN = "DN5";
"UPI1_TX_DP7":   PN = "DM6"  !CDS_PN = "DM6";
"UPI1_TX_DP8":   PN = "DJ5"  !CDS_PN = "DJ5";
"UPI1_TX_DP9":   PN = "DG7"  !CDS_PN = "DG7";
"UPI1_TX_DP10":   PN = "DF6"  !CDS_PN = "DF6";
"UPI1_TX_DP11":   PN = "DC7"  !CDS_PN = "DC7";
"UPI1_TX_DP12":   PN = "DB6"  !CDS_PN = "DB6";
"UPI1_TX_DP13":   PN = "CW7"  !CDS_PN = "CW7";
"UPI1_TX_DP14":   PN = "CV6"  !CDS_PN = "CV6";
"UPI1_TX_DP15":   PN = "CR7"  !CDS_PN = "CR7";
"UPI1_TX_DP16":   PN = "CP6"  !CDS_PN = "CP6";
"UPI1_TX_DP17":   PN = "CL7"  !CDS_PN = "CL7";
"UPI1_TX_DP18":   PN = "CK6"  !CDS_PN = "CK6";
"UPI1_TX_DP19":   PN = "CG7"  !CDS_PN = "CG7";
"UPI1_TX_DP20":   PN = "CF6"  !CDS_PN = "CF6";
"UPI1_TX_DP21":   PN = "CC7"  !CDS_PN = "CC7";
"UPI1_TX_DP22":   PN = "CB6"  !CDS_PN = "CB6";
"UPI1_TX_DP23":   PN = "BW7"  !CDS_PN = "BW7";
DRAWING = "@s9s_mb_2u_lib.s9s_mb_2u(sch_1):page34";
BODY = "SOCKET4677_AZIF0045P001C01CS","I102": LOCATION = "U2" #&CDS_LOCATION = "U2" &SEC = "24" #&CDS_SEC = "24";
"UPI2_RX_DN0":   PN = "E80"  !CDS_PN = "E80";
"UPI2_RX_DN1":   PN = "F81"  !CDS_PN = "F81";
"UPI2_RX_DN2":   PN = "G82"  !CDS_PN = "G82";
"UPI2_RX_DN3":   PN = "K79"  !CDS_PN = "K79";
"UPI2_RX_DN4":   PN = "J82"  !CDS_PN = "J82";
"UPI2_RX_DN5":   PN = "L80"  !CDS_PN = "L80";
"UPI2_RX_DN6":   PN = "AC80"  !CDS_PN = "AC80";
"UPI2_RX_DN7":   PN = "AD81"  !CDS_PN = "AD81";
"UPI2_RX_DN8":   PN = "AF79"  !CDS_PN = "AF79";
"UPI2_RX_DN9":   PN = "AE82"  !CDS_PN = "AE82";
"UPI2_RX_DN10":   PN = "AJ80"  !CDS_PN = "AJ80";
"UPI2_RX_DN11":   PN = "AG82"  !CDS_PN = "AG82";
"UPI2_RX_DN12":   PN = "BA72"  !CDS_PN = "BA72";
"UPI2_RX_DN13":   PN = "AV73"  !CDS_PN = "AV73";
"UPI2_RX_DN14":   PN = "AY75"  !CDS_PN = "AY75";
"UPI2_RX_DN15":   PN = "BB75"  !CDS_PN = "BB75";
"UPI2_RX_DN16":   PN = "AW74"  !CDS_PN = "AW74";
"UPI2_RX_DN17":   PN = "BH75"  !CDS_PN = "BH75";
"UPI2_RX_DN18":   PN = "BJ76"  !CDS_PN = "BJ76";
"UPI2_RX_DN19":   PN = "BL76"  !CDS_PN = "BL76";
"UPI2_RX_DN20":   PN = "BG74"  !CDS_PN = "BG74";
"UPI2_RX_DN21":   PN = "BN74"  !CDS_PN = "BN74";
"UPI2_RX_DN22":   PN = "BK73"  !CDS_PN = "BK73";
"UPI2_RX_DN23":   PN = "BD73"  !CDS_PN = "BD73";
"UPI2_RX_DP0":   PN = "G80"  !CDS_PN = "G80";
"UPI2_RX_DP1":   PN = "E82"  !CDS_PN = "E82";
"UPI2_RX_DP2":   PN = "H83"  !CDS_PN = "H83";
"UPI2_RX_DP3":   PN = "M79"  !CDS_PN = "M79";
"UPI2_RX_DP4":   PN = "L82"  !CDS_PN = "L82";
"UPI2_RX_DP5":   PN = "K81"  !CDS_PN = "K81";
"UPI2_RX_DP6":   PN = "AE80"  !CDS_PN = "AE80";
"UPI2_RX_DP7":   PN = "AC82"  !CDS_PN = "AC82";
"UPI2_RX_DP8":   PN = "AG80"  !CDS_PN = "AG80";
"UPI2_RX_DP9":   PN = "AF83"  !CDS_PN = "AF83";
"UPI2_RX_DP10":   PN = "AH81"  !CDS_PN = "AH81";
"UPI2_RX_DP11":   PN = "AJ82"  !CDS_PN = "AJ82";
"UPI2_RX_DP12":   PN = "BB73"  !CDS_PN = "BB73";
"UPI2_RX_DP13":   PN = "AY73"  !CDS_PN = "AY73";
"UPI2_RX_DP14":   PN = "BA76"  !CDS_PN = "BA76";
"UPI2_RX_DP15":   PN = "BD75"  !CDS_PN = "BD75";
"UPI2_RX_DP16":   PN = "AV75"  !CDS_PN = "AV75";
"UPI2_RX_DP17":   PN = "BG76"  !CDS_PN = "BG76";
"UPI2_RX_DP18":   PN = "BK77"  !CDS_PN = "BK77";
"UPI2_RX_DP19":   PN = "BN76"  !CDS_PN = "BN76";
"UPI2_RX_DP20":   PN = "BJ74"  !CDS_PN = "BJ74";
"UPI2_RX_DP21":   PN = "BM75"  !CDS_PN = "BM75";
"UPI2_RX_DP22":   PN = "BL74"  !CDS_PN = "BL74";
"UPI2_RX_DP23":   PN = "BC74"  !CDS_PN = "BC74";
"UPI2_TX_DN0":   PN = "B85"  !CDS_PN = "B85";
"UPI2_TX_DN1":   PN = "E84"  !CDS_PN = "E84";
"UPI2_TX_DN2":   PN = "D87"  !CDS_PN = "D87";
"UPI2_TX_DN3":   PN = "F87"  !CDS_PN = "F87";
"UPI2_TX_DN4":   PN = "H85"  !CDS_PN = "H85";
"UPI2_TX_DN5":   PN = "P81"  !CDS_PN = "P81";
"UPI2_TX_DN6":   PN = "R82"  !CDS_PN = "R82";
"UPI2_TX_DN7":   PN = "U80"  !CDS_PN = "U80";
"UPI2_TX_DN8":   PN = "V83"  !CDS_PN = "V83";
"UPI2_TX_DN9":   PN = "Y81"  !CDS_PN = "Y81";
"UPI2_TX_DN10":   PN = "AW78"  !CDS_PN = "AW78";
"UPI2_TX_DN11":   PN = "AU78"  !CDS_PN = "AU78";
"UPI2_TX_DN12":   PN = "AM81"  !CDS_PN = "AM81";
"UPI2_TX_DN13":   PN = "AN82"  !CDS_PN = "AN82";
"UPI2_TX_DN14":   PN = "AR80"  !CDS_PN = "AR80";
"UPI2_TX_DN15":   PN = "AT83"  !CDS_PN = "AT83";
"UPI2_TX_DN16":   PN = "AV81"  !CDS_PN = "AV81";
"UPI2_TX_DN17":   PN = "BA80"  !CDS_PN = "BA80";
"UPI2_TX_DN18":   PN = "BC82"  !CDS_PN = "BC82";
"UPI2_TX_DN19":   PN = "BE82"  !CDS_PN = "BE82";
"UPI2_TX_DN20":   PN = "BD79"  !CDS_PN = "BD79";
"UPI2_TX_DN21":   PN = "BF81"  !CDS_PN = "BF81";
"UPI2_TX_DN22":   PN = "BG80"  !CDS_PN = "BG80";
"UPI2_TX_DN23":   PN = "BM71"  !CDS_PN = "BM71";
"UPI2_TX_DP0":   PN = "D85"  !CDS_PN = "D85";
"UPI2_TX_DP1":   PN = "F85"  !CDS_PN = "F85";
"UPI2_TX_DP2":   PN = "E88"  !CDS_PN = "E88";
"UPI2_TX_DP3":   PN = "H87"  !CDS_PN = "H87";
"UPI2_TX_DP4":   PN = "G86"  !CDS_PN = "G86";
"UPI2_TX_DP5":   PN = "T81"  !CDS_PN = "T81";
"UPI2_TX_DP6":   PN = "P83"  !CDS_PN = "P83";
"UPI2_TX_DP7":   PN = "V81"  !CDS_PN = "V81";
"UPI2_TX_DP8":   PN = "Y83"  !CDS_PN = "Y83";
"UPI2_TX_DP9":   PN = "W82"  !CDS_PN = "W82";
"UPI2_TX_DP10":   PN = "BA78"  !CDS_PN = "BA78";
"UPI2_TX_DP11":   PN = "AV79"  !CDS_PN = "AV79";
"UPI2_TX_DP12":   PN = "AP81"  !CDS_PN = "AP81";
"UPI2_TX_DP13":   PN = "AM83"  !CDS_PN = "AM83";
"UPI2_TX_DP14":   PN = "AT81"  !CDS_PN = "AT81";
"UPI2_TX_DP15":   PN = "AV83"  !CDS_PN = "AV83";
"UPI2_TX_DP16":   PN = "AU82"  !CDS_PN = "AU82";
"UPI2_TX_DP17":   PN = "BB81"  !CDS_PN = "BB81";
"UPI2_TX_DP18":   PN = "BA82"  !CDS_PN = "BA82";
"UPI2_TX_DP19":   PN = "BD83"  !CDS_PN = "BD83";
"UPI2_TX_DP20":   PN = "BC80"  !CDS_PN = "BC80";
"UPI2_TX_DP21":   PN = "BG82"  !CDS_PN = "BG82";
"UPI2_TX_DP22":   PN = "BE80"  !CDS_PN = "BE80";
"UPI2_TX_DP23":   PN = "BN72"  !CDS_PN = "BN72";
DRAWING = "@s9s_mb_2u_lib.s9s_mb_2u(sch_1):page35";
BODY = "SOCKET4677_AZIF0045P001C01CS","I102": LOCATION = "U2" #&CDS_LOCATION = "U2" &SEC = "25" #&CDS_SEC = "25";
"UPI3_RX_DN0":   PN = "EJ80"  !CDS_PN = "EJ80";
"UPI3_RX_DN1":   PN = "EP81"  !CDS_PN = "EP81";
"UPI3_RX_DN2":   PN = "EL82"  !CDS_PN = "EL82";
"UPI3_RX_DN3":   PN = "EK81"  !CDS_PN = "EK81";
"UPI3_RX_DN4":   PN = "EF81"  !CDS_PN = "EF81";
"UPI3_RX_DN5":   PN = "ED83"  !CDS_PN = "ED83";
"UPI3_RX_DN6":   PN = "EC80"  !CDS_PN = "EC80";
"UPI3_RX_DN7":   PN = "EA82"  !CDS_PN = "EA82";
"UPI3_RX_DN8":   PN = "DY81"  !CDS_PN = "DY81";
"UPI3_RX_DN9":   PN = "DJ78"  !CDS_PN = "DJ78";
"UPI3_RX_DN10":   PN = "DG78"  !CDS_PN = "DG78";
"UPI3_RX_DN11":   PN = "DH81"  !CDS_PN = "DH81";
"UPI3_RX_DN12":   PN = "DF83"  !CDS_PN = "DF83";
"UPI3_RX_DN13":   PN = "DE80"  !CDS_PN = "DE80";
"UPI3_RX_DN14":   PN = "DC82"  !CDS_PN = "DC82";
"UPI3_RX_DN15":   PN = "DB81"  !CDS_PN = "DB81";
"UPI3_RX_DN16":   PN = "DF77"  !CDS_PN = "DF77";
"UPI3_RX_DN17":   PN = "CU82"  !CDS_PN = "CU82";
"UPI3_RX_DN18":   PN = "CR82"  !CDS_PN = "CR82";
"UPI3_RX_DN19":   PN = "CW80"  !CDS_PN = "CW80";
"UPI3_RX_DN20":   PN = "CP81"  !CDS_PN = "CP81";
"UPI3_RX_DN21":   PN = "CN80"  !CDS_PN = "CN80";
"UPI3_RX_DN22":   PN = "CT79"  !CDS_PN = "CT79";
"UPI3_RX_DN23":   PN = "DA78"  !CDS_PN = "DA78";
"UPI3_RX_DP0":   PN = "EL80"  !CDS_PN = "EL80";
"UPI3_RX_DP1":   PN = "ER82"  !CDS_PN = "ER82";
"UPI3_RX_DP2":   PN = "EN82"  !CDS_PN = "EN82";
"UPI3_RX_DP3":   PN = "EJ82"  !CDS_PN = "EJ82";
"UPI3_RX_DP4":   PN = "EE82"  !CDS_PN = "EE82";
"UPI3_RX_DP5":   PN = "EF83"  !CDS_PN = "EF83";
"UPI3_RX_DP6":   PN = "ED81"  !CDS_PN = "ED81";
"UPI3_RX_DP7":   PN = "DY83"  !CDS_PN = "DY83";
"UPI3_RX_DP8":   PN = "EB81"  !CDS_PN = "EB81";
"UPI3_RX_DP9":   PN = "DL78"  !CDS_PN = "DL78";
"UPI3_RX_DP10":   PN = "DH79"  !CDS_PN = "DH79";
"UPI3_RX_DP11":   PN = "DG82"  !CDS_PN = "DG82";
"UPI3_RX_DP12":   PN = "DH83"  !CDS_PN = "DH83";
"UPI3_RX_DP13":   PN = "DF81"  !CDS_PN = "DF81";
"UPI3_RX_DP14":   PN = "DB83"  !CDS_PN = "DB83";
"UPI3_RX_DP15":   PN = "DD81"  !CDS_PN = "DD81";
"UPI3_RX_DP16":   PN = "DE78"  !CDS_PN = "DE78";
"UPI3_RX_DP17":   PN = "CW82"  !CDS_PN = "CW82";
"UPI3_RX_DP18":   PN = "CT83"  !CDS_PN = "CT83";
"UPI3_RX_DP19":   PN = "CV81"  !CDS_PN = "CV81";
"UPI3_RX_DP20":   PN = "CN82"  !CDS_PN = "CN82";
"UPI3_RX_DP21":   PN = "CR80"  !CDS_PN = "CR80";
"UPI3_RX_DP22":   PN = "CU80"  !CDS_PN = "CU80";
"UPI3_RX_DP23":   PN = "DB79"  !CDS_PN = "DB79";
"UPI3_TX_DN0":   PN = "EH85"  !CDS_PN = "EH85";
"UPI3_TX_DN1":   PN = "EL84"  !CDS_PN = "EL84";
"UPI3_TX_DN2":   PN = "EP85"  !CDS_PN = "EP85";
"UPI3_TX_DN3":   PN = "EM87"  !CDS_PN = "EM87";
"UPI3_TX_DN4":   PN = "EJ86"  !CDS_PN = "EJ86";
"UPI3_TX_DN5":   PN = "EK87"  !CDS_PN = "EK87";
"UPI3_TX_DN6":   PN = "DU80"  !CDS_PN = "DU80";
"UPI3_TX_DN7":   PN = "DR82"  !CDS_PN = "DR82";
"UPI3_TX_DN8":   PN = "DP79"  !CDS_PN = "DP79";
"UPI3_TX_DN9":   PN = "DN82"  !CDS_PN = "DN82";
"UPI3_TX_DN10":   PN = "DM81"  !CDS_PN = "DM81";
"UPI3_TX_DN11":   PN = "DL80"  !CDS_PN = "DL80";
"UPI3_TX_DN12":   PN = "CW76"  !CDS_PN = "CW76";
"UPI3_TX_DN13":   PN = "CU76"  !CDS_PN = "CU76";
"UPI3_TX_DN14":   PN = "CT75"  !CDS_PN = "CT75";
"UPI3_TX_DN15":   PN = "CR74"  !CDS_PN = "CR74";
"UPI3_TX_DN16":   PN = "CK77"  !CDS_PN = "CK77";
"UPI3_TX_DN17":   PN = "CH77"  !CDS_PN = "CH77";
"UPI3_TX_DN18":   PN = "CM75"  !CDS_PN = "CM75";
"UPI3_TX_DN19":   PN = "CG76"  !CDS_PN = "CG76";
"UPI3_TX_DN20":   PN = "CF75"  !CDS_PN = "CF75";
"UPI3_TX_DN21":   PN = "CJ74"  !CDS_PN = "CJ74";
"UPI3_TX_DN22":   PN = "CV73"  !CDS_PN = "CV73";
"UPI3_TX_DN23":   PN = "CF73"  !CDS_PN = "CF73";
"UPI3_TX_DP0":   PN = "EK85"  !CDS_PN = "EK85";
"UPI3_TX_DP1":   PN = "EM85"  !CDS_PN = "EM85";
"UPI3_TX_DP2":   PN = "EN86"  !CDS_PN = "EN86";
"UPI3_TX_DP3":   PN = "EP87"  !CDS_PN = "EP87";
"UPI3_TX_DP4":   PN = "EH87"  !CDS_PN = "EH87";
"UPI3_TX_DP5":   PN = "EL88"  !CDS_PN = "EL88";
"UPI3_TX_DP6":   PN = "DT81"  !CDS_PN = "DT81";
"UPI3_TX_DP7":   PN = "DU82"  !CDS_PN = "DU82";
"UPI3_TX_DP8":   PN = "DR80"  !CDS_PN = "DR80";
"UPI3_TX_DP9":   PN = "DP83"  !CDS_PN = "DP83";
"UPI3_TX_DP10":   PN = "DL82"  !CDS_PN = "DL82";
"UPI3_TX_DP11":   PN = "DN80"  !CDS_PN = "DN80";
"UPI3_TX_DP12":   PN = "DA76"  !CDS_PN = "DA76";
"UPI3_TX_DP13":   PN = "CV77"  !CDS_PN = "CV77";
"UPI3_TX_DP14":   PN = "CR76"  !CDS_PN = "CR76";
"UPI3_TX_DP15":   PN = "CU74"  !CDS_PN = "CU74";
"UPI3_TX_DP16":   PN = "CM77"  !CDS_PN = "CM77";
"UPI3_TX_DP17":   PN = "CJ78"  !CDS_PN = "CJ78";
"UPI3_TX_DP18":   PN = "CL76"  !CDS_PN = "CL76";
"UPI3_TX_DP19":   PN = "CF77"  !CDS_PN = "CF77";
"UPI3_TX_DP20":   PN = "CH75"  !CDS_PN = "CH75";
"UPI3_TX_DP21":   PN = "CK75"  !CDS_PN = "CK75";
"UPI3_TX_DP22":   PN = "CW74"  !CDS_PN = "CW74";
"UPI3_TX_DP23":   PN = "CD73"  !CDS_PN = "CD73";
DRAWING = "@s9s_mb_2u_lib.s9s_mb_2u(sch_1):page36";
BODY = "SOCKET4677_AZIF0045P001C01CS","I1": LOCATION = "U2" #&CDS_LOCATION = "U2" &SEC = "26" #&CDS_SEC = "26";
"VCCIN190":   PN = "BW80"  !CDS_PN = "BW80";
"VCCIN191":   PN = "BW82"  !CDS_PN = "BW82";
"VCCIN192":   PN = "BW84"  !CDS_PN = "BW84";
"VCCIN193":   PN = "BW86"  !CDS_PN = "BW86";
"VCCIN194":   PN = "BW88"  !CDS_PN = "BW88";
"VCCIN195":   PN = "BW90"  !CDS_PN = "BW90";
"VCCIN196":   PN = "BY32"  !CDS_PN = "BY32";
"VCCIN197":   PN = "BY34"  !CDS_PN = "BY34";
"VCCIN198":   PN = "BY36"  !CDS_PN = "BY36";
"VCCIN199":   PN = "BY38"  !CDS_PN = "BY38";
"VCCIN200":   PN = "BY40"  !CDS_PN = "BY40";
"VCCIN201":   PN = "BY42"  !CDS_PN = "BY42";
"VCCIN202":   PN = "BY44"  !CDS_PN = "BY44";
"VCCIN203":   PN = "BY47"  !CDS_PN = "BY47";
"VCCIN204":   PN = "BY49"  !CDS_PN = "BY49";
"VCCIN205":   PN = "BY51"  !CDS_PN = "BY51";
"VCCIN206":   PN = "BY53"  !CDS_PN = "BY53";
"VCCIN207":   PN = "BY55"  !CDS_PN = "BY55";
"VCCIN208":   PN = "BY57"  !CDS_PN = "BY57";
"VCCIN209":   PN = "BY59"  !CDS_PN = "BY59";
"VCCIN210":   PN = "BY61"  !CDS_PN = "BY61";
"VCCIN211":   PN = "BY63"  !CDS_PN = "BY63";
"VCCIN212":   PN = "BY65"  !CDS_PN = "BY65";
"VCCIN213":   PN = "BY67"  !CDS_PN = "BY67";
"VCCIN214":   PN = "BY69"  !CDS_PN = "BY69";
"VCCIN215":   PN = "BY71"  !CDS_PN = "BY71";
"VCCIN216":   PN = "BY73"  !CDS_PN = "BY73";
"VCCIN217":   PN = "BY75"  !CDS_PN = "BY75";
"VCCIN218":   PN = "BY77"  !CDS_PN = "BY77";
"VCCIN219":   PN = "BY79"  !CDS_PN = "BY79";
"VCCIN220":   PN = "BY81"  !CDS_PN = "BY81";
"VCCIN221":   PN = "BY83"  !CDS_PN = "BY83";
"VCCIN222":   PN = "BY85"  !CDS_PN = "BY85";
"VCCIN223":   PN = "BY87"  !CDS_PN = "BY87";
"VCCIN224":   PN = "BY89"  !CDS_PN = "BY89";
"VCCIN225":   PN = "CA33"  !CDS_PN = "CA33";
"VCCIN226":   PN = "CA35"  !CDS_PN = "CA35";
"VCCIN227":   PN = "CA37"  !CDS_PN = "CA37";
"VCCIN228":   PN = "CA39"  !CDS_PN = "CA39";
"VCCIN229":   PN = "CA41"  !CDS_PN = "CA41";
"VCCIN230":   PN = "CA43"  !CDS_PN = "CA43";
"VCCIN231":   PN = "CA45"  !CDS_PN = "CA45";
"VCCIN232":   PN = "CA48"  !CDS_PN = "CA48";
"VCCIN233":   PN = "CA50"  !CDS_PN = "CA50";
"VCCIN234":   PN = "CA52"  !CDS_PN = "CA52";
"VCCIN235":   PN = "CA54"  !CDS_PN = "CA54";
"VCCIN236":   PN = "CA56"  !CDS_PN = "CA56";
"VCCIN237":   PN = "CA58"  !CDS_PN = "CA58";
"VCCIN238":   PN = "CA60"  !CDS_PN = "CA60";
"VCCIN239":   PN = "CA62"  !CDS_PN = "CA62";
"VCCIN240":   PN = "CA64"  !CDS_PN = "CA64";
"VCCIN241":   PN = "CA66"  !CDS_PN = "CA66";
"VCCIN242":   PN = "CA68"  !CDS_PN = "CA68";
"VCCIN243":   PN = "CA70"  !CDS_PN = "CA70";
"VCCIN244":   PN = "CA72"  !CDS_PN = "CA72";
"VCCIN245":   PN = "CA74"  !CDS_PN = "CA74";
"VCCIN246":   PN = "CA76"  !CDS_PN = "CA76";
"VCCIN247":   PN = "CA78"  !CDS_PN = "CA78";
"VCCIN248":   PN = "CA80"  !CDS_PN = "CA80";
"VCCIN249":   PN = "CA82"  !CDS_PN = "CA82";
"VCCIN250":   PN = "CA84"  !CDS_PN = "CA84";
"VCCIN251":   PN = "CA86"  !CDS_PN = "CA86";
"VCCIN252":   PN = "CA88"  !CDS_PN = "CA88";
"VCCIN253":   PN = "CA90"  !CDS_PN = "CA90";
"VCCIN254":   PN = "CB61"  !CDS_PN = "CB61";
"VCCIN255":   PN = "CB75"  !CDS_PN = "CB75";
"VCCIN256":   PN = "CB77"  !CDS_PN = "CB77";
"VCCIN257":   PN = "CC33"  !CDS_PN = "CC33";
"VCCIN258":   PN = "CC35"  !CDS_PN = "CC35";
"VCCIN259":   PN = "CC37"  !CDS_PN = "CC37";
"VCCIN260":   PN = "CC39"  !CDS_PN = "CC39";
"VCCIN261":   PN = "CC41"  !CDS_PN = "CC41";
"VCCIN262":   PN = "CC43"  !CDS_PN = "CC43";
"VCCIN263":   PN = "CC45"  !CDS_PN = "CC45";
"VCCIN264":   PN = "CC48"  !CDS_PN = "CC48";
"VCCIN265":   PN = "CC50"  !CDS_PN = "CC50";
"VCCIN266":   PN = "CC52"  !CDS_PN = "CC52";
"VCCIN267":   PN = "CC54"  !CDS_PN = "CC54";
"VCCIN268":   PN = "CC56"  !CDS_PN = "CC56";
"VCCIN269":   PN = "CC58"  !CDS_PN = "CC58";
"VCCIN270":   PN = "CC60"  !CDS_PN = "CC60";
"VCCIN271":   PN = "CC76"  !CDS_PN = "CC76";
"VCCIN272":   PN = "CC78"  !CDS_PN = "CC78";
"VCCIN273":   PN = "CC80"  !CDS_PN = "CC80";
"VCCIN274":   PN = "CC82"  !CDS_PN = "CC82";
"VCCIN275":   PN = "CC84"  !CDS_PN = "CC84";
"VCCIN276":   PN = "CC86"  !CDS_PN = "CC86";
"VCCIN277":   PN = "CC88"  !CDS_PN = "CC88";
"VCCIN278":   PN = "CC90"  !CDS_PN = "CC90";
"VCCIN279":   PN = "CD32"  !CDS_PN = "CD32";
"VCCIN280":   PN = "CD34"  !CDS_PN = "CD34";
"VCCIN281":   PN = "CD36"  !CDS_PN = "CD36";
"VCCIN282":   PN = "CD38"  !CDS_PN = "CD38";
"VCCIN283":   PN = "CD40"  !CDS_PN = "CD40";
"VCCIN284":   PN = "CD42"  !CDS_PN = "CD42";
"VCCIN285":   PN = "CD44"  !CDS_PN = "CD44";
"VCCIN286":   PN = "CD47"  !CDS_PN = "CD47";
"VCCIN287":   PN = "CD49"  !CDS_PN = "CD49";
"VCCIN288":   PN = "CD51"  !CDS_PN = "CD51";
"VCCIN289":   PN = "CD53"  !CDS_PN = "CD53";
"VCCIN290":   PN = "CD55"  !CDS_PN = "CD55";
"VCCIN291":   PN = "CD57"  !CDS_PN = "CD57";
"VCCIN292":   PN = "CD59"  !CDS_PN = "CD59";
"VCCIN293":   PN = "CD79"  !CDS_PN = "CD79";
"VCCIN294":   PN = "CD81"  !CDS_PN = "CD81";
"VCCIN295":   PN = "CD83"  !CDS_PN = "CD83";
"VCCIN296":   PN = "CD85"  !CDS_PN = "CD85";
"VCCIN297":   PN = "CD87"  !CDS_PN = "CD87";
"VCCIN298":   PN = "CD89"  !CDS_PN = "CD89";
"VCCIN299":   PN = "CE80"  !CDS_PN = "CE80";
"VCCIN300":   PN = "CE82"  !CDS_PN = "CE82";
"VCCIN301":   PN = "CE84"  !CDS_PN = "CE84";
"VCCIN302":   PN = "CE86"  !CDS_PN = "CE86";
"VCCIN303":   PN = "CE88"  !CDS_PN = "CE88";
"VCCIN304":   PN = "CE90"  !CDS_PN = "CE90";
"VCCIN305":   PN = "CF79"  !CDS_PN = "CF79";
"VCCIN306":   PN = "CF81"  !CDS_PN = "CF81";
"VCCIN307":   PN = "CF83"  !CDS_PN = "CF83";
"VCCIN308":   PN = "CF85"  !CDS_PN = "CF85";
"VCCIN309":   PN = "CF87"  !CDS_PN = "CF87";
"VCCIN310":   PN = "CF89"  !CDS_PN = "CF89";
"VCCIN311":   PN = "CF91"  !CDS_PN = "CF91";
"VCCIN312":   PN = "CG80"  !CDS_PN = "CG80";
"VCCIN313":   PN = "CG82"  !CDS_PN = "CG82";
"VCCIN314":   PN = "CG84"  !CDS_PN = "CG84";
"VCCIN315":   PN = "CG86"  !CDS_PN = "CG86";
"VCCIN316":   PN = "CG88"  !CDS_PN = "CG88";
"VCCIN317":   PN = "CG90"  !CDS_PN = "CG90";
"VCCIN318":   PN = "CH81"  !CDS_PN = "CH81";
"VCCIN319":   PN = "CH91"  !CDS_PN = "CH91";
"VCCIN320":   PN = "CJ82"  !CDS_PN = "CJ82";
"VCCIN321":   PN = "CJ84"  !CDS_PN = "CJ84";
"VCCIN322":   PN = "CJ86"  !CDS_PN = "CJ86";
"VCCIN323":   PN = "CJ88"  !CDS_PN = "CJ88";
"VCCIN324":   PN = "CJ90"  !CDS_PN = "CJ90";
"VCCIN325":   PN = "CK83"  !CDS_PN = "CK83";
"VCCIN326":   PN = "CK85"  !CDS_PN = "CK85";
"VCCIN327":   PN = "CK87"  !CDS_PN = "CK87";
"VCCIN328":   PN = "CK89"  !CDS_PN = "CK89";
"VCCIN329":   PN = "CK91"  !CDS_PN = "CK91";
"VCCIN330":   PN = "CL84"  !CDS_PN = "CL84";
"VCCIN331":   PN = "CL86"  !CDS_PN = "CL86";
"VCCIN332":   PN = "CL88"  !CDS_PN = "CL88";
"VCCIN333":   PN = "CL90"  !CDS_PN = "CL90";
"VCCIN334":   PN = "CM87"  !CDS_PN = "CM87";
"VCCIN335":   PN = "CM91"  !CDS_PN = "CM91";
"VCCIN336":   PN = "CN88"  !CDS_PN = "CN88";
"VCCIN337":   PN = "CN90"  !CDS_PN = "CN90";
"VCCIN338":   PN = "CP89"  !CDS_PN = "CP89";
"VCCIN339":   PN = "CM89"  !CDS_PN = "CM89";
BODY = "SOCKET4677_AZIF0045P001C01CS","I7": LOCATION = "U2" #&CDS_LOCATION = "U2" &SEC = "27" #&CDS_SEC = "27";
"VCCIN40":   PN = "BN43"  !CDS_PN = "BN43";
"VCCIN41":   PN = "BN45"  !CDS_PN = "BN45";
"VCCIN42":   PN = "BN48"  !CDS_PN = "BN48";
"VCCIN43":   PN = "BN50"  !CDS_PN = "BN50";
"VCCIN44":   PN = "BN52"  !CDS_PN = "BN52";
"VCCIN45":   PN = "BN54"  !CDS_PN = "BN54";
"VCCIN46":   PN = "BN56"  !CDS_PN = "BN56";
"VCCIN47":   PN = "BN58"  !CDS_PN = "BN58";
"VCCIN48":   PN = "BN60"  !CDS_PN = "BN60";
"VCCIN49":   PN = "BN78"  !CDS_PN = "BN78";
"VCCIN50":   PN = "BN80"  !CDS_PN = "BN80";
"VCCIN51":   PN = "BN82"  !CDS_PN = "BN82";
"VCCIN52":   PN = "BN84"  !CDS_PN = "BN84";
"VCCIN53":   PN = "BN86"  !CDS_PN = "BN86";
"VCCIN54":   PN = "BN88"  !CDS_PN = "BN88";
"VCCIN55":   PN = "BN90"  !CDS_PN = "BN90";
"VCCIN56":   PN = "BP32"  !CDS_PN = "BP32";
"VCCIN57":   PN = "BP34"  !CDS_PN = "BP34";
"VCCIN58":   PN = "BP36"  !CDS_PN = "BP36";
"VCCIN59":   PN = "BP38"  !CDS_PN = "BP38";
"VCCIN60":   PN = "BP40"  !CDS_PN = "BP40";
"VCCIN61":   PN = "BP42"  !CDS_PN = "BP42";
"VCCIN62":   PN = "BP44"  !CDS_PN = "BP44";
"VCCIN63":   PN = "BP47"  !CDS_PN = "BP47";
"VCCIN64":   PN = "BP49"  !CDS_PN = "BP49";
"VCCIN65":   PN = "BP51"  !CDS_PN = "BP51";
"VCCIN66":   PN = "BP53"  !CDS_PN = "BP53";
"VCCIN67":   PN = "BP55"  !CDS_PN = "BP55";
"VCCIN68":   PN = "BP57"  !CDS_PN = "BP57";
"VCCIN69":   PN = "BP59"  !CDS_PN = "BP59";
"VCCIN70":   PN = "BP61"  !CDS_PN = "BP61";
"VCCIN71":   PN = "BP79"  !CDS_PN = "BP79";
"VCCIN72":   PN = "BP81"  !CDS_PN = "BP81";
"VCCIN73":   PN = "BP83"  !CDS_PN = "BP83";
"VCCIN74":   PN = "BP85"  !CDS_PN = "BP85";
"VCCIN75":   PN = "BP87"  !CDS_PN = "BP87";
"VCCIN76":   PN = "BP89"  !CDS_PN = "BP89";
"VCCIN77":   PN = "BR60"  !CDS_PN = "BR60";
"VCCIN78":   PN = "BR62"  !CDS_PN = "BR62";
"VCCIN79":   PN = "BR78"  !CDS_PN = "BR78";
"VCCIN80":   PN = "BT32"  !CDS_PN = "BT32";
"VCCIN81":   PN = "BT34"  !CDS_PN = "BT34";
"VCCIN82":   PN = "BT36"  !CDS_PN = "BT36";
"VCCIN83":   PN = "BT38"  !CDS_PN = "BT38";
"VCCIN84":   PN = "BT40"  !CDS_PN = "BT40";
"VCCIN85":   PN = "BT42"  !CDS_PN = "BT42";
"VCCIN86":   PN = "BT44"  !CDS_PN = "BT44";
"VCCIN87":   PN = "BT47"  !CDS_PN = "BT47";
"VCCIN88":   PN = "BT49"  !CDS_PN = "BT49";
"VCCIN89":   PN = "BT51"  !CDS_PN = "BT51";
"VCCIN90":   PN = "BT53"  !CDS_PN = "BT53";
"VCCIN91":   PN = "BT55"  !CDS_PN = "BT55";
"VCCIN92":   PN = "BT57"  !CDS_PN = "BT57";
"VCCIN93":   PN = "BT59"  !CDS_PN = "BT59";
"VCCIN94":   PN = "BT61"  !CDS_PN = "BT61";
"VCCIN95":   PN = "BT63"  !CDS_PN = "BT63";
"VCCIN96":   PN = "BT65"  !CDS_PN = "BT65";
"VCCIN97":   PN = "BT67"  !CDS_PN = "BT67";
"VCCIN98":   PN = "BT69"  !CDS_PN = "BT69";
"VCCIN99":   PN = "BT71"  !CDS_PN = "BT71";
"VCCIN100":   PN = "BT73"  !CDS_PN = "BT73";
"VCCIN101":   PN = "BT75"  !CDS_PN = "BT75";
"VCCIN102":   PN = "BT77"  !CDS_PN = "BT77";
"VCCIN103":   PN = "BT79"  !CDS_PN = "BT79";
"VCCIN104":   PN = "BT81"  !CDS_PN = "BT81";
"VCCIN105":   PN = "BT83"  !CDS_PN = "BT83";
"VCCIN106":   PN = "BT85"  !CDS_PN = "BT85";
"VCCIN107":   PN = "BT87"  !CDS_PN = "BT87";
"VCCIN108":   PN = "BT89"  !CDS_PN = "BT89";
"VCCIN109":   PN = "BU33"  !CDS_PN = "BU33";
"VCCIN110":   PN = "BU35"  !CDS_PN = "BU35";
"VCCIN111":   PN = "BU37"  !CDS_PN = "BU37";
"VCCIN112":   PN = "BU39"  !CDS_PN = "BU39";
"VCCIN113":   PN = "BU41"  !CDS_PN = "BU41";
"VCCIN114":   PN = "BU43"  !CDS_PN = "BU43";
"VCCIN115":   PN = "BU45"  !CDS_PN = "BU45";
"VCCIN116":   PN = "BU48"  !CDS_PN = "BU48";
"VCCIN117":   PN = "BU50"  !CDS_PN = "BU50";
"VCCIN118":   PN = "BU52"  !CDS_PN = "BU52";
"VCCIN119":   PN = "BU54"  !CDS_PN = "BU54";
"VCCIN120":   PN = "BU56"  !CDS_PN = "BU56";
"VCCIN121":   PN = "BU58"  !CDS_PN = "BU58";
"VCCIN122":   PN = "BU60"  !CDS_PN = "BU60";
"VCCIN123":   PN = "BU62"  !CDS_PN = "BU62";
"VCCIN124":   PN = "BU64"  !CDS_PN = "BU64";
"VCCIN125":   PN = "BU66"  !CDS_PN = "BU66";
"VCCIN126":   PN = "BU68"  !CDS_PN = "BU68";
"VCCIN127":   PN = "BU70"  !CDS_PN = "BU70";
"VCCIN128":   PN = "BU72"  !CDS_PN = "BU72";
"VCCIN129":   PN = "BU74"  !CDS_PN = "BU74";
"VCCIN130":   PN = "BU76"  !CDS_PN = "BU76";
"VCCIN131":   PN = "BU78"  !CDS_PN = "BU78";
"VCCIN132":   PN = "BU80"  !CDS_PN = "BU80";
"VCCIN133":   PN = "BU82"  !CDS_PN = "BU82";
"VCCIN134":   PN = "BU84"  !CDS_PN = "BU84";
"VCCIN135":   PN = "BU86"  !CDS_PN = "BU86";
"VCCIN136":   PN = "BU88"  !CDS_PN = "BU88";
"VCCIN137":   PN = "BU90"  !CDS_PN = "BU90";
"VCCIN138":   PN = "BV32"  !CDS_PN = "BV32";
"VCCIN139":   PN = "BV34"  !CDS_PN = "BV34";
"VCCIN140":   PN = "BV36"  !CDS_PN = "BV36";
"VCCIN141":   PN = "BV38"  !CDS_PN = "BV38";
"VCCIN142":   PN = "BV40"  !CDS_PN = "BV40";
"VCCIN143":   PN = "BV42"  !CDS_PN = "BV42";
"VCCIN144":   PN = "BV44"  !CDS_PN = "BV44";
"VCCIN145":   PN = "BV47"  !CDS_PN = "BV47";
"VCCIN146":   PN = "BV49"  !CDS_PN = "BV49";
"VCCIN147":   PN = "BV51"  !CDS_PN = "BV51";
"VCCIN148":   PN = "BV53"  !CDS_PN = "BV53";
"VCCIN149":   PN = "BV55"  !CDS_PN = "BV55";
"VCCIN150":   PN = "BV57"  !CDS_PN = "BV57";
"VCCIN151":   PN = "BV59"  !CDS_PN = "BV59";
"VCCIN152":   PN = "BV61"  !CDS_PN = "BV61";
"VCCIN153":   PN = "BV63"  !CDS_PN = "BV63";
"VCCIN154":   PN = "BV65"  !CDS_PN = "BV65";
"VCCIN155":   PN = "BV67"  !CDS_PN = "BV67";
"VCCIN156":   PN = "BV69"  !CDS_PN = "BV69";
"VCCIN157":   PN = "BV71"  !CDS_PN = "BV71";
"VCCIN158":   PN = "BV73"  !CDS_PN = "BV73";
"VCCIN159":   PN = "BV75"  !CDS_PN = "BV75";
"VCCIN160":   PN = "BV77"  !CDS_PN = "BV77";
"VCCIN161":   PN = "BV79"  !CDS_PN = "BV79";
"VCCIN162":   PN = "BV81"  !CDS_PN = "BV81";
"VCCIN163":   PN = "BV83"  !CDS_PN = "BV83";
"VCCIN164":   PN = "BV85"  !CDS_PN = "BV85";
"VCCIN165":   PN = "BV87"  !CDS_PN = "BV87";
"VCCIN166":   PN = "BV89"  !CDS_PN = "BV89";
"VCCIN167":   PN = "BW33"  !CDS_PN = "BW33";
"VCCIN168":   PN = "BW35"  !CDS_PN = "BW35";
"VCCIN169":   PN = "BW37"  !CDS_PN = "BW37";
"VCCIN170":   PN = "BW39"  !CDS_PN = "BW39";
"VCCIN171":   PN = "BW41"  !CDS_PN = "BW41";
"VCCIN172":   PN = "BW43"  !CDS_PN = "BW43";
"VCCIN173":   PN = "BW45"  !CDS_PN = "BW45";
"VCCIN174":   PN = "BW48"  !CDS_PN = "BW48";
"VCCIN175":   PN = "BW50"  !CDS_PN = "BW50";
"VCCIN176":   PN = "BW52"  !CDS_PN = "BW52";
"VCCIN177":   PN = "BW54"  !CDS_PN = "BW54";
"VCCIN178":   PN = "BW56"  !CDS_PN = "BW56";
"VCCIN179":   PN = "BW58"  !CDS_PN = "BW58";
"VCCIN180":   PN = "BW60"  !CDS_PN = "BW60";
"VCCIN181":   PN = "BW62"  !CDS_PN = "BW62";
"VCCIN182":   PN = "BW64"  !CDS_PN = "BW64";
"VCCIN183":   PN = "BW66"  !CDS_PN = "BW66";
"VCCIN184":   PN = "BW68"  !CDS_PN = "BW68";
"VCCIN185":   PN = "BW70"  !CDS_PN = "BW70";
"VCCIN186":   PN = "BW72"  !CDS_PN = "BW72";
"VCCIN187":   PN = "BW74"  !CDS_PN = "BW74";
"VCCIN188":   PN = "BW76"  !CDS_PN = "BW76";
"VCCIN189":   PN = "BW78"  !CDS_PN = "BW78";
DRAWING = "@s9s_mb_2u_lib.s9s_mb_2u(sch_1):page37";
BODY = "SOCKET4677_AZIF0045P001C01CS","I7": LOCATION = "U2" #&CDS_LOCATION = "U2" &SEC = "28" #&CDS_SEC = "28";
"VCCIN0":   PN = "BD91"  !CDS_PN = "BD91";
"VCCIN1":   PN = "BE86"  !CDS_PN = "BE86";
"VCCIN2":   PN = "BE88"  !CDS_PN = "BE88";
"VCCIN3":   PN = "BE90"  !CDS_PN = "BE90";
"VCCIN4":   PN = "BF85"  !CDS_PN = "BF85";
"VCCIN5":   PN = "BF87"  !CDS_PN = "BF87";
"VCCIN6":   PN = "BF89"  !CDS_PN = "BF89";
"VCCIN7":   PN = "BF91"  !CDS_PN = "BF91";
"VCCIN8":   PN = "BG84"  !CDS_PN = "BG84";
"VCCIN9":   PN = "BG86"  !CDS_PN = "BG86";
"VCCIN10":   PN = "BG88"  !CDS_PN = "BG88";
"VCCIN11":   PN = "BG90"  !CDS_PN = "BG90";
"VCCIN12":   PN = "BH85"  !CDS_PN = "BH85";
"VCCIN13":   PN = "BH87"  !CDS_PN = "BH87";
"VCCIN14":   PN = "BH89"  !CDS_PN = "BH89";
"VCCIN15":   PN = "BH91"  !CDS_PN = "BH91";
"VCCIN16":   PN = "BK81"  !CDS_PN = "BK81";
"VCCIN17":   PN = "BK83"  !CDS_PN = "BK83";
"VCCIN18":   PN = "BK85"  !CDS_PN = "BK85";
"VCCIN19":   PN = "BK87"  !CDS_PN = "BK87";
"VCCIN20":   PN = "BK89"  !CDS_PN = "BK89";
"VCCIN21":   PN = "BK91"  !CDS_PN = "BK91";
"VCCIN22":   PN = "BL80"  !CDS_PN = "BL80";
"VCCIN23":   PN = "BL82"  !CDS_PN = "BL82";
"VCCIN24":   PN = "BL84"  !CDS_PN = "BL84";
"VCCIN25":   PN = "BL86"  !CDS_PN = "BL86";
"VCCIN26":   PN = "BL88"  !CDS_PN = "BL88";
"VCCIN27":   PN = "BL90"  !CDS_PN = "BL90";
"VCCIN28":   PN = "BM79"  !CDS_PN = "BM79";
"VCCIN29":   PN = "BM81"  !CDS_PN = "BM81";
"VCCIN30":   PN = "BM83"  !CDS_PN = "BM83";
"VCCIN31":   PN = "BM85"  !CDS_PN = "BM85";
"VCCIN32":   PN = "BM87"  !CDS_PN = "BM87";
"VCCIN33":   PN = "BM89"  !CDS_PN = "BM89";
"VCCIN34":   PN = "BM91"  !CDS_PN = "BM91";
"VCCIN35":   PN = "BN33"  !CDS_PN = "BN33";
"VCCIN36":   PN = "BN35"  !CDS_PN = "BN35";
"VCCIN37":   PN = "BN37"  !CDS_PN = "BN37";
"VCCIN38":   PN = "BN39"  !CDS_PN = "BN39";
"VCCIN39":   PN = "BN41"  !CDS_PN = "BN41";
"VCCINFAON33":   PN = "AY18"  !CDS_PN = "AY18";
"VCCINFAON34":   PN = "BA15"  !CDS_PN = "BA15";
"VCCINFAON35":   PN = "BC60"  !CDS_PN = "BC60";
"VCCINFAON36":   PN = "BE15"  !CDS_PN = "BE15";
"VCCINFAON37":   PN = "BE60"  !CDS_PN = "BE60";
"VCCINFAON38":   PN = "BG60"  !CDS_PN = "BG60";
"VCCINFAON39":   PN = "BJ15"  !CDS_PN = "BJ15";
"VCCINFAON40":   PN = "BJ60"  !CDS_PN = "BJ60";
"VCCINFAON41":   PN = "BK61"  !CDS_PN = "BK61";
"VCCINFAON42":   PN = "BN15"  !CDS_PN = "BN15";
"VCCINFAON43":   PN = "CA15"  !CDS_PN = "CA15";
"VCCINFAON44":   PN = "CE19"  !CDS_PN = "CE19";
"VCCINFAON45":   PN = "CJ11"  !CDS_PN = "CJ11";
"VCCINFAON46":   PN = "CJ19"  !CDS_PN = "CJ19";
"VCCINFAON47":   PN = "CN19"  !CDS_PN = "CN19";
"VCCINFAON48":   PN = "CP63"  !CDS_PN = "CP63";
"VCCINFAON49":   PN = "CT63"  !CDS_PN = "CT63";
"VCCINFAON50":   PN = "CV61"  !CDS_PN = "CV61";
"VCCINFAON51":   PN = "CV63"  !CDS_PN = "CV63";
"VCCINFAON52":   PN = "CW62"  !CDS_PN = "CW62";
"VCCINFAON53":   PN = "DA21"  !CDS_PN = "DA21";
BODY = "SOCKET4677_AZIF0045P001C01CS","I8": LOCATION = "U2" #&CDS_LOCATION = "U2" &SEC = "29" #&CDS_SEC = "29";
"VCCD_HV0":   PN = "AT36"  !CDS_PN = "AT36";
"VCCD_HV1":   PN = "AT55"  !CDS_PN = "AT55";
"VCCD_HV2":   PN = "AU3"  !CDS_PN = "AU3";
"VCCD_HV3":   PN = "AU35"  !CDS_PN = "AU35";
"VCCD_HV4":   PN = "AU54"  !CDS_PN = "AU54";
"VCCD_HV5":   PN = "AU7"  !CDS_PN = "AU7";
"VCCD_HV6":   PN = "AV34"  !CDS_PN = "AV34";
"VCCD_HV7":   PN = "AV36"  !CDS_PN = "AV36";
"VCCD_HV8":   PN = "AV53"  !CDS_PN = "AV53";
"VCCD_HV9":   PN = "AV55"  !CDS_PN = "AV55";
"VCCD_HV10":   PN = "BA3"  !CDS_PN = "BA3";
"VCCD_HV11":   PN = "BA7"  !CDS_PN = "BA7";
"VCCD_HV12":   PN = "BE11"  !CDS_PN = "BE11";
"VCCD_HV13":   PN = "BE3"  !CDS_PN = "BE3";
"VCCD_HV14":   PN = "BE7"  !CDS_PN = "BE7";
"VCCD_HV15":   PN = "BJ11"  !CDS_PN = "BJ11";
"VCCD_HV16":   PN = "BJ3"  !CDS_PN = "BJ3";
"VCCD_HV17":   PN = "BJ7"  !CDS_PN = "BJ7";
"VCCD_HV18":   PN = "BN7"  !CDS_PN = "BN7";
"VCCD_HV19":   PN = "CA7"  !CDS_PN = "CA7";
"VCCD_HV20":   PN = "CE7"  !CDS_PN = "CE7";
"VCCD_HV21":   PN = "CW35"  !CDS_PN = "CW35";
"VCCD_HV22":   PN = "CW37"  !CDS_PN = "CW37";
"VCCD_HV23":   PN = "CW52"  !CDS_PN = "CW52";
"VCCD_HV24":   PN = "CW54"  !CDS_PN = "CW54";
"VCCD_HV25":   PN = "CW56"  !CDS_PN = "CW56";
"VCCD_HV26":   PN = "CY34"  !CDS_PN = "CY34";
"VCCD_HV27":   PN = "CY36"  !CDS_PN = "CY36";
"VCCD_HV28":   PN = "CY53"  !CDS_PN = "CY53";
"VCCFA_EHV0":   PN = "AA3"  !CDS_PN = "AA3";
"VCCFA_EHV1":   PN = "AE3"  !CDS_PN = "AE3";
"VCCFA_EHV2":   PN = "AJ3"  !CDS_PN = "AJ3";
"VCCFA_EHV3":   PN = "AN3"  !CDS_PN = "AN3";
"VCCFA_EHV4":   PN = "AT61"  !CDS_PN = "AT61";
"VCCFA_EHV5":   PN = "AU60"  !CDS_PN = "AU60";
"VCCFA_EHV6":   PN = "AV61"  !CDS_PN = "AV61";
"VCCFA_EHV7":   PN = "AW60"  !CDS_PN = "AW60";
"VCCFA_EHV8":   PN = "N3"  !CDS_PN = "N3";
"VCCFA_EHV9":   PN = "U3"  !CDS_PN = "U3";
"VCCINFAON0":   PN = "CE15"  !CDS_PN = "CE15";
"VCCINFAON1":   PN = "CJ15"  !CDS_PN = "CJ15";
"VCCINFAON2":   PN = "CJ3"  !CDS_PN = "CJ3";
"VCCINFAON3":   PN = "CJ7"  !CDS_PN = "CJ7";
"VCCINFAON4":   PN = "CN11"  !CDS_PN = "CN11";
"VCCINFAON5":   PN = "CN15"  !CDS_PN = "CN15";
"VCCINFAON6":   PN = "CN3"  !CDS_PN = "CN3";
"VCCINFAON7":   PN = "CN64"  !CDS_PN = "CN64";
"VCCINFAON8":   PN = "CN66"  !CDS_PN = "CN66";
"VCCINFAON9":   PN = "CN7"  !CDS_PN = "CN7";
"VCCINFAON10":   PN = "CP65"  !CDS_PN = "CP65";
"VCCINFAON11":   PN = "CP67"  !CDS_PN = "CP67";
"VCCINFAON12":   PN = "CT65"  !CDS_PN = "CT65";
"VCCINFAON13":   PN = "CT67"  !CDS_PN = "CT67";
"VCCINFAON14":   PN = "CU11"  !CDS_PN = "CU11";
"VCCINFAON15":   PN = "CU15"  !CDS_PN = "CU15";
"VCCINFAON16":   PN = "CU3"  !CDS_PN = "CU3";
"VCCINFAON17":   PN = "CU64"  !CDS_PN = "CU64";
"VCCINFAON18":   PN = "CU7"  !CDS_PN = "CU7";
"VCCINFAON19":   PN = "CV65"  !CDS_PN = "CV65";
"VCCINFAON20":   PN = "CV67"  !CDS_PN = "CV67";
"VCCINFAON21":   PN = "CW66"  !CDS_PN = "CW66";
"VCCINFAON22":   PN = "CY65"  !CDS_PN = "CY65";
"VCCINFAON23":   PN = "CY67"  !CDS_PN = "CY67";
"VCCINFAON24":   PN = "DA11"  !CDS_PN = "DA11";
"VCCINFAON25":   PN = "DA15"  !CDS_PN = "DA15";
"VCCINFAON26":   PN = "DA64"  !CDS_PN = "DA64";
"VCCINFAON27":   PN = "DE11"  !CDS_PN = "DE11";
"VCCINFAON28":   PN = "DE15"  !CDS_PN = "DE15";
"VCCINFAON29":   PN = "DE3"  !CDS_PN = "DE3";
"VCCINFAON30":   PN = "DJ15"  !CDS_PN = "DJ15";
"VCCINFAON31":   PN = "DJ3"  !CDS_PN = "DJ3";
"VCCINFAON32":   PN = "DJ7"  !CDS_PN = "DJ7";
"VCCINFAON54":   PN = "CR66"  !CDS_PN = "CR66";
"VCCINFAON55":   PN = "CW64"  !CDS_PN = "CW64";
"VCCINFAON56":   PN = "DA3"  !CDS_PN = "DA3";
"VCCINFAON57":   PN = "DA7"  !CDS_PN = "DA7";
"VCCINFAON58":   PN = "DE7"  !CDS_PN = "DE7";
"VCCINFAON59":   PN = "DJ11"  !CDS_PN = "DJ11";
"VCCVNN0":   PN = "BA19"  !CDS_PN = "BA19";
"VCCVNN1":   PN = "BE19"  !CDS_PN = "BE19";
"VCCVNN2":   PN = "BJ19"  !CDS_PN = "BJ19";
"VCCVNN3":   PN = "BN19"  !CDS_PN = "BN19";
"VPP_HBM1":   PN = "CF67"  !CDS_PN = "CF67";
"VPP_HBM2":   PN = "CE68"  !CDS_PN = "CE68";
"VPP_HBM3":   PN = "CD67"  !CDS_PN = "CD67";
"VPP_HBM4":   PN = "CC68"  !CDS_PN = "CC68";
"VCC_3P3_AUX0":   PN = "BC21"  !CDS_PN = "BC21";
"VCC_3P3_AUX1":   PN = "BA21"  !CDS_PN = "BA21";
"VPP_HBM":   PN = "CG68"  !CDS_PN = "CG68";
BODY = "Q_CAP","I15": LOCATION = "C1" #&CDS_LOCATION = "C1" &SEC = "1" #&CDS_SEC = "1";
"A":   PN = "1"  !CDS_PN = "1";
"B":   PN = "2"  !CDS_PN = "2";
DRAWING = "@s9s_mb_2u_lib.s9s_mb_2u(sch_1):page38";
BODY = "SOCKET4677_AZIF0045P001C01CS","I4": LOCATION = "U2" #&CDS_LOCATION = "U2" &SEC = "30" #&CDS_SEC = "30";
"VCCFA_EHV_FIVRA0":   PN = "AA11"  !CDS_PN = "AA11";
"VCCFA_EHV_FIVRA1":   PN = "AA15"  !CDS_PN = "AA15";
"VCCFA_EHV_FIVRA2":   PN = "AA7"  !CDS_PN = "AA7";
"VCCFA_EHV_FIVRA3":   PN = "AD85"  !CDS_PN = "AD85";
"VCCFA_EHV_FIVRA4":   PN = "AD89"  !CDS_PN = "AD89";
"VCCFA_EHV_FIVRA5":   PN = "AE11"  !CDS_PN = "AE11";
"VCCFA_EHV_FIVRA6":   PN = "AE15"  !CDS_PN = "AE15";
"VCCFA_EHV_FIVRA7":   PN = "AE7"  !CDS_PN = "AE7";
"VCCFA_EHV_FIVRA8":   PN = "AF77"  !CDS_PN = "AF77";
"VCCFA_EHV_FIVRA9":   PN = "AG78"  !CDS_PN = "AG78";
"VCCFA_EHV_FIVRA10":   PN = "AH85"  !CDS_PN = "AH85";
"VCCFA_EHV_FIVRA11":   PN = "AH89"  !CDS_PN = "AH89";
"VCCFA_EHV_FIVRA12":   PN = "AJ11"  !CDS_PN = "AJ11";
"VCCFA_EHV_FIVRA13":   PN = "AJ15"  !CDS_PN = "AJ15";
"VCCFA_EHV_FIVRA14":   PN = "AJ7"  !CDS_PN = "AJ7";
"VCCFA_EHV_FIVRA15":   PN = "AM79"  !CDS_PN = "AM79";
"VCCFA_EHV_FIVRA16":   PN = "AM85"  !CDS_PN = "AM85";
"VCCFA_EHV_FIVRA17":   PN = "AM89"  !CDS_PN = "AM89";
"VCCFA_EHV_FIVRA18":   PN = "AN11"  !CDS_PN = "AN11";
"VCCFA_EHV_FIVRA19":   PN = "AN15"  !CDS_PN = "AN15";
"VCCFA_EHV_FIVRA20":   PN = "AN7"  !CDS_PN = "AN7";
"VCCFA_EHV_FIVRA21":   PN = "AN80"  !CDS_PN = "AN80";
"VCCFA_EHV_FIVRA22":   PN = "AT73"  !CDS_PN = "AT73";
"VCCFA_EHV_FIVRA23":   PN = "AT89"  !CDS_PN = "AT89";
"VCCFA_EHV_FIVRA24":   PN = "AU15"  !CDS_PN = "AU15";
"VCCFA_EHV_FIVRA25":   PN = "AW76"  !CDS_PN = "AW76";
"VCCFA_EHV_FIVRA26":   PN = "AY89"  !CDS_PN = "AY89";
"VCCFA_EHV_FIVRA27":   PN = "BE72"  !CDS_PN = "BE72";
"VCCFA_EHV_FIVRA28":   PN = "BF77"  !CDS_PN = "BF77";
"VCCFA_EHV_FIVRA29":   PN = "BH79"  !CDS_PN = "BH79";
"VCCFA_EHV_FIVRA30":   PN = "BJ72"  !CDS_PN = "BJ72";
"VCCFA_EHV_FIVRA31":   PN = "BJ78"  !CDS_PN = "BJ78";
"VCCFA_EHV_FIVRA32":   PN = "C84"  !CDS_PN = "C84";
"VCCFA_EHV_FIVRA33":   PN = "C88"  !CDS_PN = "C88";
"VCCFA_EHV_FIVRA34":   PN = "CE74"  !CDS_PN = "CE74";
"VCCFA_EHV_FIVRA35":   PN = "CK73"  !CDS_PN = "CK73";
"VCCFA_EHV_FIVRA36":   PN = "CK79"  !CDS_PN = "CK79";
"VCCFA_EHV_FIVRA37":   PN = "CM73"  !CDS_PN = "CM73";
"VCCFA_EHV_FIVRA38":   PN = "CN78"  !CDS_PN = "CN78";
"VCCFA_EHV_FIVRA39":   PN = "CP73"  !CDS_PN = "CP73";
"VCCFA_EHV_FIVRA40":   PN = "CT77"  !CDS_PN = "CT77";
"VCCFA_EHV_FIVRA41":   PN = "CT85"  !CDS_PN = "CT85";
"VCCFA_EHV_FIVRA42":   PN = "CY75"  !CDS_PN = "CY75";
"VCCFA_EHV_FIVRA43":   PN = "CY79"  !CDS_PN = "CY79";
"VCCFA_EHV_FIVRA44":   PN = "CY85"  !CDS_PN = "CY85";
"VCCFA_EHV_FIVRA45":   PN = "CY89"  !CDS_PN = "CY89";
"VCCFA_EHV_FIVRA46":   PN = "DD77"  !CDS_PN = "DD77";
"VCCFA_EHV_FIVRA47":   PN = "DD83"  !CDS_PN = "DD83";
"VCCFA_EHV_FIVRA48":   PN = "DD85"  !CDS_PN = "DD85";
"VCCFA_EHV_FIVRA49":   PN = "DD89"  !CDS_PN = "DD89";
"VCCFA_EHV_FIVRA50":   PN = "DH89"  !CDS_PN = "DH89";
"VCCFA_EHV_FIVRA51":   PN = "DM83"  !CDS_PN = "DM83";
"VCCFA_EHV_FIVRA52":   PN = "DM85"  !CDS_PN = "DM85";
"VCCFA_EHV_FIVRA53":   PN = "DM89"  !CDS_PN = "DM89";
"VCCFA_EHV_FIVRA54":   PN = "DN11"  !CDS_PN = "DN11";
"VCCFA_EHV_FIVRA55":   PN = "DN15"  !CDS_PN = "DN15";
"VCCFA_EHV_FIVRA56":   PN = "DN3"  !CDS_PN = "DN3";
"VCCFA_EHV_FIVRA57":   PN = "DN7"  !CDS_PN = "DN7";
"VCCFA_EHV_FIVRA58":   PN = "DT79"  !CDS_PN = "DT79";
"VCCFA_EHV_FIVRA59":   PN = "DT85"  !CDS_PN = "DT85";
"VCCFA_EHV_FIVRA60":   PN = "DT89"  !CDS_PN = "DT89";
"VCCFA_EHV_FIVRA61":   PN = "DU11"  !CDS_PN = "DU11";
"VCCFA_EHV_FIVRA62":   PN = "DU15"  !CDS_PN = "DU15";
"VCCFA_EHV_FIVRA63":   PN = "DU3"  !CDS_PN = "DU3";
"VCCFA_EHV_FIVRA64":   PN = "DU7"  !CDS_PN = "DU7";
"VCCFA_EHV_FIVRA65":   PN = "DY85"  !CDS_PN = "DY85";
"VCCFA_EHV_FIVRA66":   PN = "DY89"  !CDS_PN = "DY89";
"VCCFA_EHV_FIVRA67":   PN = "EA11"  !CDS_PN = "EA11";
"VCCFA_EHV_FIVRA68":   PN = "EA15"  !CDS_PN = "EA15";
"VCCFA_EHV_FIVRA69":   PN = "EA3"  !CDS_PN = "EA3";
"VCCFA_EHV_FIVRA70":   PN = "EA7"  !CDS_PN = "EA7";
"VCCFA_EHV_FIVRA71":   PN = "EC78"  !CDS_PN = "EC78";
"VCCFA_EHV_FIVRA72":   PN = "ED79"  !CDS_PN = "ED79";
"VCCFA_EHV_FIVRA73":   PN = "ED85"  !CDS_PN = "ED85";
"VCCFA_EHV_FIVRA74":   PN = "ED89"  !CDS_PN = "ED89";
"VCCFA_EHV_FIVRA75":   PN = "EE11"  !CDS_PN = "EE11";
"VCCFA_EHV_FIVRA76":   PN = "EE15"  !CDS_PN = "EE15";
"VCCFA_EHV_FIVRA77":   PN = "EE7"  !CDS_PN = "EE7";
"VCCFA_EHV_FIVRA78":   PN = "EE84"  !CDS_PN = "EE84";
"VCCFA_EHV_FIVRA79":   PN = "EF79"  !CDS_PN = "EF79";
"VCCFA_EHV_FIVRA80":   PN = "EG80"  !CDS_PN = "EG80";
"VCCFA_EHV_FIVRA81":   PN = "EJ15"  !CDS_PN = "EJ15";
"VCCFA_EHV_FIVRA82":   PN = "EJ84"  !CDS_PN = "EJ84";
"VCCFA_EHV_FIVRA83":   PN = "EN84"  !CDS_PN = "EN84";
"VCCFA_EHV_FIVRA84":   PN = "H89"  !CDS_PN = "H89";
"VCCFA_EHV_FIVRA85":   PN = "J11"  !CDS_PN = "J11";
"VCCFA_EHV_FIVRA86":   PN = "J7"  !CDS_PN = "J7";
"VCCFA_EHV_FIVRA87":   PN = "J80"  !CDS_PN = "J80";
"VCCFA_EHV_FIVRA88":   PN = "K87"  !CDS_PN = "K87";
"VCCFA_EHV_FIVRA89":   PN = "L84"  !CDS_PN = "L84";
"VCCFA_EHV_FIVRA90":   PN = "M85"  !CDS_PN = "M85";
"VCCFA_EHV_FIVRA91":   PN = "M89"  !CDS_PN = "M89";
"VCCFA_EHV_FIVRA92":   PN = "N11"  !CDS_PN = "N11";
"VCCFA_EHV_FIVRA93":   PN = "N7"  !CDS_PN = "N7";
"VCCFA_EHV_FIVRA94":   PN = "P79"  !CDS_PN = "P79";
"VCCFA_EHV_FIVRA95":   PN = "R80"  !CDS_PN = "R80";
"VCCFA_EHV_FIVRA96":   PN = "T85"  !CDS_PN = "T85";
"VCCFA_EHV_FIVRA97":   PN = "T89"  !CDS_PN = "T89";
"VCCFA_EHV_FIVRA98":   PN = "U11"  !CDS_PN = "U11";
"VCCFA_EHV_FIVRA99":   PN = "U15"  !CDS_PN = "U15";
"VCCFA_EHV_FIVRA100":   PN = "U7"  !CDS_PN = "U7";
"VCCFA_EHV_FIVRA101":   PN = "W80"  !CDS_PN = "W80";
"VCCFA_EHV_FIVRA102":   PN = "Y79"  !CDS_PN = "Y79";
"VCCFA_EHV_FIVRA103":   PN = "Y85"  !CDS_PN = "Y85";
"VCCFA_EHV_FIVRA104":   PN = "Y89"  !CDS_PN = "Y89";
DRAWING = "@s9s_mb_2u_lib.s9s_mb_2u(sch_1):page39";
BODY = "SOCKET4677_AZIF0045P001C01CS","I1": LOCATION = "U2" #&CDS_LOCATION = "U2" &SEC = "31" #&CDS_SEC = "31";
"VSS1312":   PN = "EH42"  !CDS_PN = "EH42";
"VSS1315":   PN = "EH55"  !CDS_PN = "EH55";
"VSS1319":   PN = "EH61"  !CDS_PN = "EH61";
"VSS1320":   PN = "EH67"  !CDS_PN = "EH67";
"VSS1322":   PN = "EH79"  !CDS_PN = "EH79";
"VSS1325":   PN = "EJ11"  !CDS_PN = "EJ11";
"VSS1328":   PN = "EJ17"  !CDS_PN = "EJ17";
"VSS1331":   PN = "EJ25"  !CDS_PN = "EJ25";
"VSS1334":   PN = "EJ35"  !CDS_PN = "EJ35";
"VSS1340":   PN = "EJ54"  !CDS_PN = "EJ54";
"VSS1343":   PN = "EJ62"  !CDS_PN = "EJ62";
"VSS1345":   PN = "EJ68"  !CDS_PN = "EJ68";
"VSS1347":   PN = "EJ72"  !CDS_PN = "EJ72";
"VSS1355":   PN = "EK16"  !CDS_PN = "EK16";
"VSS1357":   PN = "EK20"  !CDS_PN = "EK20";
"VSS1359":   PN = "EK26"  !CDS_PN = "EK26";
"VSS1366":   PN = "EK44"  !CDS_PN = "EK44";
"VSS1368":   PN = "EK51"  !CDS_PN = "EK51";
"VSS1369":   PN = "EK53"  !CDS_PN = "EK53";
"VSS1371":   PN = "EK59"  !CDS_PN = "EK59";
"VSS1372":   PN = "EK63"  !CDS_PN = "EK63";
"VSS1375":   PN = "EK71"  !CDS_PN = "EK71";
"VSS1377":   PN = "EK77"  !CDS_PN = "EK77";
"VSS1378":   PN = "EK79"  !CDS_PN = "EK79";
"VSS1379":   PN = "EK83"  !CDS_PN = "EK83";
"VSS1380":   PN = "EK89"  !CDS_PN = "EK89";
"VSS1381":   PN = "EL15"  !CDS_PN = "EL15";
"VSS1391":   PN = "EL52"  !CDS_PN = "EL52";
"VSS1394":   PN = "EL58"  !CDS_PN = "EL58";
"VSS1396":   PN = "EL7"  !CDS_PN = "EL7";
"VSS1397":   PN = "EL70"  !CDS_PN = "EL70";
"VSS1398":   PN = "EL72"  !CDS_PN = "EL72";
"VSS1400":   PN = "EL86"  !CDS_PN = "EL86";
"VSS1401":   PN = "EL9"  !CDS_PN = "EL9";
"VSS1405":   PN = "EM49"  !CDS_PN = "EM49";
"VSS1409":   PN = "EM79"  !CDS_PN = "EM79";
"VSS1419":   PN = "EH36"  !CDS_PN = "EH36";
"VSS1421":   PN = "EH49"  !CDS_PN = "EH49";
"VSS1422":   PN = "EH73"  !CDS_PN = "EH73";
"VSS1423":   PN = "EH81"  !CDS_PN = "EH81";
"VSS1424":   PN = "EH83"  !CDS_PN = "EH83";
"VSS1425":   PN = "EJ13"  !CDS_PN = "EJ13";
"VSS1426":   PN = "EJ19"  !CDS_PN = "EJ19";
"VSS1427":   PN = "EN39"  !CDS_PN = "EN39";
"VSS1428":   PN = "EJ23"  !CDS_PN = "EJ23";
"VSS1429":   PN = "EJ29"  !CDS_PN = "EJ29";
"VSS1430":   PN = "EJ31"  !CDS_PN = "EJ31";
"VSS1431":   PN = "EJ37"  !CDS_PN = "EJ37";
"VSS1432":   PN = "EJ41"  !CDS_PN = "EJ41";
"VSS1433":   PN = "EJ43"  !CDS_PN = "EJ43";
"VSS1434":   PN = "EJ48"  !CDS_PN = "EJ48";
"VSS1435":   PN = "EJ50"  !CDS_PN = "EJ50";
"VSS1436":   PN = "EN58"  !CDS_PN = "EN58";
"VSS1437":   PN = "EN60"  !CDS_PN = "EN60";
"VSS1438":   PN = "EN62"  !CDS_PN = "EN62";
"VSS1439":   PN = "EJ56"  !CDS_PN = "EJ56";
"VSS1440":   PN = "EN66"  !CDS_PN = "EN66";
"VSS1441":   PN = "EN72"  !CDS_PN = "EN72";
"VSS1442":   PN = "EJ60"  !CDS_PN = "EJ60";
"VSS1443":   PN = "EJ66"  !CDS_PN = "EJ66";
"VSS1444":   PN = "EJ7"  !CDS_PN = "EJ7";
"VSS1445":   PN = "EN88"  !CDS_PN = "EN88";
"VSS1446":   PN = "EN9"  !CDS_PN = "EN9";
"VSS1447":   PN = "EJ74"  !CDS_PN = "EJ74";
"VSS1448":   PN = "EJ78"  !CDS_PN = "EJ78";
"VSS1449":   PN = "EJ88"  !CDS_PN = "EJ88";
"VSS1450":   PN = "EJ9"  !CDS_PN = "EJ9";
"VSS1451":   PN = "EK10"  !CDS_PN = "EK10";
"VSS1452":   PN = "EP69"  !CDS_PN = "EP69";
"VSS1453":   PN = "EP71"  !CDS_PN = "EP71";
"VSS1454":   PN = "EP77"  !CDS_PN = "EP77";
"VSS1455":   PN = "EK14"  !CDS_PN = "EK14";
"VSS1456":   PN = "ER15"  !CDS_PN = "ER15";
"VSS1457":   PN = "ER21"  !CDS_PN = "ER21";
"VSS1458":   PN = "EK2"  !CDS_PN = "EK2";
"VSS1459":   PN = "EK22"  !CDS_PN = "EK22";
"VSS1460":   PN = "EK28"  !CDS_PN = "EK28";
"VSS1461":   PN = "EK32"  !CDS_PN = "EK32";
"VSS1462":   PN = "ER39"  !CDS_PN = "ER39";
"VSS1463":   PN = "EK34"  !CDS_PN = "EK34";
"VSS1464":   PN = "ER52"  !CDS_PN = "ER52";
"VSS1465":   PN = "EK38"  !CDS_PN = "EK38";
"VSS1466":   PN = "EK4"  !CDS_PN = "EK4";
"VSS1467":   PN = "ER58"  !CDS_PN = "ER58";
"VSS1468":   PN = "ER64"  !CDS_PN = "ER64";
"VSS1469":   PN = "EK40"  !CDS_PN = "EK40";
"VSS1470":   PN = "EK47"  !CDS_PN = "EK47";
"VSS1471":   PN = "EK57"  !CDS_PN = "EK57";
"VSS1472":   PN = "EK65"  !CDS_PN = "EK65";
"VSS1473":   PN = "EK69"  !CDS_PN = "EK69";
"VSS1474":   PN = "EK75"  !CDS_PN = "EK75";
"VSS1475":   PN = "EL21"  !CDS_PN = "EL21";
"VSS1476":   PN = "ER9"  !CDS_PN = "ER9";
"VSS1477":   PN = "EL27"  !CDS_PN = "EL27";
"VSS1478":   PN = "ET14"  !CDS_PN = "ET14";
"VSS1479":   PN = "EL3"  !CDS_PN = "EL3";
"VSS1480":   PN = "ET20"  !CDS_PN = "ET20";
"VSS1481":   PN = "EL33"  !CDS_PN = "EL33";
"VSS1482":   PN = "ET26"  !CDS_PN = "ET26";
"VSS1483":   PN = "EL39"  !CDS_PN = "EL39";
"VSS1484":   PN = "ET32"  !CDS_PN = "ET32";
"VSS1485":   PN = "EL45"  !CDS_PN = "EL45";
"VSS1486":   PN = "EL5"  !CDS_PN = "EL5";
"VSS1488":   PN = "EL64"  !CDS_PN = "EL64";
"VSS1489":   PN = "EL76"  !CDS_PN = "EL76";
"VSS1491":   PN = "ET53"  !CDS_PN = "ET53";
"VSS1492":   PN = "EM42"  !CDS_PN = "EM42";
"VSS1493":   PN = "ET59"  !CDS_PN = "ET59";
"VSS1496":   PN = "EM73"  !CDS_PN = "EM73";
"VSS1497":   PN = "EM8"  !CDS_PN = "EM8";
"VSS1498":   PN = "EM81"  !CDS_PN = "EM81";
"VSS1499":   PN = "EM83"  !CDS_PN = "EM83";
"VSS1500":   PN = "EN11"  !CDS_PN = "EN11";
"VSS1501":   PN = "EN13"  !CDS_PN = "EN13";
"VSS1503":   PN = "EN15"  !CDS_PN = "EN15";
"VSS1505":   PN = "EN17"  !CDS_PN = "EN17";
"VSS1506":   PN = "EN19"  !CDS_PN = "EN19";
"VSS1512":   PN = "EN21"  !CDS_PN = "EN21";
"VSS1513":   PN = "EN23"  !CDS_PN = "EN23";
"VSS1515":   PN = "EN25"  !CDS_PN = "EN25";
"VSS1517":   PN = "EN27"  !CDS_PN = "EN27";
"VSS1518":   PN = "EN29"  !CDS_PN = "EN29";
"VSS1520":   PN = "EN31"  !CDS_PN = "EN31";
"VSS1522":   PN = "EN33"  !CDS_PN = "EN33";
"VSS1524":   PN = "EN35"  !CDS_PN = "EN35";
"VSS1525":   PN = "EN37"  !CDS_PN = "EN37";
"VSS1526":   PN = "EN41"  !CDS_PN = "EN41";
"VSS1528":   PN = "EN43"  !CDS_PN = "EN43";
"VSS1529":   PN = "EN45"  !CDS_PN = "EN45";
"VSS1530":   PN = "EN48"  !CDS_PN = "EN48";
"VSS1531":   PN = "EN50"  !CDS_PN = "EN50";
"VSS1533":   PN = "EN52"  !CDS_PN = "EN52";
"VSS1537":   PN = "EN54"  !CDS_PN = "EN54";
"VSS1539":   PN = "EN56"  !CDS_PN = "EN56";
"VSS1540":   PN = "EN64"  !CDS_PN = "EN64";
"VSS1541":   PN = "EN78"  !CDS_PN = "EN78";
"VSS1542":   PN = "EN80"  !CDS_PN = "EN80";
"VSS1543":   PN = "EP67"  !CDS_PN = "EP67";
"VSS1545":   PN = "EP83"  !CDS_PN = "EP83";
"VSS1547":   PN = "ER27"  !CDS_PN = "ER27";
"VSS1548":   PN = "ER33"  !CDS_PN = "ER33";
"VSS1549":   PN = "ER5"  !CDS_PN = "ER5";
"VSS1550":   PN = "ER7"  !CDS_PN = "ER7";
"VSS1551":   PN = "ER70"  !CDS_PN = "ER70";
"VSS1552":   PN = "ER74"  !CDS_PN = "ER74";
"VSS1553":   PN = "ER78"  !CDS_PN = "ER78";
"VSS1554":   PN = "ER80"  !CDS_PN = "ER80";
"VSS1555":   PN = "ER84"  !CDS_PN = "ER84";
"VSS1556":   PN = "ER86"  !CDS_PN = "ER86";
"VSS1557":   PN = "ET10"  !CDS_PN = "ET10";
"VSS1559":   PN = "ET16"  !CDS_PN = "ET16";
"VSS1561":   PN = "ET22"  !CDS_PN = "ET22";
"VSS1562":   PN = "ET28"  !CDS_PN = "ET28";
"VSS1563":   PN = "ET34"  !CDS_PN = "ET34";
"VSS1565":   PN = "ET38"  !CDS_PN = "ET38";
"VSS1569":   PN = "ET57"  !CDS_PN = "ET57";
"VSS1834":   PN = "ER41"  !CDS_PN = "ER41";
"VSS1835":   PN = "ER43"  !CDS_PN = "ER43";
"VSS1836":   PN = "ER48"  !CDS_PN = "ER48";
"VSS1837":   PN = "ER50"  !CDS_PN = "ER50";
BODY = "SOCKET4677_AZIF0045P001C01CS","I9": LOCATION = "U2" #&CDS_LOCATION = "U2" &SEC = "32" #&CDS_SEC = "32";
"VSS1111":   PN = "DY12"  !CDS_PN = "DY12";
"VSS1112":   PN = "DY16"  !CDS_PN = "DY16";
"VSS1115":   PN = "DY4"  !CDS_PN = "DY4";
"VSS1116":   PN = "DY42"  !CDS_PN = "DY42";
"VSS1141":   PN = "EA39"  !CDS_PN = "EA39";
"VSS1142":   PN = "EA45"  !CDS_PN = "EA45";
"VSS1144":   PN = "EA52"  !CDS_PN = "EA52";
"VSS1145":   PN = "EA58"  !CDS_PN = "EA58";
"VSS1146":   PN = "EA64"  !CDS_PN = "EA64";
"VSS1155":   PN = "EB16"  !CDS_PN = "EB16";
"VSS1156":   PN = "EB20"  !CDS_PN = "EB20";
"VSS1158":   PN = "EB26"  !CDS_PN = "EB26";
"VSS1161":   PN = "EB34"  !CDS_PN = "EB34";
"VSS1163":   PN = "EB4"  !CDS_PN = "EB4";
"VSS1165":   PN = "EB44"  !CDS_PN = "EB44";
"VSS1167":   PN = "EB51"  !CDS_PN = "EB51";
"VSS1168":   PN = "EB53"  !CDS_PN = "EB53";
"VSS1170":   PN = "EB59"  !CDS_PN = "EB59";
"VSS1171":   PN = "EB63"  !CDS_PN = "EB63";
"VSS1180":   PN = "EB91"  !CDS_PN = "EB91";
"VSS1185":   PN = "EC25"  !CDS_PN = "EC25";
"VSS1188":   PN = "EC35"  !CDS_PN = "EC35";
"VSS1193":   PN = "EC5"  !CDS_PN = "EC5";
"VSS1195":   PN = "EC54"  !CDS_PN = "EC54";
"VSS1197":   PN = "EC60"  !CDS_PN = "EC60";
"VSS1198":   PN = "EC62"  !CDS_PN = "EC62";
"VSS1200":   PN = "EC68"  !CDS_PN = "EC68";
"VSS1208":   PN = "ED12"  !CDS_PN = "ED12";
"VSS1210":   PN = "ED18"  !CDS_PN = "ED18";
"VSS1217":   PN = "ED42"  !CDS_PN = "ED42";
"VSS1220":   PN = "ED55"  !CDS_PN = "ED55";
"VSS1223":   PN = "ED61"  !CDS_PN = "ED61";
"VSS1224":   PN = "ED67"  !CDS_PN = "ED67";
"VSS1225":   PN = "ED73"  !CDS_PN = "ED73";
"VSS1232":   PN = "EE17"  !CDS_PN = "EE17";
"VSS1235":   PN = "EE39"  !CDS_PN = "EE39";
"VSS1237":   PN = "EE52"  !CDS_PN = "EE52";
"VSS1257":   PN = "DW66"  !CDS_PN = "DW66";
"VSS1258":   PN = "DW68"  !CDS_PN = "DW68";
"VSS1259":   PN = "DW70"  !CDS_PN = "DW70";
"VSS1260":   PN = "DW72"  !CDS_PN = "DW72";
"VSS1261":   PN = "DW74"  !CDS_PN = "DW74";
"VSS1262":   PN = "DW76"  !CDS_PN = "DW76";
"VSS1263":   PN = "DW80"  !CDS_PN = "DW80";
"VSS1264":   PN = "DW82"  !CDS_PN = "DW82";
"VSS1265":   PN = "EF51"  !CDS_PN = "EF51";
"VSS1266":   PN = "DW84"  !CDS_PN = "DW84";
"VSS1267":   PN = "DW88"  !CDS_PN = "DW88";
"VSS1269":   PN = "DY77"  !CDS_PN = "DY77";
"VSS1270":   PN = "DY8"  !CDS_PN = "DY8";
"VSS1274":   PN = "EA21"  !CDS_PN = "EA21";
"VSS1275":   PN = "EA27"  !CDS_PN = "EA27";
"VSS1276":   PN = "EF73"  !CDS_PN = "EF73";
"VSS1277":   PN = "EF75"  !CDS_PN = "EF75";
"VSS1278":   PN = "EA33"  !CDS_PN = "EA33";
"VSS1279":   PN = "EA70"  !CDS_PN = "EA70";
"VSS1280":   PN = "EA76"  !CDS_PN = "EA76";
"VSS1281":   PN = "EA78"  !CDS_PN = "EA78";
"VSS1282":   PN = "EA80"  !CDS_PN = "EA80";
"VSS1283":   PN = "EF89"  !CDS_PN = "EF89";
"VSS1284":   PN = "EG13"  !CDS_PN = "EG13";
"VSS1285":   PN = "EA84"  !CDS_PN = "EA84";
"VSS1286":   PN = "EA88"  !CDS_PN = "EA88";
"VSS1287":   PN = "EB12"  !CDS_PN = "EB12";
"VSS1288":   PN = "EB22"  !CDS_PN = "EB22";
"VSS1289":   PN = "EB28"  !CDS_PN = "EB28";
"VSS1290":   PN = "EG5"  !CDS_PN = "EG5";
"VSS1291":   PN = "EG52"  !CDS_PN = "EG52";
"VSS1292":   PN = "EB32"  !CDS_PN = "EB32";
"VSS1293":   PN = "EB38"  !CDS_PN = "EB38";
"VSS1294":   PN = "EG7"  !CDS_PN = "EG7";
"VSS1295":   PN = "EB40"  !CDS_PN = "EB40";
"VSS1296":   PN = "EB47"  !CDS_PN = "EB47";
"VSS1297":   PN = "EB57"  !CDS_PN = "EB57";
"VSS1298":   PN = "EB65"  !CDS_PN = "EB65";
"VSS1299":   PN = "EB69"  !CDS_PN = "EB69";
"VSS1300":   PN = "EB71"  !CDS_PN = "EB71";
"VSS1301":   PN = "EB75"  !CDS_PN = "EB75";
"VSS1302":   PN = "EH12"  !CDS_PN = "EH12";
"VSS1303":   PN = "EH14"  !CDS_PN = "EH14";
"VSS1304":   PN = "EB79"  !CDS_PN = "EB79";
"VSS1305":   PN = "EH18"  !CDS_PN = "EH18";
"VSS1306":   PN = "EB8"  !CDS_PN = "EB8";
"VSS1307":   PN = "EB83"  !CDS_PN = "EB83";
"VSS1308":   PN = "EB87"  !CDS_PN = "EB87";
"VSS1309":   PN = "EC1"  !CDS_PN = "EC1";
"VSS1310":   PN = "EC13"  !CDS_PN = "EC13";
"VSS1311":   PN = "EC19"  !CDS_PN = "EC19";
"VSS1313":   PN = "EC23"  !CDS_PN = "EC23";
"VSS1314":   PN = "EC29"  !CDS_PN = "EC29";
"VSS1316":   PN = "EC31"  !CDS_PN = "EC31";
"VSS1317":   PN = "EC37"  !CDS_PN = "EC37";
"VSS1318":   PN = "EH6"  !CDS_PN = "EH6";
"VSS1321":   PN = "EC41"  !CDS_PN = "EC41";
"VSS1323":   PN = "EC43"  !CDS_PN = "EC43";
"VSS1324":   PN = "EC48"  !CDS_PN = "EC48";
"VSS1326":   PN = "EC50"  !CDS_PN = "EC50";
"VSS1327":   PN = "EC56"  !CDS_PN = "EC56";
"VSS1329":   PN = "EC66"  !CDS_PN = "EC66";
"VSS1330":   PN = "EC72"  !CDS_PN = "EC72";
"VSS1332":   PN = "EC74"  !CDS_PN = "EC74";
"VSS1333":   PN = "EC82"  !CDS_PN = "EC82";
"VSS1335":   PN = "EC84"  !CDS_PN = "EC84";
"VSS1336":   PN = "EC88"  !CDS_PN = "EC88";
"VSS1337":   PN = "EC9"  !CDS_PN = "EC9";
"VSS1338":   PN = "ED16"  !CDS_PN = "ED16";
"VSS1339":   PN = "ED24"  !CDS_PN = "ED24";
"VSS1341":   PN = "ED30"  !CDS_PN = "ED30";
"VSS1342":   PN = "ED36"  !CDS_PN = "ED36";
"VSS1344":   PN = "ED4"  !CDS_PN = "ED4";
"VSS1346":   PN = "ED49"  !CDS_PN = "ED49";
"VSS1348":   PN = "ED8"  !CDS_PN = "ED8";
"VSS1349":   PN = "EE78"  !CDS_PN = "EE78";
"VSS1350":   PN = "EE80"  !CDS_PN = "EE80";
"VSS1351":   PN = "EE88"  !CDS_PN = "EE88";
"VSS1352":   PN = "EF12"  !CDS_PN = "EF12";
"VSS1353":   PN = "EF16"  !CDS_PN = "EF16";
"VSS1354":   PN = "EF18"  !CDS_PN = "EF18";
"VSS1356":   PN = "EF2"  !CDS_PN = "EF2";
"VSS1358":   PN = "EF20"  !CDS_PN = "EF20";
"VSS1360":   PN = "EF22"  !CDS_PN = "EF22";
"VSS1361":   PN = "EF24"  !CDS_PN = "EF24";
"VSS1362":   PN = "EF26"  !CDS_PN = "EF26";
"VSS1363":   PN = "EF28"  !CDS_PN = "EF28";
"VSS1364":   PN = "EF30"  !CDS_PN = "EF30";
"VSS1365":   PN = "EF32"  !CDS_PN = "EF32";
"VSS1367":   PN = "EF34"  !CDS_PN = "EF34";
"VSS1370":   PN = "EF36"  !CDS_PN = "EF36";
"VSS1373":   PN = "EF38"  !CDS_PN = "EF38";
"VSS1374":   PN = "EF4"  !CDS_PN = "EF4";
"VSS1376":   PN = "EF40"  !CDS_PN = "EF40";
"VSS1382":   PN = "EF42"  !CDS_PN = "EF42";
"VSS1383":   PN = "EF44"  !CDS_PN = "EF44";
"VSS1384":   PN = "EF47"  !CDS_PN = "EF47";
"VSS1385":   PN = "EF49"  !CDS_PN = "EF49";
"VSS1386":   PN = "EF53"  !CDS_PN = "EF53";
"VSS1387":   PN = "EF55"  !CDS_PN = "EF55";
"VSS1388":   PN = "EF57"  !CDS_PN = "EF57";
"VSS1389":   PN = "EF59"  !CDS_PN = "EF59";
"VSS1390":   PN = "EF61"  !CDS_PN = "EF61";
"VSS1392":   PN = "EF63"  !CDS_PN = "EF63";
"VSS1393":   PN = "EF65"  !CDS_PN = "EF65";
"VSS1395":   PN = "EF67"  !CDS_PN = "EF67";
"VSS1399":   PN = "EF69"  !CDS_PN = "EF69";
"VSS1402":   PN = "EF71"  !CDS_PN = "EF71";
"VSS1403":   PN = "EF77"  !CDS_PN = "EF77";
"VSS1404":   PN = "EF8"  !CDS_PN = "EF8";
"VSS1406":   PN = "EF85"  !CDS_PN = "EF85";
"VSS1407":   PN = "EF87"  !CDS_PN = "EF87";
"VSS1408":   PN = "EG39"  !CDS_PN = "EG39";
"VSS1410":   PN = "EG82"  !CDS_PN = "EG82";
"VSS1411":   PN = "EG84"  !CDS_PN = "EG84";
"VSS1412":   PN = "EG86"  !CDS_PN = "EG86";
"VSS1413":   PN = "EG88"  !CDS_PN = "EG88";
"VSS1414":   PN = "EG9"  !CDS_PN = "EG9";
"VSS1415":   PN = "EG90"  !CDS_PN = "EG90";
"VSS1416":   PN = "EH16"  !CDS_PN = "EH16";
"VSS1417":   PN = "EH24"  !CDS_PN = "EH24";
"VSS1418":   PN = "EH30"  !CDS_PN = "EH30";
"VSS1420":   PN = "EH4"  !CDS_PN = "EH4";
BODY = "SOCKET4677_AZIF0045P001C01CS","I10": LOCATION = "U2" #&CDS_LOCATION = "U2" &SEC = "33" #&CDS_SEC = "33";
"VSS934":   PN = "DM51"  !CDS_PN = "DM51";
"VSS945":   PN = "DM73"  !CDS_PN = "DM73";
"VSS955":   PN = "DN17"  !CDS_PN = "DN17";
"VSS957":   PN = "DN39"  !CDS_PN = "DN39";
"VSS959":   PN = "DN52"  !CDS_PN = "DN52";
"VSS966":   PN = "DP12"  !CDS_PN = "DP12";
"VSS968":   PN = "DP18"  !CDS_PN = "DP18";
"VSS969":   PN = "DP24"  !CDS_PN = "DP24";
"VSS973":   PN = "DP42"  !CDS_PN = "DP42";
"VSS976":   PN = "DP55"  !CDS_PN = "DP55";
"VSS979":   PN = "DP61"  !CDS_PN = "DP61";
"VSS980":   PN = "DP67"  !CDS_PN = "DP67";
"VSS985":   PN = "DP91"  !CDS_PN = "DP91";
"VSS990":   PN = "DR25"  !CDS_PN = "DR25";
"VSS993":   PN = "DR35"  !CDS_PN = "DR35";
"VSS998":   PN = "DR5"  !CDS_PN = "DR5";
"VSS1000":   PN = "DR54"  !CDS_PN = "DR54";
"VSS1002":   PN = "DR60"  !CDS_PN = "DR60";
"VSS1003":   PN = "DR62"  !CDS_PN = "DR62";
"VSS1005":   PN = "DR68"  !CDS_PN = "DR68";
"VSS1006":   PN = "DR72"  !CDS_PN = "DR72";
"VSS1013":   PN = "DT16"  !CDS_PN = "DT16";
"VSS1014":   PN = "DT20"  !CDS_PN = "DT20";
"VSS1016":   PN = "DT26"  !CDS_PN = "DT26";
"VSS1021":   PN = "DT4"  !CDS_PN = "DT4";
"VSS1023":   PN = "DT44"  !CDS_PN = "DT44";
"VSS1025":   PN = "DT51"  !CDS_PN = "DT51";
"VSS1026":   PN = "DT53"  !CDS_PN = "DT53";
"VSS1028":   PN = "DT59"  !CDS_PN = "DT59";
"VSS1029":   PN = "DT63"  !CDS_PN = "DT63";
"VSS1036":   PN = "DT83"  !CDS_PN = "DT83";
"VSS1047":   PN = "DU39"  !CDS_PN = "DU39";
"VSS1048":   PN = "DU45"  !CDS_PN = "DU45";
"VSS1050":   PN = "DU52"  !CDS_PN = "DU52";
"VSS1051":   PN = "DU58"  !CDS_PN = "DU58";
"VSS1052":   PN = "DU64"  !CDS_PN = "DU64";
"VSS1054":   PN = "DU70"  !CDS_PN = "DU70";
"VSS1059":   PN = "DV12"  !CDS_PN = "DV12";
"VSS1060":   PN = "DV16"  !CDS_PN = "DV16";
"VSS1063":   PN = "DV4"  !CDS_PN = "DV4";
"VSS1064":   PN = "DV42"  !CDS_PN = "DV42";
"VSS1077":   PN = "DW21"  !CDS_PN = "DW21";
"VSS1097":   PN = "DW60"  !CDS_PN = "DW60";
"VSS1100":   PN = "DM12"  !CDS_PN = "DM12";
"VSS1101":   PN = "DM16"  !CDS_PN = "DM16";
"VSS1102":   PN = "DM18"  !CDS_PN = "DM18";
"VSS1103":   PN = "DM20"  !CDS_PN = "DM20";
"VSS1104":   PN = "DM22"  !CDS_PN = "DM22";
"VSS1105":   PN = "DM24"  !CDS_PN = "DM24";
"VSS1106":   PN = "DM26"  !CDS_PN = "DM26";
"VSS1107":   PN = "DM28"  !CDS_PN = "DM28";
"VSS1108":   PN = "DM30"  !CDS_PN = "DM30";
"VSS1109":   PN = "DM32"  !CDS_PN = "DM32";
"VSS1110":   PN = "DM34"  !CDS_PN = "DM34";
"VSS1113":   PN = "DM36"  !CDS_PN = "DM36";
"VSS1114":   PN = "DM38"  !CDS_PN = "DM38";
"VSS1117":   PN = "DM4"  !CDS_PN = "DM4";
"VSS1118":   PN = "DM40"  !CDS_PN = "DM40";
"VSS1119":   PN = "DM42"  !CDS_PN = "DM42";
"VSS1120":   PN = "DM44"  !CDS_PN = "DM44";
"VSS1121":   PN = "DM47"  !CDS_PN = "DM47";
"VSS1122":   PN = "DM49"  !CDS_PN = "DM49";
"VSS1123":   PN = "DM53"  !CDS_PN = "DM53";
"VSS1124":   PN = "DM55"  !CDS_PN = "DM55";
"VSS1127":   PN = "DM57"  !CDS_PN = "DM57";
"VSS1128":   PN = "DM59"  !CDS_PN = "DM59";
"VSS1130":   PN = "DM61"  !CDS_PN = "DM61";
"VSS1132":   PN = "DM63"  !CDS_PN = "DM63";
"VSS1133":   PN = "DM65"  !CDS_PN = "DM65";
"VSS1134":   PN = "DM67"  !CDS_PN = "DM67";
"VSS1135":   PN = "DM69"  !CDS_PN = "DM69";
"VSS1136":   PN = "DM71"  !CDS_PN = "DM71";
"VSS1137":   PN = "DM75"  !CDS_PN = "DM75";
"VSS1138":   PN = "DM77"  !CDS_PN = "DM77";
"VSS1139":   PN = "DM79"  !CDS_PN = "DM79";
"VSS1140":   PN = "DM8"  !CDS_PN = "DM8";
"VSS1143":   PN = "DN78"  !CDS_PN = "DN78";
"VSS1147":   PN = "DN84"  !CDS_PN = "DN84";
"VSS1148":   PN = "DN88"  !CDS_PN = "DN88";
"VSS1149":   PN = "DP16"  !CDS_PN = "DP16";
"VSS1150":   PN = "DP30"  !CDS_PN = "DP30";
"VSS1151":   PN = "DP36"  !CDS_PN = "DP36";
"VSS1152":   PN = "DP4"  !CDS_PN = "DP4";
"VSS1153":   PN = "DP49"  !CDS_PN = "DP49";
"VSS1154":   PN = "DP73"  !CDS_PN = "DP73";
"VSS1157":   PN = "DP8"  !CDS_PN = "DP8";
"VSS1159":   PN = "DP81"  !CDS_PN = "DP81";
"VSS1160":   PN = "DP87"  !CDS_PN = "DP87";
"VSS1162":   PN = "DR1"  !CDS_PN = "DR1";
"VSS1164":   PN = "DR13"  !CDS_PN = "DR13";
"VSS1166":   PN = "DR19"  !CDS_PN = "DR19";
"VSS1169":   PN = "DR23"  !CDS_PN = "DR23";
"VSS1172":   PN = "DR29"  !CDS_PN = "DR29";
"VSS1173":   PN = "DR31"  !CDS_PN = "DR31";
"VSS1174":   PN = "DR37"  !CDS_PN = "DR37";
"VSS1175":   PN = "DR41"  !CDS_PN = "DR41";
"VSS1176":   PN = "DR43"  !CDS_PN = "DR43";
"VSS1177":   PN = "DR48"  !CDS_PN = "DR48";
"VSS1178":   PN = "DR50"  !CDS_PN = "DR50";
"VSS1179":   PN = "DR56"  !CDS_PN = "DR56";
"VSS1181":   PN = "DR66"  !CDS_PN = "DR66";
"VSS1182":   PN = "DR74"  !CDS_PN = "DR74";
"VSS1183":   PN = "DR78"  !CDS_PN = "DR78";
"VSS1184":   PN = "DR84"  !CDS_PN = "DR84";
"VSS1186":   PN = "DR88"  !CDS_PN = "DR88";
"VSS1187":   PN = "DR9"  !CDS_PN = "DR9";
"VSS1189":   PN = "DT12"  !CDS_PN = "DT12";
"VSS1190":   PN = "DT22"  !CDS_PN = "DT22";
"VSS1191":   PN = "DT28"  !CDS_PN = "DT28";
"VSS1192":   PN = "DT32"  !CDS_PN = "DT32";
"VSS1194":   PN = "DT34"  !CDS_PN = "DT34";
"VSS1196":   PN = "DT38"  !CDS_PN = "DT38";
"VSS1199":   PN = "DT40"  !CDS_PN = "DT40";
"VSS1201":   PN = "DT47"  !CDS_PN = "DT47";
"VSS1202":   PN = "DT57"  !CDS_PN = "DT57";
"VSS1203":   PN = "DT65"  !CDS_PN = "DT65";
"VSS1204":   PN = "DT69"  !CDS_PN = "DT69";
"VSS1205":   PN = "DT71"  !CDS_PN = "DT71";
"VSS1206":   PN = "DT75"  !CDS_PN = "DT75";
"VSS1207":   PN = "DT8"  !CDS_PN = "DT8";
"VSS1209":   PN = "DU21"  !CDS_PN = "DU21";
"VSS1211":   PN = "DU27"  !CDS_PN = "DU27";
"VSS1212":   PN = "DU33"  !CDS_PN = "DU33";
"VSS1213":   PN = "DU76"  !CDS_PN = "DU76";
"VSS1214":   PN = "DU78"  !CDS_PN = "DU78";
"VSS1215":   PN = "DU84"  !CDS_PN = "DU84";
"VSS1216":   PN = "DU88"  !CDS_PN = "DU88";
"VSS1218":   PN = "DV77"  !CDS_PN = "DV77";
"VSS1219":   PN = "DV79"  !CDS_PN = "DV79";
"VSS1221":   PN = "DV8"  !CDS_PN = "DV8";
"VSS1222":   PN = "DV81"  !CDS_PN = "DV81";
"VSS1226":   PN = "DV83"  !CDS_PN = "DV83";
"VSS1227":   PN = "DV87"  !CDS_PN = "DV87";
"VSS1228":   PN = "DV91"  !CDS_PN = "DV91";
"VSS1229":   PN = "DW1"  !CDS_PN = "DW1";
"VSS1230":   PN = "DW13"  !CDS_PN = "DW13";
"VSS1231":   PN = "DW17"  !CDS_PN = "DW17";
"VSS1233":   PN = "DW19"  !CDS_PN = "DW19";
"VSS1234":   PN = "DW23"  !CDS_PN = "DW23";
"VSS1236":   PN = "DW25"  !CDS_PN = "DW25";
"VSS1238":   PN = "DW27"  !CDS_PN = "DW27";
"VSS1239":   PN = "DW29"  !CDS_PN = "DW29";
"VSS1240":   PN = "DW31"  !CDS_PN = "DW31";
"VSS1241":   PN = "DW33"  !CDS_PN = "DW33";
"VSS1242":   PN = "DW35"  !CDS_PN = "DW35";
"VSS1243":   PN = "DW37"  !CDS_PN = "DW37";
"VSS1244":   PN = "DW39"  !CDS_PN = "DW39";
"VSS1245":   PN = "DW41"  !CDS_PN = "DW41";
"VSS1246":   PN = "DW43"  !CDS_PN = "DW43";
"VSS1247":   PN = "DW45"  !CDS_PN = "DW45";
"VSS1248":   PN = "DW48"  !CDS_PN = "DW48";
"VSS1249":   PN = "DW5"  !CDS_PN = "DW5";
"VSS1250":   PN = "DW50"  !CDS_PN = "DW50";
"VSS1251":   PN = "DW52"  !CDS_PN = "DW52";
"VSS1252":   PN = "DW54"  !CDS_PN = "DW54";
"VSS1253":   PN = "DW56"  !CDS_PN = "DW56";
"VSS1254":   PN = "DW58"  !CDS_PN = "DW58";
"VSS1255":   PN = "DW62"  !CDS_PN = "DW62";
"VSS1256":   PN = "DW64"  !CDS_PN = "DW64";
"VSS1268":   PN = "DW9"  !CDS_PN = "DW9";
DRAWING = "@s9s_mb_2u_lib.s9s_mb_2u(sch_1):page40";
BODY = "SOCKET4677_AZIF0045P001C01CS","I10": LOCATION = "U2" #&CDS_LOCATION = "U2" &SEC = "34" #&CDS_SEC = "34";
"VSS723":   PN = "DB91"  !CDS_PN = "DB91";
"VSS724":   PN = "DC1"  !CDS_PN = "DC1";
"VSS725":   PN = "DC13"  !CDS_PN = "DC13";
"VSS726":   PN = "DC21"  !CDS_PN = "DC21";
"VSS735":   PN = "DC52"  !CDS_PN = "DC52";
"VSS738":   PN = "DC58"  !CDS_PN = "DC58";
"VSS739":   PN = "DC64"  !CDS_PN = "DC64";
"VSS747":   PN = "DD12"  !CDS_PN = "DD12";
"VSS748":   PN = "DD16"  !CDS_PN = "DD16";
"VSS753":   PN = "DD49"  !CDS_PN = "DD49";
"VSS776":   PN = "DE39"  !CDS_PN = "DE39";
"VSS791":   PN = "DE70"  !CDS_PN = "DE70";
"VSS798":   PN = "DF12"  !CDS_PN = "DF12";
"VSS799":   PN = "DF16"  !CDS_PN = "DF16";
"VSS802":   PN = "DF49"  !CDS_PN = "DF49";
"VSS806":   PN = "DF91"  !CDS_PN = "DF91";
"VSS807":   PN = "DG1"  !CDS_PN = "DG1";
"VSS808":   PN = "DG13"  !CDS_PN = "DG13";
"VSS809":   PN = "DG21"  !CDS_PN = "DG21";
"VSS817":   PN = "DG52"  !CDS_PN = "DG52";
"VSS820":   PN = "DG58"  !CDS_PN = "DG58";
"VSS821":   PN = "DG64"  !CDS_PN = "DG64";
"VSS829":   PN = "DH16"  !CDS_PN = "DH16";
"VSS830":   PN = "DH20"  !CDS_PN = "DH20";
"VSS832":   PN = "DH26"  !CDS_PN = "DH26";
"VSS835":   PN = "DH34"  !CDS_PN = "DH34";
"VSS839":   PN = "DH44"  !CDS_PN = "DH44";
"VSS841":   PN = "DH51"  !CDS_PN = "DH51";
"VSS842":   PN = "DH53"  !CDS_PN = "DH53";
"VSS844":   PN = "DH59"  !CDS_PN = "DH59";
"VSS845":   PN = "DH63"  !CDS_PN = "DH63";
"VSS847":   PN = "DH69"  !CDS_PN = "DH69";
"VSS849":   PN = "DH75"  !CDS_PN = "DH75";
"VSS857":   PN = "DJ25"  !CDS_PN = "DJ25";
"VSS861":   PN = "DJ35"  !CDS_PN = "DJ35";
"VSS867":   PN = "DJ54"  !CDS_PN = "DJ54";
"VSS870":   PN = "DJ62"  !CDS_PN = "DJ62";
"VSS872":   PN = "DJ68"  !CDS_PN = "DJ68";
"VSS880":   PN = "DK12"  !CDS_PN = "DK12";
"VSS882":   PN = "DK18"  !CDS_PN = "DK18";
"VSS883":   PN = "DK24"  !CDS_PN = "DK24";
"VSS887":   PN = "DK42"  !CDS_PN = "DK42";
"VSS890":   PN = "DK55"  !CDS_PN = "DK55";
"VSS893":   PN = "DK61"  !CDS_PN = "DK61";
"VSS894":   PN = "DK67"  !CDS_PN = "DK67";
"VSS903":   PN = "DL1"  !CDS_PN = "DL1";
"VSS904":   PN = "DL13"  !CDS_PN = "DL13";
"VSS905":   PN = "DL17"  !CDS_PN = "DL17";
"VSS908":   PN = "DL5"  !CDS_PN = "DL5";
"VSS909":   PN = "DL52"  !CDS_PN = "DL52";
"VSS949":   PN = "DC27"  !CDS_PN = "DC27";
"VSS950":   PN = "DC33"  !CDS_PN = "DC33";
"VSS951":   PN = "DC39"  !CDS_PN = "DC39";
"VSS952":   PN = "DC45"  !CDS_PN = "DC45";
"VSS953":   PN = "DC5"  !CDS_PN = "DC5";
"VSS954":   PN = "DC70"  !CDS_PN = "DC70";
"VSS956":   PN = "DC76"  !CDS_PN = "DC76";
"VSS958":   PN = "DC78"  !CDS_PN = "DC78";
"VSS960":   PN = "DC80"  !CDS_PN = "DC80";
"VSS961":   PN = "DC84"  !CDS_PN = "DC84";
"VSS962":   PN = "DC88"  !CDS_PN = "DC88";
"VSS963":   PN = "DC9"  !CDS_PN = "DC9";
"VSS964":   PN = "DD4"  !CDS_PN = "DD4";
"VSS965":   PN = "DD79"  !CDS_PN = "DD79";
"VSS967":   PN = "DD8"  !CDS_PN = "DD8";
"VSS970":   PN = "DE17"  !CDS_PN = "DE17";
"VSS971":   PN = "DE19"  !CDS_PN = "DE19";
"VSS972":   PN = "DE21"  !CDS_PN = "DE21";
"VSS974":   PN = "DE23"  !CDS_PN = "DE23";
"VSS975":   PN = "DE25"  !CDS_PN = "DE25";
"VSS977":   PN = "DE27"  !CDS_PN = "DE27";
"VSS978":   PN = "DE29"  !CDS_PN = "DE29";
"VSS981":   PN = "DE31"  !CDS_PN = "DE31";
"VSS982":   PN = "DE33"  !CDS_PN = "DE33";
"VSS983":   PN = "DE35"  !CDS_PN = "DE35";
"VSS984":   PN = "DE37"  !CDS_PN = "DE37";
"VSS986":   PN = "DE41"  !CDS_PN = "DE41";
"VSS987":   PN = "DE43"  !CDS_PN = "DE43";
"VSS988":   PN = "DE45"  !CDS_PN = "DE45";
"VSS989":   PN = "DE48"  !CDS_PN = "DE48";
"VSS991":   PN = "DE50"  !CDS_PN = "DE50";
"VSS992":   PN = "DE52"  !CDS_PN = "DE52";
"VSS994":   PN = "DE54"  !CDS_PN = "DE54";
"VSS995":   PN = "DE56"  !CDS_PN = "DE56";
"VSS996":   PN = "DE58"  !CDS_PN = "DE58";
"VSS997":   PN = "DE60"  !CDS_PN = "DE60";
"VSS999":   PN = "DE62"  !CDS_PN = "DE62";
"VSS1001":   PN = "DE64"  !CDS_PN = "DE64";
"VSS1004":   PN = "DE66"  !CDS_PN = "DE66";
"VSS1007":   PN = "DE68"  !CDS_PN = "DE68";
"VSS1008":   PN = "DE72"  !CDS_PN = "DE72";
"VSS1009":   PN = "DE74"  !CDS_PN = "DE74";
"VSS1010":   PN = "DE76"  !CDS_PN = "DE76";
"VSS1011":   PN = "DE82"  !CDS_PN = "DE82";
"VSS1012":   PN = "DE84"  !CDS_PN = "DE84";
"VSS1015":   PN = "DE88"  !CDS_PN = "DE88";
"VSS1017":   PN = "DF4"  !CDS_PN = "DF4";
"VSS1018":   PN = "DF79"  !CDS_PN = "DF79";
"VSS1019":   PN = "DF8"  !CDS_PN = "DF8";
"VSS1020":   PN = "DF87"  !CDS_PN = "DF87";
"VSS1022":   PN = "DG27"  !CDS_PN = "DG27";
"VSS1024":   PN = "DG33"  !CDS_PN = "DG33";
"VSS1027":   PN = "DG39"  !CDS_PN = "DG39";
"VSS1030":   PN = "DG45"  !CDS_PN = "DG45";
"VSS1031":   PN = "DG5"  !CDS_PN = "DG5";
"VSS1032":   PN = "DG70"  !CDS_PN = "DG70";
"VSS1033":   PN = "DG76"  !CDS_PN = "DG76";
"VSS1034":   PN = "DG80"  !CDS_PN = "DG80";
"VSS1035":   PN = "DG84"  !CDS_PN = "DG84";
"VSS1037":   PN = "DG88"  !CDS_PN = "DG88";
"VSS1038":   PN = "DG9"  !CDS_PN = "DG9";
"VSS1039":   PN = "DH12"  !CDS_PN = "DH12";
"VSS1040":   PN = "DH22"  !CDS_PN = "DH22";
"VSS1041":   PN = "DH28"  !CDS_PN = "DH28";
"VSS1042":   PN = "DH32"  !CDS_PN = "DH32";
"VSS1043":   PN = "DH38"  !CDS_PN = "DH38";
"VSS1044":   PN = "DH4"  !CDS_PN = "DH4";
"VSS1045":   PN = "DH40"  !CDS_PN = "DH40";
"VSS1046":   PN = "DH47"  !CDS_PN = "DH47";
"VSS1049":   PN = "DH57"  !CDS_PN = "DH57";
"VSS1053":   PN = "DH65"  !CDS_PN = "DH65";
"VSS1055":   PN = "DH71"  !CDS_PN = "DH71";
"VSS1056":   PN = "DH77"  !CDS_PN = "DH77";
"VSS1057":   PN = "DH8"  !CDS_PN = "DH8";
"VSS1058":   PN = "DH85"  !CDS_PN = "DH85";
"VSS1061":   PN = "DJ19"  !CDS_PN = "DJ19";
"VSS1062":   PN = "DJ23"  !CDS_PN = "DJ23";
"VSS1065":   PN = "DJ29"  !CDS_PN = "DJ29";
"VSS1066":   PN = "DJ31"  !CDS_PN = "DJ31";
"VSS1067":   PN = "DJ37"  !CDS_PN = "DJ37";
"VSS1068":   PN = "DJ41"  !CDS_PN = "DJ41";
"VSS1069":   PN = "DJ43"  !CDS_PN = "DJ43";
"VSS1070":   PN = "DJ48"  !CDS_PN = "DJ48";
"VSS1071":   PN = "DJ50"  !CDS_PN = "DJ50";
"VSS1072":   PN = "DJ56"  !CDS_PN = "DJ56";
"VSS1073":   PN = "DJ60"  !CDS_PN = "DJ60";
"VSS1074":   PN = "DJ66"  !CDS_PN = "DJ66";
"VSS1075":   PN = "DJ72"  !CDS_PN = "DJ72";
"VSS1076":   PN = "DJ74"  !CDS_PN = "DJ74";
"VSS1078":   PN = "DJ80"  !CDS_PN = "DJ80";
"VSS1079":   PN = "DJ82"  !CDS_PN = "DJ82";
"VSS1080":   PN = "DJ84"  !CDS_PN = "DJ84";
"VSS1081":   PN = "DJ88"  !CDS_PN = "DJ88";
"VSS1082":   PN = "DK16"  !CDS_PN = "DK16";
"VSS1083":   PN = "DK30"  !CDS_PN = "DK30";
"VSS1084":   PN = "DK36"  !CDS_PN = "DK36";
"VSS1085":   PN = "DK4"  !CDS_PN = "DK4";
"VSS1086":   PN = "DK49"  !CDS_PN = "DK49";
"VSS1087":   PN = "DK73"  !CDS_PN = "DK73";
"VSS1088":   PN = "DK77"  !CDS_PN = "DK77";
"VSS1089":   PN = "DK79"  !CDS_PN = "DK79";
"VSS1090":   PN = "DK8"  !CDS_PN = "DK8";
"VSS1091":   PN = "DK81"  !CDS_PN = "DK81";
"VSS1092":   PN = "DK83"  !CDS_PN = "DK83";
"VSS1093":   PN = "DK87"  !CDS_PN = "DK87";
"VSS1094":   PN = "DK91"  !CDS_PN = "DK91";
"VSS1095":   PN = "DL39"  !CDS_PN = "DL39";
"VSS1096":   PN = "DL84"  !CDS_PN = "DL84";
"VSS1098":   PN = "DL88"  !CDS_PN = "DL88";
"VSS1099":   PN = "DL9"  !CDS_PN = "DL9";
BODY = "SOCKET4677_AZIF0045P001C01CS","I11": LOCATION = "U2" #&CDS_LOCATION = "U2" &SEC = "35" #&CDS_SEC = "35";
"VSS436":   PN = "CM16"  !CDS_PN = "CM16";
"VSS438":   PN = "CM22"  !CDS_PN = "CM22";
"VSS471":   PN = "CN76"  !CDS_PN = "CN76";
"VSS478":   PN = "CP16"  !CDS_PN = "CP16";
"VSS493":   PN = "CP79"  !CDS_PN = "CP79";
"VSS514":   PN = "CR78"  !CDS_PN = "CR78";
"VSS521":   PN = "CT16"  !CDS_PN = "CT16";
"VSS526":   PN = "CT4"  !CDS_PN = "CT4";
"VSS534":   PN = "CT8"  !CDS_PN = "CT8";
"VSS537":   PN = "CT89"  !CDS_PN = "CT89";
"VSS544":   PN = "CU25"  !CDS_PN = "CU25";
"VSS553":   PN = "CU72"  !CDS_PN = "CU72";
"VSS554":   PN = "CU78"  !CDS_PN = "CU78";
"VSS558":   PN = "CV16"  !CDS_PN = "CV16";
"VSS562":   PN = "CV26"  !CDS_PN = "CV26";
"VSS571":   PN = "CV79"  !CDS_PN = "CV79";
"VSS583":   PN = "CW33"  !CDS_PN = "CW33";
"VSS595":   PN = "CW70"  !CDS_PN = "CW70";
"VSS611":   PN = "CY4"  !CDS_PN = "CY4";
"VSS679":   PN = "DA43"  !CDS_PN = "DA43";
"VSS690":   PN = "DA68"  !CDS_PN = "DA68";
"VSS699":   PN = "DB16"  !CDS_PN = "DB16";
"VSS700":   PN = "DB20"  !CDS_PN = "DB20";
"VSS702":   PN = "DB26"  !CDS_PN = "DB26";
"VSS705":   PN = "DB34"  !CDS_PN = "DB34";
"VSS709":   PN = "DB44"  !CDS_PN = "DB44";
"VSS711":   PN = "DB51"  !CDS_PN = "DB51";
"VSS712":   PN = "DB53"  !CDS_PN = "DB53";
"VSS714":   PN = "DB59"  !CDS_PN = "DB59";
"VSS715":   PN = "DB63"  !CDS_PN = "DB63";
"VSS717":   PN = "DB69"  !CDS_PN = "DB69";
"VSS719":   PN = "DB75"  !CDS_PN = "DB75";
"VSS744":   PN = "CK63"  !CDS_PN = "CK63";
"VSS745":   PN = "CK69"  !CDS_PN = "CK69";
"VSS749":   PN = "CK81"  !CDS_PN = "CK81";
"VSS750":   PN = "CL1"  !CDS_PN = "CL1";
"VSS751":   PN = "CL13"  !CDS_PN = "CL13";
"VSS752":   PN = "CL17"  !CDS_PN = "CL17";
"VSS754":   PN = "CL5"  !CDS_PN = "CL5";
"VSS755":   PN = "CL62"  !CDS_PN = "CL62";
"VSS756":   PN = "CL74"  !CDS_PN = "CL74";
"VSS757":   PN = "CL78"  !CDS_PN = "CL78";
"VSS758":   PN = "CL80"  !CDS_PN = "CL80";
"VSS759":   PN = "CL82"  !CDS_PN = "CL82";
"VSS760":   PN = "CL9"  !CDS_PN = "CL9";
"VSS761":   PN = "CM12"  !CDS_PN = "CM12";
"VSS762":   PN = "CM20"  !CDS_PN = "CM20";
"VSS763":   PN = "CM24"  !CDS_PN = "CM24";
"VSS764":   PN = "CM4"  !CDS_PN = "CM4";
"VSS765":   PN = "CM61"  !CDS_PN = "CM61";
"VSS766":   PN = "CM65"  !CDS_PN = "CM65";
"VSS767":   PN = "CM67"  !CDS_PN = "CM67";
"VSS768":   PN = "CM79"  !CDS_PN = "CM79";
"VSS769":   PN = "CM8"  !CDS_PN = "CM8";
"VSS770":   PN = "CM81"  !CDS_PN = "CM81";
"VSS771":   PN = "CM83"  !CDS_PN = "CM83";
"VSS772":   PN = "CM85"  !CDS_PN = "CM85";
"VSS773":   PN = "CN68"  !CDS_PN = "CN68";
"VSS774":   PN = "CN70"  !CDS_PN = "CN70";
"VSS775":   PN = "CN72"  !CDS_PN = "CN72";
"VSS777":   PN = "CN74"  !CDS_PN = "CN74";
"VSS778":   PN = "CN84"  !CDS_PN = "CN84";
"VSS779":   PN = "CN86"  !CDS_PN = "CN86";
"VSS780":   PN = "CP12"  !CDS_PN = "CP12";
"VSS781":   PN = "CP18"  !CDS_PN = "CP18";
"VSS782":   PN = "CP4"  !CDS_PN = "CP4";
"VSS783":   PN = "CP75"  !CDS_PN = "CP75";
"VSS784":   PN = "CP77"  !CDS_PN = "CP77";
"VSS785":   PN = "CP8"  !CDS_PN = "CP8";
"VSS786":   PN = "CP83"  !CDS_PN = "CP83";
"VSS787":   PN = "CP87"  !CDS_PN = "CP87";
"VSS788":   PN = "CP91"  !CDS_PN = "CP91";
"VSS789":   PN = "CR1"  !CDS_PN = "CR1";
"VSS790":   PN = "CR11"  !CDS_PN = "CR11";
"VSS792":   PN = "CR13"  !CDS_PN = "CR13";
"VSS793":   PN = "CR17"  !CDS_PN = "CR17";
"VSS794":   PN = "CR5"  !CDS_PN = "CR5";
"VSS795":   PN = "CR62"  !CDS_PN = "CR62";
"VSS796":   PN = "CR64"  !CDS_PN = "CR64";
"VSS797":   PN = "CR84"  !CDS_PN = "CR84";
"VSS800":   PN = "CR88"  !CDS_PN = "CR88";
"VSS801":   PN = "CR9"  !CDS_PN = "CR9";
"VSS803":   PN = "CR90"  !CDS_PN = "CR90";
"VSS804":   PN = "CT10"  !CDS_PN = "CT10";
"VSS805":   PN = "CT12"  !CDS_PN = "CT12";
"VSS810":   PN = "CT69"  !CDS_PN = "CT69";
"VSS811":   PN = "CT73"  !CDS_PN = "CT73";
"VSS812":   PN = "CT81"  !CDS_PN = "CT81";
"VSS813":   PN = "CU19"  !CDS_PN = "CU19";
"VSS814":   PN = "CU21"  !CDS_PN = "CU21";
"VSS815":   PN = "CU23"  !CDS_PN = "CU23";
"VSS816":   PN = "CU60"  !CDS_PN = "CU60";
"VSS818":   PN = "CU66"  !CDS_PN = "CU66";
"VSS819":   PN = "CU68"  !CDS_PN = "CU68";
"VSS822":   PN = "CU84"  !CDS_PN = "CU84";
"VSS823":   PN = "CU88"  !CDS_PN = "CU88";
"VSS824":   PN = "CV12"  !CDS_PN = "CV12";
"VSS825":   PN = "CV4"  !CDS_PN = "CV4";
"VSS826":   PN = "CV75"  !CDS_PN = "CV75";
"VSS827":   PN = "CV8"  !CDS_PN = "CV8";
"VSS828":   PN = "CV83"  !CDS_PN = "CV83";
"VSS831":   PN = "CV87"  !CDS_PN = "CV87";
"VSS833":   PN = "CV91"  !CDS_PN = "CV91";
"VSS834":   PN = "CW1"  !CDS_PN = "CW1";
"VSS836":   PN = "CW13"  !CDS_PN = "CW13";
"VSS837":   PN = "CW17"  !CDS_PN = "CW17";
"VSS838":   PN = "CW5"  !CDS_PN = "CW5";
"VSS840":   PN = "CW72"  !CDS_PN = "CW72";
"VSS843":   PN = "CW78"  !CDS_PN = "CW78";
"VSS846":   PN = "CW84"  !CDS_PN = "CW84";
"VSS848":   PN = "CW88"  !CDS_PN = "CW88";
"VSS850":   PN = "CW9"  !CDS_PN = "CW9";
"VSS851":   PN = "CY12"  !CDS_PN = "CY12";
"VSS852":   PN = "CY16"  !CDS_PN = "CY16";
"VSS853":   PN = "CY18"  !CDS_PN = "CY18";
"VSS854":   PN = "CY26"  !CDS_PN = "CY26";
"VSS855":   PN = "CY30"  !CDS_PN = "CY30";
"VSS856":   PN = "CY63"  !CDS_PN = "CY63";
"VSS858":   PN = "CY73"  !CDS_PN = "CY73";
"VSS859":   PN = "CY77"  !CDS_PN = "CY77";
"VSS860":   PN = "CY8"  !CDS_PN = "CY8";
"VSS862":   PN = "CY81"  !CDS_PN = "CY81";
"VSS863":   PN = "CY83"  !CDS_PN = "CY83";
"VSS910":   PN = "DA19"  !CDS_PN = "DA19";
"VSS911":   PN = "DA23"  !CDS_PN = "DA23";
"VSS912":   PN = "DA25"  !CDS_PN = "DA25";
"VSS913":   PN = "DA29"  !CDS_PN = "DA29";
"VSS914":   PN = "DA31"  !CDS_PN = "DA31";
"VSS915":   PN = "DA33"  !CDS_PN = "DA33";
"VSS916":   PN = "DA35"  !CDS_PN = "DA35";
"VSS917":   PN = "DA37"  !CDS_PN = "DA37";
"VSS918":   PN = "DA41"  !CDS_PN = "DA41";
"VSS919":   PN = "DA48"  !CDS_PN = "DA48";
"VSS920":   PN = "DA50"  !CDS_PN = "DA50";
"VSS921":   PN = "DA54"  !CDS_PN = "DA54";
"VSS922":   PN = "DA56"  !CDS_PN = "DA56";
"VSS923":   PN = "DA58"  !CDS_PN = "DA58";
"VSS924":   PN = "DA60"  !CDS_PN = "DA60";
"VSS925":   PN = "DA62"  !CDS_PN = "DA62";
"VSS926":   PN = "DA66"  !CDS_PN = "DA66";
"VSS927":   PN = "DA72"  !CDS_PN = "DA72";
"VSS928":   PN = "DA74"  !CDS_PN = "DA74";
"VSS929":   PN = "DA80"  !CDS_PN = "DA80";
"VSS930":   PN = "DA82"  !CDS_PN = "DA82";
"VSS931":   PN = "DA84"  !CDS_PN = "DA84";
"VSS932":   PN = "DA88"  !CDS_PN = "DA88";
"VSS933":   PN = "DB12"  !CDS_PN = "DB12";
"VSS935":   PN = "DB22"  !CDS_PN = "DB22";
"VSS936":   PN = "DB28"  !CDS_PN = "DB28";
"VSS937":   PN = "DB32"  !CDS_PN = "DB32";
"VSS938":   PN = "DB38"  !CDS_PN = "DB38";
"VSS939":   PN = "DB4"  !CDS_PN = "DB4";
"VSS940":   PN = "DB40"  !CDS_PN = "DB40";
"VSS941":   PN = "DB47"  !CDS_PN = "DB47";
"VSS942":   PN = "DB57"  !CDS_PN = "DB57";
"VSS943":   PN = "DB65"  !CDS_PN = "DB65";
"VSS944":   PN = "DB71"  !CDS_PN = "DB71";
"VSS946":   PN = "DB77"  !CDS_PN = "DB77";
"VSS947":   PN = "DB8"  !CDS_PN = "DB8";
"VSS948":   PN = "DB87"  !CDS_PN = "DB87";
BODY = "SOCKET4677_AZIF0045P001C01CS","I12": LOCATION = "U2" #&CDS_LOCATION = "U2" &SEC = "36" #&CDS_SEC = "36";
"VSS383":   PN = "CJ76"  !CDS_PN = "CJ76";
"VSS396":   PN = "CK4"  !CDS_PN = "CK4";
"VSS542":   PN = "BR35"  !CDS_PN = "BR35";
"VSS543":   PN = "BR37"  !CDS_PN = "BR37";
"VSS545":   PN = "BR39"  !CDS_PN = "BR39";
"VSS546":   PN = "BR41"  !CDS_PN = "BR41";
"VSS547":   PN = "BR43"  !CDS_PN = "BR43";
"VSS548":   PN = "BR45"  !CDS_PN = "BR45";
"VSS549":   PN = "BR48"  !CDS_PN = "BR48";
"VSS550":   PN = "BR50"  !CDS_PN = "BR50";
"VSS551":   PN = "BR52"  !CDS_PN = "BR52";
"VSS552":   PN = "BR54"  !CDS_PN = "BR54";
"VSS555":   PN = "BR56"  !CDS_PN = "BR56";
"VSS556":   PN = "BR58"  !CDS_PN = "BR58";
"VSS557":   PN = "BR64"  !CDS_PN = "BR64";
"VSS559":   PN = "BR66"  !CDS_PN = "BR66";
"VSS560":   PN = "BR68"  !CDS_PN = "BR68";
"VSS561":   PN = "BR70"  !CDS_PN = "BR70";
"VSS563":   PN = "BR72"  !CDS_PN = "BR72";
"VSS564":   PN = "BR74"  !CDS_PN = "BR74";
"VSS565":   PN = "BR76"  !CDS_PN = "BR76";
"VSS566":   PN = "BR80"  !CDS_PN = "BR80";
"VSS567":   PN = "BR82"  !CDS_PN = "BR82";
"VSS568":   PN = "BR84"  !CDS_PN = "BR84";
"VSS569":   PN = "BR86"  !CDS_PN = "BR86";
"VSS570":   PN = "BR88"  !CDS_PN = "BR88";
"VSS573":   PN = "BR90"  !CDS_PN = "BR90";
"VSS574":   PN = "BT12"  !CDS_PN = "BT12";
"VSS575":   PN = "BT16"  !CDS_PN = "BT16";
"VSS576":   PN = "BT20"  !CDS_PN = "BT20";
"VSS577":   PN = "BT4"  !CDS_PN = "BT4";
"VSS578":   PN = "BT8"  !CDS_PN = "BT8";
"VSS579":   PN = "BU15"  !CDS_PN = "BU15";
"VSS580":   PN = "BU19"  !CDS_PN = "BU19";
"VSS581":   PN = "BU21"  !CDS_PN = "BU21";
"VSS582":   PN = "BU23"  !CDS_PN = "BU23";
"VSS584":   PN = "BU25"  !CDS_PN = "BU25";
"VSS585":   PN = "BU31"  !CDS_PN = "BU31";
"VSS586":   PN = "BU7"  !CDS_PN = "BU7";
"VSS587":   PN = "BV12"  !CDS_PN = "BV12";
"VSS588":   PN = "BV16"  !CDS_PN = "BV16";
"VSS589":   PN = "BV18"  !CDS_PN = "BV18";
"VSS590":   PN = "BV2"  !CDS_PN = "BV2";
"VSS591":   PN = "BV20"  !CDS_PN = "BV20";
"VSS592":   PN = "BV4"  !CDS_PN = "BV4";
"VSS593":   PN = "BV6"  !CDS_PN = "BV6";
"VSS594":   PN = "BV8"  !CDS_PN = "BV8";
"VSS596":   PN = "BW13"  !CDS_PN = "BW13";
"VSS597":   PN = "BW17"  !CDS_PN = "BW17";
"VSS598":   PN = "BW27"  !CDS_PN = "BW27";
"VSS599":   PN = "BW29"  !CDS_PN = "BW29";
"VSS600":   PN = "BW3"  !CDS_PN = "BW3";
"VSS601":   PN = "BW31"  !CDS_PN = "BW31";
"VSS602":   PN = "BW5"  !CDS_PN = "BW5";
"VSS603":   PN = "BW9"  !CDS_PN = "BW9";
"VSS604":   PN = "BY12"  !CDS_PN = "BY12";
"VSS605":   PN = "BY16"  !CDS_PN = "BY16";
"VSS606":   PN = "BY20"  !CDS_PN = "BY20";
"VSS607":   PN = "BY4"  !CDS_PN = "BY4";
"VSS608":   PN = "BY8"  !CDS_PN = "BY8";
"VSS620":   PN = "CA3"  !CDS_PN = "CA3";
"VSS621":   PN = "CA31"  !CDS_PN = "CA31";
"VSS622":   PN = "CB12"  !CDS_PN = "CB12";
"VSS623":   PN = "CB16"  !CDS_PN = "CB16";
"VSS624":   PN = "CB20"  !CDS_PN = "CB20";
"VSS625":   PN = "CB22"  !CDS_PN = "CB22";
"VSS626":   PN = "CB24"  !CDS_PN = "CB24";
"VSS627":   PN = "CB26"  !CDS_PN = "CB26";
"VSS628":   PN = "CB28"  !CDS_PN = "CB28";
"VSS629":   PN = "CB32"  !CDS_PN = "CB32";
"VSS630":   PN = "CB34"  !CDS_PN = "CB34";
"VSS631":   PN = "CB36"  !CDS_PN = "CB36";
"VSS632":   PN = "CB38"  !CDS_PN = "CB38";
"VSS633":   PN = "CB4"  !CDS_PN = "CB4";
"VSS634":   PN = "CB40"  !CDS_PN = "CB40";
"VSS635":   PN = "CB42"  !CDS_PN = "CB42";
"VSS636":   PN = "CB44"  !CDS_PN = "CB44";
"VSS637":   PN = "CB47"  !CDS_PN = "CB47";
"VSS638":   PN = "CB49"  !CDS_PN = "CB49";
"VSS639":   PN = "CB51"  !CDS_PN = "CB51";
"VSS640":   PN = "CB53"  !CDS_PN = "CB53";
"VSS641":   PN = "CB55"  !CDS_PN = "CB55";
"VSS642":   PN = "CB57"  !CDS_PN = "CB57";
"VSS643":   PN = "CB59"  !CDS_PN = "CB59";
"VSS644":   PN = "CB63"  !CDS_PN = "CB63";
"VSS645":   PN = "CB65"  !CDS_PN = "CB65";
"VSS646":   PN = "CB67"  !CDS_PN = "CB67";
"VSS647":   PN = "CB69"  !CDS_PN = "CB69";
"VSS648":   PN = "CB71"  !CDS_PN = "CB71";
"VSS649":   PN = "CB73"  !CDS_PN = "CB73";
"VSS650":   PN = "CB79"  !CDS_PN = "CB79";
"VSS651":   PN = "CB8"  !CDS_PN = "CB8";
"VSS652":   PN = "CB81"  !CDS_PN = "CB81";
"VSS653":   PN = "CB83"  !CDS_PN = "CB83";
"VSS654":   PN = "CB85"  !CDS_PN = "CB85";
"VSS655":   PN = "CB87"  !CDS_PN = "CB87";
"VSS656":   PN = "CB89"  !CDS_PN = "CB89";
"VSS660":   PN = "CC13"  !CDS_PN = "CC13";
"VSS661":   PN = "CC17"  !CDS_PN = "CC17";
"VSS664":   PN = "CC31"  !CDS_PN = "CC31";
"VSS665":   PN = "CC5"  !CDS_PN = "CC5";
"VSS666":   PN = "CC62"  !CDS_PN = "CC62";
"VSS667":   PN = "CC70"  !CDS_PN = "CC70";
"VSS668":   PN = "CC72"  !CDS_PN = "CC72";
"VSS669":   PN = "CC74"  !CDS_PN = "CC74";
"VSS670":   PN = "CC9"  !CDS_PN = "CC9";
"VSS671":   PN = "CD12"  !CDS_PN = "CD12";
"VSS672":   PN = "CD16"  !CDS_PN = "CD16";
"VSS673":   PN = "CD20"  !CDS_PN = "CD20";
"VSS674":   PN = "CD4"  !CDS_PN = "CD4";
"VSS675":   PN = "CD61"  !CDS_PN = "CD61";
"VSS676":   PN = "CD75"  !CDS_PN = "CD75";
"VSS677":   PN = "CD77"  !CDS_PN = "CD77";
"VSS678":   PN = "CD8"  !CDS_PN = "CD8";
"VSS680":   PN = "CE3"  !CDS_PN = "CE3";
"VSS681":   PN = "CE60"  !CDS_PN = "CE60";
"VSS682":   PN = "CE66"  !CDS_PN = "CE66";
"VSS683":   PN = "CE72"  !CDS_PN = "CE72";
"VSS684":   PN = "CE76"  !CDS_PN = "CE76";
"VSS685":   PN = "CE78"  !CDS_PN = "CE78";
"VSS686":   PN = "CF12"  !CDS_PN = "CF12";
"VSS687":   PN = "CF16"  !CDS_PN = "CF16";
"VSS688":   PN = "CF20"  !CDS_PN = "CF20";
"VSS689":   PN = "CF4"  !CDS_PN = "CF4";
"VSS691":   PN = "CF69"  !CDS_PN = "CF69";
"VSS692":   PN = "CF71"  !CDS_PN = "CF71";
"VSS693":   PN = "CF8"  !CDS_PN = "CF8";
"VSS694":   PN = "CG1"  !CDS_PN = "CG1";
"VSS695":   PN = "CG13"  !CDS_PN = "CG13";
"VSS696":   PN = "CG17"  !CDS_PN = "CG17";
"VSS697":   PN = "CG21"  !CDS_PN = "CG21";
"VSS698":   PN = "CG23"  !CDS_PN = "CG23";
"VSS701":   PN = "CG25"  !CDS_PN = "CG25";
"VSS703":   PN = "CG5"  !CDS_PN = "CG5";
"VSS704":   PN = "CG62"  !CDS_PN = "CG62";
"VSS706":   PN = "CG64"  !CDS_PN = "CG64";
"VSS707":   PN = "CG70"  !CDS_PN = "CG70";
"VSS708":   PN = "CG72"  !CDS_PN = "CG72";
"VSS710":   PN = "CG74"  !CDS_PN = "CG74";
"VSS713":   PN = "CG78"  !CDS_PN = "CG78";
"VSS716":   PN = "CG9"  !CDS_PN = "CG9";
"VSS718":   PN = "CH12"  !CDS_PN = "CH12";
"VSS720":   PN = "CH16"  !CDS_PN = "CH16";
"VSS721":   PN = "CH20"  !CDS_PN = "CH20";
"VSS722":   PN = "CH4"  !CDS_PN = "CH4";
"VSS727":   PN = "CH67"  !CDS_PN = "CH67";
"VSS728":   PN = "CH73"  !CDS_PN = "CH73";
"VSS729":   PN = "CH79"  !CDS_PN = "CH79";
"VSS730":   PN = "CH8"  !CDS_PN = "CH8";
"VSS731":   PN = "CH83"  !CDS_PN = "CH83";
"VSS732":   PN = "CH85"  !CDS_PN = "CH85";
"VSS733":   PN = "CH87"  !CDS_PN = "CH87";
"VSS734":   PN = "CH89"  !CDS_PN = "CH89";
"VSS736":   PN = "CJ60"  !CDS_PN = "CJ60";
"VSS737":   PN = "CJ80"  !CDS_PN = "CJ80";
"VSS740":   PN = "CK12"  !CDS_PN = "CK12";
"VSS741":   PN = "CK16"  !CDS_PN = "CK16";
"VSS742":   PN = "CK20"  !CDS_PN = "CK20";
"VSS743":   PN = "CK26"  !CDS_PN = "CK26";
"VSS746":   PN = "CK8"  !CDS_PN = "CK8";
DRAWING = "@s9s_mb_2u_lib.s9s_mb_2u(sch_1):page41";
BODY = "SOCKET4677_AZIF0045P001C01CS","I9": LOCATION = "U2" #&CDS_LOCATION = "U2" &SEC = "37" #&CDS_SEC = "37";
"VSS0":   PN = "BR5"  !CDS_PN = "BR5";
"VSS356":   PN = "AW21"  !CDS_PN = "AW21";
"VSS357":   PN = "AW23"  !CDS_PN = "AW23";
"VSS358":   PN = "AW25"  !CDS_PN = "AW25";
"VSS360":   PN = "AW62"  !CDS_PN = "AW62";
"VSS361":   PN = "AW66"  !CDS_PN = "AW66";
"VSS362":   PN = "AW68"  !CDS_PN = "AW68";
"VSS363":   PN = "AW72"  !CDS_PN = "AW72";
"VSS364":   PN = "AW80"  !CDS_PN = "AW80";
"VSS365":   PN = "AW82"  !CDS_PN = "AW82";
"VSS366":   PN = "AW84"  !CDS_PN = "AW84";
"VSS367":   PN = "AW88"  !CDS_PN = "AW88";
"VSS369":   PN = "AY12"  !CDS_PN = "AY12";
"VSS370":   PN = "AY16"  !CDS_PN = "AY16";
"VSS371":   PN = "AY4"  !CDS_PN = "AY4";
"VSS372":   PN = "AY71"  !CDS_PN = "AY71";
"VSS373":   PN = "AY77"  !CDS_PN = "AY77";
"VSS374":   PN = "AY79"  !CDS_PN = "AY79";
"VSS375":   PN = "AY8"  !CDS_PN = "AY8";
"VSS376":   PN = "AY81"  !CDS_PN = "AY81";
"VSS377":   PN = "AY83"  !CDS_PN = "AY83";
"VSS393":   PN = "BA17"  !CDS_PN = "BA17";
"VSS394":   PN = "BA60"  !CDS_PN = "BA60";
"VSS395":   PN = "BA64"  !CDS_PN = "BA64";
"VSS397":   PN = "BA74"  !CDS_PN = "BA74";
"VSS398":   PN = "BA84"  !CDS_PN = "BA84";
"VSS399":   PN = "BA88"  !CDS_PN = "BA88";
"VSS400":   PN = "BB10"  !CDS_PN = "BB10";
"VSS401":   PN = "BB12"  !CDS_PN = "BB12";
"VSS402":   PN = "BB16"  !CDS_PN = "BB16";
"VSS403":   PN = "BB20"  !CDS_PN = "BB20";
"VSS404":   PN = "BB22"  !CDS_PN = "BB22";
"VSS405":   PN = "BB24"  !CDS_PN = "BB24";
"VSS406":   PN = "BB26"  !CDS_PN = "BB26";
"VSS407":   PN = "BB4"  !CDS_PN = "BB4";
"VSS408":   PN = "BB63"  !CDS_PN = "BB63";
"VSS409":   PN = "BB69"  !CDS_PN = "BB69";
"VSS410":   PN = "BB71"  !CDS_PN = "BB71";
"VSS411":   PN = "BB77"  !CDS_PN = "BB77";
"VSS412":   PN = "BB79"  !CDS_PN = "BB79";
"VSS413":   PN = "BB8"  !CDS_PN = "BB8";
"VSS414":   PN = "BB83"  !CDS_PN = "BB83";
"VSS415":   PN = "BB87"  !CDS_PN = "BB87";
"VSS416":   PN = "BB91"  !CDS_PN = "BB91";
"VSS417":   PN = "BC1"  !CDS_PN = "BC1";
"VSS418":   PN = "BC13"  !CDS_PN = "BC13";
"VSS419":   PN = "BC17"  !CDS_PN = "BC17";
"VSS420":   PN = "BC5"  !CDS_PN = "BC5";
"VSS421":   PN = "BC62"  !CDS_PN = "BC62";
"VSS422":   PN = "BC66"  !CDS_PN = "BC66";
"VSS423":   PN = "BC72"  !CDS_PN = "BC72";
"VSS424":   PN = "BC76"  !CDS_PN = "BC76";
"VSS425":   PN = "BC78"  !CDS_PN = "BC78";
"VSS426":   PN = "BC84"  !CDS_PN = "BC84";
"VSS427":   PN = "BC86"  !CDS_PN = "BC86";
"VSS428":   PN = "BC88"  !CDS_PN = "BC88";
"VSS429":   PN = "BC9"  !CDS_PN = "BC9";
"VSS430":   PN = "BD12"  !CDS_PN = "BD12";
"VSS431":   PN = "BD16"  !CDS_PN = "BD16";
"VSS432":   PN = "BD20"  !CDS_PN = "BD20";
"VSS433":   PN = "BD4"  !CDS_PN = "BD4";
"VSS434":   PN = "BD8"  !CDS_PN = "BD8";
"VSS435":   PN = "BD81"  !CDS_PN = "BD81";
"VSS437":   PN = "BD85"  !CDS_PN = "BD85";
"VSS439":   PN = "BD89"  !CDS_PN = "BD89";
"VSS440":   PN = "BE64"  !CDS_PN = "BE64";
"VSS441":   PN = "BE66"  !CDS_PN = "BE66";
"VSS442":   PN = "BE68"  !CDS_PN = "BE68";
"VSS443":   PN = "BE74"  !CDS_PN = "BE74";
"VSS444":   PN = "BE76"  !CDS_PN = "BE76";
"VSS445":   PN = "BE78"  !CDS_PN = "BE78";
"VSS446":   PN = "BE84"  !CDS_PN = "BE84";
"VSS447":   PN = "BF12"  !CDS_PN = "BF12";
"VSS448":   PN = "BF16"  !CDS_PN = "BF16";
"VSS449":   PN = "BF20"  !CDS_PN = "BF20";
"VSS450":   PN = "BF4"  !CDS_PN = "BF4";
"VSS451":   PN = "BF61"  !CDS_PN = "BF61";
"VSS452":   PN = "BF63"  !CDS_PN = "BF63";
"VSS453":   PN = "BF73"  !CDS_PN = "BF73";
"VSS454":   PN = "BF75"  !CDS_PN = "BF75";
"VSS455":   PN = "BF79"  !CDS_PN = "BF79";
"VSS456":   PN = "BF8"  !CDS_PN = "BF8";
"VSS457":   PN = "BF83"  !CDS_PN = "BF83";
"VSS458":   PN = "BG1"  !CDS_PN = "BG1";
"VSS459":   PN = "BG13"  !CDS_PN = "BG13";
"VSS460":   PN = "BG17"  !CDS_PN = "BG17";
"VSS461":   PN = "BG21"  !CDS_PN = "BG21";
"VSS462":   PN = "BG23"  !CDS_PN = "BG23";
"VSS463":   PN = "BG25"  !CDS_PN = "BG25";
"VSS464":   PN = "BG5"  !CDS_PN = "BG5";
"VSS465":   PN = "BG70"  !CDS_PN = "BG70";
"VSS466":   PN = "BG9"  !CDS_PN = "BG9";
"VSS467":   PN = "BH12"  !CDS_PN = "BH12";
"VSS468":   PN = "BH16"  !CDS_PN = "BH16";
"VSS469":   PN = "BH20"  !CDS_PN = "BH20";
"VSS470":   PN = "BH4"  !CDS_PN = "BH4";
"VSS472":   PN = "BH67"  !CDS_PN = "BH67";
"VSS473":   PN = "BH73"  !CDS_PN = "BH73";
"VSS474":   PN = "BH77"  !CDS_PN = "BH77";
"VSS475":   PN = "BH8"  !CDS_PN = "BH8";
"VSS476":   PN = "BH81"  !CDS_PN = "BH81";
"VSS477":   PN = "BH83"  !CDS_PN = "BH83";
"VSS479":   PN = "BJ62"  !CDS_PN = "BJ62";
"VSS480":   PN = "BJ68"  !CDS_PN = "BJ68";
"VSS481":   PN = "BJ80"  !CDS_PN = "BJ80";
"VSS482":   PN = "BJ82"  !CDS_PN = "BJ82";
"VSS483":   PN = "BJ84"  !CDS_PN = "BJ84";
"VSS484":   PN = "BJ86"  !CDS_PN = "BJ86";
"VSS485":   PN = "BJ88"  !CDS_PN = "BJ88";
"VSS486":   PN = "BJ90"  !CDS_PN = "BJ90";
"VSS487":   PN = "BK12"  !CDS_PN = "BK12";
"VSS488":   PN = "BK16"  !CDS_PN = "BK16";
"VSS489":   PN = "BK20"  !CDS_PN = "BK20";
"VSS490":   PN = "BK4"  !CDS_PN = "BK4";
"VSS491":   PN = "BK65"  !CDS_PN = "BK65";
"VSS492":   PN = "BK71"  !CDS_PN = "BK71";
"VSS494":   PN = "BK75"  !CDS_PN = "BK75";
"VSS495":   PN = "BK79"  !CDS_PN = "BK79";
"VSS496":   PN = "BK8"  !CDS_PN = "BK8";
"VSS497":   PN = "BL1"  !CDS_PN = "BL1";
"VSS498":   PN = "BL13"  !CDS_PN = "BL13";
"VSS499":   PN = "BL17"  !CDS_PN = "BL17";
"VSS500":   PN = "BL5"  !CDS_PN = "BL5";
"VSS501":   PN = "BL68"  !CDS_PN = "BL68";
"VSS502":   PN = "BL70"  !CDS_PN = "BL70";
"VSS503":   PN = "BL72"  !CDS_PN = "BL72";
"VSS504":   PN = "BL78"  !CDS_PN = "BL78";
"VSS505":   PN = "BL9"  !CDS_PN = "BL9";
"VSS506":   PN = "BM12"  !CDS_PN = "BM12";
"VSS507":   PN = "BM16"  !CDS_PN = "BM16";
"VSS508":   PN = "BM20"  !CDS_PN = "BM20";
"VSS509":   PN = "BM22"  !CDS_PN = "BM22";
"VSS510":   PN = "BM24"  !CDS_PN = "BM24";
"VSS511":   PN = "BM26"  !CDS_PN = "BM26";
"VSS512":   PN = "BM4"  !CDS_PN = "BM4";
"VSS513":   PN = "BM61"  !CDS_PN = "BM61";
"VSS515":   PN = "BM73"  !CDS_PN = "BM73";
"VSS516":   PN = "BM77"  !CDS_PN = "BM77";
"VSS517":   PN = "BM8"  !CDS_PN = "BM8";
"VSS518":   PN = "BN31"  !CDS_PN = "BN31";
"VSS519":   PN = "BN62"  !CDS_PN = "BN62";
"VSS520":   PN = "BN70"  !CDS_PN = "BN70";
"VSS522":   PN = "BP12"  !CDS_PN = "BP12";
"VSS523":   PN = "BP16"  !CDS_PN = "BP16";
"VSS524":   PN = "BP2"  !CDS_PN = "BP2";
"VSS525":   PN = "BP20"  !CDS_PN = "BP20";
"VSS527":   PN = "BP4"  !CDS_PN = "BP4";
"VSS528":   PN = "BP63"  !CDS_PN = "BP63";
"VSS529":   PN = "BP71"  !CDS_PN = "BP71";
"VSS530":   PN = "BP73"  !CDS_PN = "BP73";
"VSS531":   PN = "BP75"  !CDS_PN = "BP75";
"VSS532":   PN = "BP77"  !CDS_PN = "BP77";
"VSS533":   PN = "BP8"  !CDS_PN = "BP8";
"VSS535":   PN = "BR13"  !CDS_PN = "BR13";
"VSS536":   PN = "BR17"  !CDS_PN = "BR17";
"VSS538":   PN = "BR27"  !CDS_PN = "BR27";
"VSS539":   PN = "BR29"  !CDS_PN = "BR29";
"VSS540":   PN = "BR31"  !CDS_PN = "BR31";
"VSS541":   PN = "BR33"  !CDS_PN = "BR33";
"VSS572":   PN = "BR9"  !CDS_PN = "BR9";
BODY = "SOCKET4677_AZIF0045P001C01CS","I10": LOCATION = "U2" #&CDS_LOCATION = "U2" &SEC = "38" #&CDS_SEC = "38";
"VSS198":   PN = "AK12"  !CDS_PN = "AK12";
"VSS199":   PN = "AK16"  !CDS_PN = "AK16";
"VSS200":   PN = "AK18"  !CDS_PN = "AK18";
"VSS201":   PN = "AK24"  !CDS_PN = "AK24";
"VSS202":   PN = "AK30"  !CDS_PN = "AK30";
"VSS203":   PN = "AK36"  !CDS_PN = "AK36";
"VSS204":   PN = "AK4"  !CDS_PN = "AK4";
"VSS205":   PN = "AK42"  !CDS_PN = "AK42";
"VSS206":   PN = "AK49"  !CDS_PN = "AK49";
"VSS207":   PN = "AK55"  !CDS_PN = "AK55";
"VSS208":   PN = "AK61"  !CDS_PN = "AK61";
"VSS209":   PN = "AK67"  !CDS_PN = "AK67";
"VSS210":   PN = "AK73"  !CDS_PN = "AK73";
"VSS211":   PN = "AK79"  !CDS_PN = "AK79";
"VSS212":   PN = "AK8"  !CDS_PN = "AK8";
"VSS213":   PN = "AK81"  !CDS_PN = "AK81";
"VSS214":   PN = "AK83"  !CDS_PN = "AK83";
"VSS215":   PN = "AK87"  !CDS_PN = "AK87";
"VSS216":   PN = "AK91"  !CDS_PN = "AK91";
"VSS217":   PN = "AL1"  !CDS_PN = "AL1";
"VSS218":   PN = "AL13"  !CDS_PN = "AL13";
"VSS219":   PN = "AL17"  !CDS_PN = "AL17";
"VSS220":   PN = "AL5"  !CDS_PN = "AL5";
"VSS221":   PN = "AL52"  !CDS_PN = "AL52";
"VSS222":   PN = "AL80"  !CDS_PN = "AL80";
"VSS223":   PN = "AL82"  !CDS_PN = "AL82";
"VSS224":   PN = "AL84"  !CDS_PN = "AL84";
"VSS225":   PN = "AL88"  !CDS_PN = "AL88";
"VSS226":   PN = "AL9"  !CDS_PN = "AL9";
"VSS227":   PN = "AM12"  !CDS_PN = "AM12";
"VSS228":   PN = "AM16"  !CDS_PN = "AM16";
"VSS229":   PN = "AM18"  !CDS_PN = "AM18";
"VSS230":   PN = "AM20"  !CDS_PN = "AM20";
"VSS231":   PN = "AM22"  !CDS_PN = "AM22";
"VSS232":   PN = "AM24"  !CDS_PN = "AM24";
"VSS233":   PN = "AM26"  !CDS_PN = "AM26";
"VSS234":   PN = "AM28"  !CDS_PN = "AM28";
"VSS235":   PN = "AM30"  !CDS_PN = "AM30";
"VSS236":   PN = "AM32"  !CDS_PN = "AM32";
"VSS237":   PN = "AM34"  !CDS_PN = "AM34";
"VSS238":   PN = "AM36"  !CDS_PN = "AM36";
"VSS239":   PN = "AM38"  !CDS_PN = "AM38";
"VSS240":   PN = "AM4"  !CDS_PN = "AM4";
"VSS241":   PN = "AM40"  !CDS_PN = "AM40";
"VSS242":   PN = "AM42"  !CDS_PN = "AM42";
"VSS243":   PN = "AM44"  !CDS_PN = "AM44";
"VSS244":   PN = "AM47"  !CDS_PN = "AM47";
"VSS245":   PN = "AM49"  !CDS_PN = "AM49";
"VSS246":   PN = "AM51"  !CDS_PN = "AM51";
"VSS247":   PN = "AM53"  !CDS_PN = "AM53";
"VSS248":   PN = "AM55"  !CDS_PN = "AM55";
"VSS249":   PN = "AM57"  !CDS_PN = "AM57";
"VSS250":   PN = "AM59"  !CDS_PN = "AM59";
"VSS251":   PN = "AM61"  !CDS_PN = "AM61";
"VSS252":   PN = "AM63"  !CDS_PN = "AM63";
"VSS253":   PN = "AM65"  !CDS_PN = "AM65";
"VSS254":   PN = "AM67"  !CDS_PN = "AM67";
"VSS255":   PN = "AM69"  !CDS_PN = "AM69";
"VSS256":   PN = "AM71"  !CDS_PN = "AM71";
"VSS257":   PN = "AM73"  !CDS_PN = "AM73";
"VSS258":   PN = "AM75"  !CDS_PN = "AM75";
"VSS259":   PN = "AM77"  !CDS_PN = "AM77";
"VSS260":   PN = "AM8"  !CDS_PN = "AM8";
"VSS261":   PN = "AN52"  !CDS_PN = "AN52";
"VSS262":   PN = "AN84"  !CDS_PN = "AN84";
"VSS263":   PN = "AN88"  !CDS_PN = "AN88";
"VSS264":   PN = "AP12"  !CDS_PN = "AP12";
"VSS265":   PN = "AP16"  !CDS_PN = "AP16";
"VSS266":   PN = "AP18"  !CDS_PN = "AP18";
"VSS267":   PN = "AP24"  !CDS_PN = "AP24";
"VSS268":   PN = "AP30"  !CDS_PN = "AP30";
"VSS269":   PN = "AP36"  !CDS_PN = "AP36";
"VSS270":   PN = "AP4"  !CDS_PN = "AP4";
"VSS271":   PN = "AP42"  !CDS_PN = "AP42";
"VSS272":   PN = "AP49"  !CDS_PN = "AP49";
"VSS273":   PN = "AP55"  !CDS_PN = "AP55";
"VSS274":   PN = "AP61"  !CDS_PN = "AP61";
"VSS275":   PN = "AP67"  !CDS_PN = "AP67";
"VSS276":   PN = "AP73"  !CDS_PN = "AP73";
"VSS277":   PN = "AP79"  !CDS_PN = "AP79";
"VSS278":   PN = "AP8"  !CDS_PN = "AP8";
"VSS279":   PN = "AP83"  !CDS_PN = "AP83";
"VSS280":   PN = "AP87"  !CDS_PN = "AP87";
"VSS281":   PN = "AP91"  !CDS_PN = "AP91";
"VSS282":   PN = "AR1"  !CDS_PN = "AR1";
"VSS283":   PN = "AR13"  !CDS_PN = "AR13";
"VSS284":   PN = "AR19"  !CDS_PN = "AR19";
"VSS285":   PN = "AR23"  !CDS_PN = "AR23";
"VSS286":   PN = "AR25"  !CDS_PN = "AR25";
"VSS287":   PN = "AR29"  !CDS_PN = "AR29";
"VSS288":   PN = "AR31"  !CDS_PN = "AR31";
"VSS289":   PN = "AR35"  !CDS_PN = "AR35";
"VSS290":   PN = "AR37"  !CDS_PN = "AR37";
"VSS291":   PN = "AR41"  !CDS_PN = "AR41";
"VSS292":   PN = "AR43"  !CDS_PN = "AR43";
"VSS293":   PN = "AR48"  !CDS_PN = "AR48";
"VSS294":   PN = "AR5"  !CDS_PN = "AR5";
"VSS295":   PN = "AR50"  !CDS_PN = "AR50";
"VSS296":   PN = "AR54"  !CDS_PN = "AR54";
"VSS297":   PN = "AR56"  !CDS_PN = "AR56";
"VSS298":   PN = "AR60"  !CDS_PN = "AR60";
"VSS299":   PN = "AR62"  !CDS_PN = "AR62";
"VSS300":   PN = "AR66"  !CDS_PN = "AR66";
"VSS301":   PN = "AR68"  !CDS_PN = "AR68";
"VSS302":   PN = "AR72"  !CDS_PN = "AR72";
"VSS303":   PN = "AR74"  !CDS_PN = "AR74";
"VSS304":   PN = "AR78"  !CDS_PN = "AR78";
"VSS305":   PN = "AR82"  !CDS_PN = "AR82";
"VSS306":   PN = "AR84"  !CDS_PN = "AR84";
"VSS307":   PN = "AR88"  !CDS_PN = "AR88";
"VSS308":   PN = "AR9"  !CDS_PN = "AR9";
"VSS309":   PN = "AT12"  !CDS_PN = "AT12";
"VSS310":   PN = "AT16"  !CDS_PN = "AT16";
"VSS311":   PN = "AT20"  !CDS_PN = "AT20";
"VSS312":   PN = "AT22"  !CDS_PN = "AT22";
"VSS313":   PN = "AT26"  !CDS_PN = "AT26";
"VSS314":   PN = "AT28"  !CDS_PN = "AT28";
"VSS315":   PN = "AT32"  !CDS_PN = "AT32";
"VSS316":   PN = "AT34"  !CDS_PN = "AT34";
"VSS317":   PN = "AT38"  !CDS_PN = "AT38";
"VSS318":   PN = "AT4"  !CDS_PN = "AT4";
"VSS319":   PN = "AT40"  !CDS_PN = "AT40";
"VSS320":   PN = "AT44"  !CDS_PN = "AT44";
"VSS321":   PN = "AT51"  !CDS_PN = "AT51";
"VSS322":   PN = "AT53"  !CDS_PN = "AT53";
"VSS323":   PN = "AT57"  !CDS_PN = "AT57";
"VSS324":   PN = "AT59"  !CDS_PN = "AT59";
"VSS325":   PN = "AT63"  !CDS_PN = "AT63";
"VSS326":   PN = "AT65"  !CDS_PN = "AT65";
"VSS327":   PN = "AT69"  !CDS_PN = "AT69";
"VSS328":   PN = "AT71"  !CDS_PN = "AT71";
"VSS329":   PN = "AT75"  !CDS_PN = "AT75";
"VSS330":   PN = "AT77"  !CDS_PN = "AT77";
"VSS331":   PN = "AT79"  !CDS_PN = "AT79";
"VSS332":   PN = "AT8"  !CDS_PN = "AT8";
"VSS333":   PN = "AU27"  !CDS_PN = "AU27";
"VSS334":   PN = "AU31"  !CDS_PN = "AU31";
"VSS335":   PN = "AU37"  !CDS_PN = "AU37";
"VSS336":   PN = "AU39"  !CDS_PN = "AU39";
"VSS337":   PN = "AU41"  !CDS_PN = "AU41";
"VSS338":   PN = "AU45"  !CDS_PN = "AU45";
"VSS339":   PN = "AU48"  !CDS_PN = "AU48";
"VSS340":   PN = "AU70"  !CDS_PN = "AU70";
"VSS341":   PN = "AU72"  !CDS_PN = "AU72";
"VSS342":   PN = "AU74"  !CDS_PN = "AU74";
"VSS343":   PN = "AU76"  !CDS_PN = "AU76";
"VSS344":   PN = "AU80"  !CDS_PN = "AU80";
"VSS345":   PN = "AU84"  !CDS_PN = "AU84";
"VSS346":   PN = "AU88"  !CDS_PN = "AU88";
"VSS347":   PN = "AV12"  !CDS_PN = "AV12";
"VSS348":   PN = "AV16"  !CDS_PN = "AV16";
"VSS349":   PN = "AV4"  !CDS_PN = "AV4";
"VSS350":   PN = "AV77"  !CDS_PN = "AV77";
"VSS351":   PN = "AV8"  !CDS_PN = "AV8";
"VSS352":   PN = "AV87"  !CDS_PN = "AV87";
"VSS353":   PN = "AV91"  !CDS_PN = "AV91";
"VSS354":   PN = "AW1"  !CDS_PN = "AW1";
"VSS355":   PN = "AW13"  !CDS_PN = "AW13";
"VSS359":   PN = "AW5"  !CDS_PN = "AW5";
"VSS368":   PN = "AW9"  !CDS_PN = "AW9";
BODY = "SOCKET4677_AZIF0045P001C01CS","I11": LOCATION = "U2" #&CDS_LOCATION = "U2" &SEC = "39" #&CDS_SEC = "39";
"VSS38":   PN = "AA82"  !CDS_PN = "AA82";
"VSS39":   PN = "AA84"  !CDS_PN = "AA84";
"VSS40":   PN = "AA88"  !CDS_PN = "AA88";
"VSS41":   PN = "AB12"  !CDS_PN = "AB12";
"VSS42":   PN = "AB16"  !CDS_PN = "AB16";
"VSS43":   PN = "AB20"  !CDS_PN = "AB20";
"VSS44":   PN = "AB22"  !CDS_PN = "AB22";
"VSS45":   PN = "AB26"  !CDS_PN = "AB26";
"VSS46":   PN = "AB28"  !CDS_PN = "AB28";
"VSS47":   PN = "AB32"  !CDS_PN = "AB32";
"VSS48":   PN = "AB34"  !CDS_PN = "AB34";
"VSS49":   PN = "AB38"  !CDS_PN = "AB38";
"VSS50":   PN = "AB4"  !CDS_PN = "AB4";
"VSS51":   PN = "AB40"  !CDS_PN = "AB40";
"VSS52":   PN = "AB44"  !CDS_PN = "AB44";
"VSS53":   PN = "AB47"  !CDS_PN = "AB47";
"VSS54":   PN = "AB51"  !CDS_PN = "AB51";
"VSS55":   PN = "AB53"  !CDS_PN = "AB53";
"VSS56":   PN = "AB57"  !CDS_PN = "AB57";
"VSS57":   PN = "AB59"  !CDS_PN = "AB59";
"VSS58":   PN = "AB63"  !CDS_PN = "AB63";
"VSS59":   PN = "AB65"  !CDS_PN = "AB65";
"VSS60":   PN = "AB69"  !CDS_PN = "AB69";
"VSS61":   PN = "AB71"  !CDS_PN = "AB71";
"VSS62":   PN = "AB75"  !CDS_PN = "AB75";
"VSS63":   PN = "AB77"  !CDS_PN = "AB77";
"VSS64":   PN = "AB79"  !CDS_PN = "AB79";
"VSS65":   PN = "AB8"  !CDS_PN = "AB8";
"VSS66":   PN = "AB81"  !CDS_PN = "AB81";
"VSS67":   PN = "AB83"  !CDS_PN = "AB83";
"VSS68":   PN = "AB87"  !CDS_PN = "AB87";
"VSS69":   PN = "AB91"  !CDS_PN = "AB91";
"VSS70":   PN = "AC1"  !CDS_PN = "AC1";
"VSS71":   PN = "AC13"  !CDS_PN = "AC13";
"VSS72":   PN = "AC21"  !CDS_PN = "AC21";
"VSS73":   PN = "AC27"  !CDS_PN = "AC27";
"VSS74":   PN = "AC33"  !CDS_PN = "AC33";
"VSS75":   PN = "AC39"  !CDS_PN = "AC39";
"VSS76":   PN = "AC45"  !CDS_PN = "AC45";
"VSS77":   PN = "AC5"  !CDS_PN = "AC5";
"VSS78":   PN = "AC52"  !CDS_PN = "AC52";
"VSS79":   PN = "AC58"  !CDS_PN = "AC58";
"VSS80":   PN = "AC64"  !CDS_PN = "AC64";
"VSS81":   PN = "AC70"  !CDS_PN = "AC70";
"VSS82":   PN = "AC76"  !CDS_PN = "AC76";
"VSS83":   PN = "AC84"  !CDS_PN = "AC84";
"VSS84":   PN = "AC88"  !CDS_PN = "AC88";
"VSS85":   PN = "AC9"  !CDS_PN = "AC9";
"VSS86":   PN = "AD12"  !CDS_PN = "AD12";
"VSS87":   PN = "AD16"  !CDS_PN = "AD16";
"VSS88":   PN = "AD4"  !CDS_PN = "AD4";
"VSS89":   PN = "AD42"  !CDS_PN = "AD42";
"VSS90":   PN = "AD79"  !CDS_PN = "AD79";
"VSS91":   PN = "AD8"  !CDS_PN = "AD8";
"VSS92":   PN = "AD83"  !CDS_PN = "AD83";
"VSS93":   PN = "AE17"  !CDS_PN = "AE17";
"VSS94":   PN = "AE19"  !CDS_PN = "AE19";
"VSS95":   PN = "AE21"  !CDS_PN = "AE21";
"VSS96":   PN = "AE23"  !CDS_PN = "AE23";
"VSS97":   PN = "AE25"  !CDS_PN = "AE25";
"VSS98":   PN = "AE27"  !CDS_PN = "AE27";
"VSS99":   PN = "AE29"  !CDS_PN = "AE29";
"VSS100":   PN = "AE31"  !CDS_PN = "AE31";
"VSS101":   PN = "AE33"  !CDS_PN = "AE33";
"VSS102":   PN = "AE35"  !CDS_PN = "AE35";
"VSS103":   PN = "AE37"  !CDS_PN = "AE37";
"VSS104":   PN = "AE39"  !CDS_PN = "AE39";
"VSS105":   PN = "AE41"  !CDS_PN = "AE41";
"VSS106":   PN = "AE43"  !CDS_PN = "AE43";
"VSS107":   PN = "AE45"  !CDS_PN = "AE45";
"VSS108":   PN = "AE48"  !CDS_PN = "AE48";
"VSS109":   PN = "AE50"  !CDS_PN = "AE50";
"VSS110":   PN = "AE52"  !CDS_PN = "AE52";
"VSS111":   PN = "AE54"  !CDS_PN = "AE54";
"VSS112":   PN = "AE56"  !CDS_PN = "AE56";
"VSS113":   PN = "AE58"  !CDS_PN = "AE58";
"VSS114":   PN = "AE60"  !CDS_PN = "AE60";
"VSS115":   PN = "AE62"  !CDS_PN = "AE62";
"VSS116":   PN = "AE64"  !CDS_PN = "AE64";
"VSS117":   PN = "AE66"  !CDS_PN = "AE66";
"VSS118":   PN = "AE68"  !CDS_PN = "AE68";
"VSS119":   PN = "AE70"  !CDS_PN = "AE70";
"VSS120":   PN = "AE72"  !CDS_PN = "AE72";
"VSS121":   PN = "AE74"  !CDS_PN = "AE74";
"VSS122":   PN = "AE76"  !CDS_PN = "AE76";
"VSS123":   PN = "AE78"  !CDS_PN = "AE78";
"VSS124":   PN = "AE84"  !CDS_PN = "AE84";
"VSS125":   PN = "AE88"  !CDS_PN = "AE88";
"VSS126":   PN = "AF12"  !CDS_PN = "AF12";
"VSS127":   PN = "AF16"  !CDS_PN = "AF16";
"VSS128":   PN = "AF4"  !CDS_PN = "AF4";
"VSS129":   PN = "AF42"  !CDS_PN = "AF42";
"VSS130":   PN = "AF8"  !CDS_PN = "AF8";
"VSS131":   PN = "AF81"  !CDS_PN = "AF81";
"VSS132":   PN = "AF87"  !CDS_PN = "AF87";
"VSS133":   PN = "AF91"  !CDS_PN = "AF91";
"VSS134":   PN = "AG1"  !CDS_PN = "AG1";
"VSS135":   PN = "AG13"  !CDS_PN = "AG13";
"VSS136":   PN = "AG21"  !CDS_PN = "AG21";
"VSS137":   PN = "AG27"  !CDS_PN = "AG27";
"VSS138":   PN = "AG33"  !CDS_PN = "AG33";
"VSS139":   PN = "AG39"  !CDS_PN = "AG39";
"VSS140":   PN = "AG45"  !CDS_PN = "AG45";
"VSS141":   PN = "AG5"  !CDS_PN = "AG5";
"VSS142":   PN = "AG52"  !CDS_PN = "AG52";
"VSS143":   PN = "AG58"  !CDS_PN = "AG58";
"VSS144":   PN = "AG64"  !CDS_PN = "AG64";
"VSS145":   PN = "AG70"  !CDS_PN = "AG70";
"VSS146":   PN = "AG76"  !CDS_PN = "AG76";
"VSS147":   PN = "AG84"  !CDS_PN = "AG84";
"VSS148":   PN = "AG88"  !CDS_PN = "AG88";
"VSS149":   PN = "AG9"  !CDS_PN = "AG9";
"VSS150":   PN = "AH12"  !CDS_PN = "AH12";
"VSS151":   PN = "AH16"  !CDS_PN = "AH16";
"VSS152":   PN = "AH20"  !CDS_PN = "AH20";
"VSS153":   PN = "AH22"  !CDS_PN = "AH22";
"VSS154":   PN = "AH26"  !CDS_PN = "AH26";
"VSS155":   PN = "AH28"  !CDS_PN = "AH28";
"VSS156":   PN = "AH32"  !CDS_PN = "AH32";
"VSS157":   PN = "AH34"  !CDS_PN = "AH34";
"VSS158":   PN = "AH38"  !CDS_PN = "AH38";
"VSS159":   PN = "AH4"  !CDS_PN = "AH4";
"VSS160":   PN = "AH40"  !CDS_PN = "AH40";
"VSS161":   PN = "AH44"  !CDS_PN = "AH44";
"VSS162":   PN = "AH47"  !CDS_PN = "AH47";
"VSS163":   PN = "AH51"  !CDS_PN = "AH51";
"VSS164":   PN = "AH53"  !CDS_PN = "AH53";
"VSS165":   PN = "AH57"  !CDS_PN = "AH57";
"VSS166":   PN = "AH59"  !CDS_PN = "AH59";
"VSS167":   PN = "AH63"  !CDS_PN = "AH63";
"VSS168":   PN = "AH65"  !CDS_PN = "AH65";
"VSS169":   PN = "AH69"  !CDS_PN = "AH69";
"VSS170":   PN = "AH71"  !CDS_PN = "AH71";
"VSS171":   PN = "AH75"  !CDS_PN = "AH75";
"VSS172":   PN = "AH77"  !CDS_PN = "AH77";
"VSS173":   PN = "AH79"  !CDS_PN = "AH79";
"VSS174":   PN = "AH8"  !CDS_PN = "AH8";
"VSS175":   PN = "AH83"  !CDS_PN = "AH83";
"VSS176":   PN = "AJ19"  !CDS_PN = "AJ19";
"VSS177":   PN = "AJ23"  !CDS_PN = "AJ23";
"VSS178":   PN = "AJ25"  !CDS_PN = "AJ25";
"VSS179":   PN = "AJ29"  !CDS_PN = "AJ29";
"VSS180":   PN = "AJ31"  !CDS_PN = "AJ31";
"VSS181":   PN = "AJ35"  !CDS_PN = "AJ35";
"VSS182":   PN = "AJ37"  !CDS_PN = "AJ37";
"VSS183":   PN = "AJ41"  !CDS_PN = "AJ41";
"VSS184":   PN = "AJ43"  !CDS_PN = "AJ43";
"VSS185":   PN = "AJ48"  !CDS_PN = "AJ48";
"VSS186":   PN = "AJ50"  !CDS_PN = "AJ50";
"VSS187":   PN = "AJ54"  !CDS_PN = "AJ54";
"VSS188":   PN = "AJ56"  !CDS_PN = "AJ56";
"VSS189":   PN = "AJ60"  !CDS_PN = "AJ60";
"VSS190":   PN = "AJ62"  !CDS_PN = "AJ62";
"VSS191":   PN = "AJ66"  !CDS_PN = "AJ66";
"VSS192":   PN = "AJ68"  !CDS_PN = "AJ68";
"VSS193":   PN = "AJ72"  !CDS_PN = "AJ72";
"VSS194":   PN = "AJ74"  !CDS_PN = "AJ74";
"VSS195":   PN = "AJ78"  !CDS_PN = "AJ78";
"VSS196":   PN = "AJ84"  !CDS_PN = "AJ84";
"VSS197":   PN = "AJ88"  !CDS_PN = "AJ88";
DRAWING = "@s9s_mb_2u_lib.s9s_mb_2u(sch_1):page42";
BODY = "SOCKET4677_AZIF0045P001C01CS","I10": LOCATION = "U2" #&CDS_LOCATION = "U2" &SEC = "40" #&CDS_SEC = "40";
"VSS17":   PN = "AA19"  !CDS_PN = "AA19";
"VSS18":   PN = "AA23"  !CDS_PN = "AA23";
"VSS19":   PN = "AA25"  !CDS_PN = "AA25";
"VSS20":   PN = "AA29"  !CDS_PN = "AA29";
"VSS21":   PN = "AA31"  !CDS_PN = "AA31";
"VSS22":   PN = "AA35"  !CDS_PN = "AA35";
"VSS23":   PN = "AA37"  !CDS_PN = "AA37";
"VSS24":   PN = "AA41"  !CDS_PN = "AA41";
"VSS25":   PN = "AA43"  !CDS_PN = "AA43";
"VSS26":   PN = "AA48"  !CDS_PN = "AA48";
"VSS27":   PN = "AA50"  !CDS_PN = "AA50";
"VSS28":   PN = "AA54"  !CDS_PN = "AA54";
"VSS29":   PN = "AA56"  !CDS_PN = "AA56";
"VSS30":   PN = "AA60"  !CDS_PN = "AA60";
"VSS31":   PN = "AA62"  !CDS_PN = "AA62";
"VSS32":   PN = "AA66"  !CDS_PN = "AA66";
"VSS33":   PN = "AA68"  !CDS_PN = "AA68";
"VSS34":   PN = "AA72"  !CDS_PN = "AA72";
"VSS35":   PN = "AA74"  !CDS_PN = "AA74";
"VSS36":   PN = "AA78"  !CDS_PN = "AA78";
"VSS37":   PN = "AA80"  !CDS_PN = "AA80";
"VSS1690":   PN = "P32"  !CDS_PN = "P32";
"VSS1696":   PN = "N76"  !CDS_PN = "N76";
"VSS1697":   PN = "P51"  !CDS_PN = "P51";
"VSS1698":   PN = "N78"  !CDS_PN = "N78";
"VSS1699":   PN = "P57"  !CDS_PN = "P57";
"VSS1700":   PN = "N80"  !CDS_PN = "N80";
"VSS1701":   PN = "N82"  !CDS_PN = "N82";
"VSS1702":   PN = "N84"  !CDS_PN = "N84";
"VSS1703":   PN = "N88"  !CDS_PN = "N88";
"VSS1704":   PN = "P71"  !CDS_PN = "P71";
"VSS1705":   PN = "P12"  !CDS_PN = "P12";
"VSS1706":   PN = "P16"  !CDS_PN = "P16";
"VSS1707":   PN = "P20"  !CDS_PN = "P20";
"VSS1708":   PN = "P22"  !CDS_PN = "P22";
"VSS1709":   PN = "P26"  !CDS_PN = "P26";
"VSS1710":   PN = "P28"  !CDS_PN = "P28";
"VSS1711":   PN = "R1"  !CDS_PN = "R1";
"VSS1712":   PN = "P34"  !CDS_PN = "P34";
"VSS1713":   PN = "P38"  !CDS_PN = "P38";
"VSS1714":   PN = "R19"  !CDS_PN = "R19";
"VSS1715":   PN = "R23"  !CDS_PN = "R23";
"VSS1716":   PN = "P4"  !CDS_PN = "P4";
"VSS1717":   PN = "P40"  !CDS_PN = "P40";
"VSS1718":   PN = "P44"  !CDS_PN = "P44";
"VSS1719":   PN = "P47"  !CDS_PN = "P47";
"VSS1720":   PN = "P53"  !CDS_PN = "P53";
"VSS1721":   PN = "P59"  !CDS_PN = "P59";
"VSS1722":   PN = "P63"  !CDS_PN = "P63";
"VSS1723":   PN = "R48"  !CDS_PN = "R48";
"VSS1724":   PN = "P65"  !CDS_PN = "P65";
"VSS1725":   PN = "P69"  !CDS_PN = "P69";
"VSS1726":   PN = "P75"  !CDS_PN = "P75";
"VSS1727":   PN = "P77"  !CDS_PN = "P77";
"VSS1728":   PN = "R60"  !CDS_PN = "R60";
"VSS1729":   PN = "P8"  !CDS_PN = "P8";
"VSS1730":   PN = "R66"  !CDS_PN = "R66";
"VSS1731":   PN = "P87"  !CDS_PN = "P87";
"VSS1732":   PN = "P91"  !CDS_PN = "P91";
"VSS1733":   PN = "R13"  !CDS_PN = "R13";
"VSS1734":   PN = "R17"  !CDS_PN = "R17";
"VSS1735":   PN = "R25"  !CDS_PN = "R25";
"VSS1736":   PN = "R29"  !CDS_PN = "R29";
"VSS1737":   PN = "R31"  !CDS_PN = "R31";
"VSS1738":   PN = "R35"  !CDS_PN = "R35";
"VSS1739":   PN = "T12"  !CDS_PN = "T12";
"VSS1740":   PN = "T16"  !CDS_PN = "T16";
"VSS1741":   PN = "T18"  !CDS_PN = "T18";
"VSS1742":   PN = "R37"  !CDS_PN = "R37";
"VSS1743":   PN = "R41"  !CDS_PN = "R41";
"VSS1744":   PN = "R43"  !CDS_PN = "R43";
"VSS1745":   PN = "R5"  !CDS_PN = "R5";
"VSS1746":   PN = "T36"  !CDS_PN = "T36";
"VSS1747":   PN = "R50"  !CDS_PN = "R50";
"VSS1748":   PN = "R54"  !CDS_PN = "R54";
"VSS1749":   PN = "T49"  !CDS_PN = "T49";
"VSS1750":   PN = "T55"  !CDS_PN = "T55";
"VSS1751":   PN = "R56"  !CDS_PN = "R56";
"VSS1752":   PN = "R62"  !CDS_PN = "R62";
"VSS1753":   PN = "R68"  !CDS_PN = "R68";
"VSS1754":   PN = "R72"  !CDS_PN = "R72";
"VSS1755":   PN = "R74"  !CDS_PN = "R74";
"VSS1756":   PN = "R78"  !CDS_PN = "R78";
"VSS1757":   PN = "R84"  !CDS_PN = "R84";
"VSS1758":   PN = "R88"  !CDS_PN = "R88";
"VSS1759":   PN = "R9"  !CDS_PN = "R9";
"VSS1760":   PN = "T24"  !CDS_PN = "T24";
"VSS1761":   PN = "T30"  !CDS_PN = "T30";
"VSS1762":   PN = "T4"  !CDS_PN = "T4";
"VSS1763":   PN = "T42"  !CDS_PN = "T42";
"VSS1764":   PN = "T61"  !CDS_PN = "T61";
"VSS1765":   PN = "T67"  !CDS_PN = "T67";
"VSS1766":   PN = "U52"  !CDS_PN = "U52";
"VSS1767":   PN = "T73"  !CDS_PN = "T73";
"VSS1768":   PN = "T79"  !CDS_PN = "T79";
"VSS1769":   PN = "T8"  !CDS_PN = "T8";
"VSS1770":   PN = "T83"  !CDS_PN = "T83";
"VSS1771":   PN = "U39"  !CDS_PN = "U39";
"VSS1772":   PN = "U82"  !CDS_PN = "U82";
"VSS1773":   PN = "U84"  !CDS_PN = "U84";
"VSS1774":   PN = "U88"  !CDS_PN = "U88";
"VSS1775":   PN = "V12"  !CDS_PN = "V12";
"VSS1776":   PN = "V16"  !CDS_PN = "V16";
"VSS1777":   PN = "V18"  !CDS_PN = "V18";
"VSS1778":   PN = "V20"  !CDS_PN = "V20";
"VSS1779":   PN = "V22"  !CDS_PN = "V22";
"VSS1780":   PN = "V24"  !CDS_PN = "V24";
"VSS1781":   PN = "V26"  !CDS_PN = "V26";
"VSS1782":   PN = "V28"  !CDS_PN = "V28";
"VSS1783":   PN = "V30"  !CDS_PN = "V30";
"VSS1784":   PN = "V32"  !CDS_PN = "V32";
"VSS1785":   PN = "V34"  !CDS_PN = "V34";
"VSS1786":   PN = "V36"  !CDS_PN = "V36";
"VSS1787":   PN = "V38"  !CDS_PN = "V38";
"VSS1788":   PN = "V4"  !CDS_PN = "V4";
"VSS1789":   PN = "V49"  !CDS_PN = "V49";
"VSS1790":   PN = "V40"  !CDS_PN = "V40";
"VSS1791":   PN = "V42"  !CDS_PN = "V42";
"VSS1792":   PN = "V44"  !CDS_PN = "V44";
"VSS1793":   PN = "V47"  !CDS_PN = "V47";
"VSS1794":   PN = "V51"  !CDS_PN = "V51";
"VSS1795":   PN = "V53"  !CDS_PN = "V53";
"VSS1796":   PN = "V55"  !CDS_PN = "V55";
"VSS1797":   PN = "V57"  !CDS_PN = "V57";
"VSS1798":   PN = "V59"  !CDS_PN = "V59";
"VSS1799":   PN = "V61"  !CDS_PN = "V61";
"VSS1800":   PN = "V71"  !CDS_PN = "V71";
"VSS1801":   PN = "V73"  !CDS_PN = "V73";
"VSS1802":   PN = "V63"  !CDS_PN = "V63";
"VSS1803":   PN = "V65"  !CDS_PN = "V65";
"VSS1804":   PN = "V67"  !CDS_PN = "V67";
"VSS1805":   PN = "V69"  !CDS_PN = "V69";
"VSS1806":   PN = "V75"  !CDS_PN = "V75";
"VSS1807":   PN = "V91"  !CDS_PN = "V91";
"VSS1808":   PN = "W1"  !CDS_PN = "W1";
"VSS1809":   PN = "W13"  !CDS_PN = "W13";
"VSS1810":   PN = "V77"  !CDS_PN = "V77";
"VSS1811":   PN = "V79"  !CDS_PN = "V79";
"VSS1812":   PN = "V8"  !CDS_PN = "V8";
"VSS1813":   PN = "V87"  !CDS_PN = "V87";
"VSS1814":   PN = "W5"  !CDS_PN = "W5";
"VSS1815":   PN = "W52"  !CDS_PN = "W52";
"VSS1816":   PN = "W39"  !CDS_PN = "W39";
"VSS1817":   PN = "W84"  !CDS_PN = "W84";
"VSS1818":   PN = "W88"  !CDS_PN = "W88";
"VSS1819":   PN = "W9"  !CDS_PN = "W9";
"VSS1820":   PN = "Y12"  !CDS_PN = "Y12";
"VSS1821":   PN = "Y16"  !CDS_PN = "Y16";
"VSS1822":   PN = "Y18"  !CDS_PN = "Y18";
"VSS1823":   PN = "Y24"  !CDS_PN = "Y24";
"VSS1824":   PN = "Y30"  !CDS_PN = "Y30";
"VSS1825":   PN = "Y36"  !CDS_PN = "Y36";
"VSS1826":   PN = "Y4"  !CDS_PN = "Y4";
"VSS1827":   PN = "Y42"  !CDS_PN = "Y42";
"VSS1828":   PN = "Y61"  !CDS_PN = "Y61";
"VSS1829":   PN = "Y67"  !CDS_PN = "Y67";
"VSS1830":   PN = "Y49"  !CDS_PN = "Y49";
"VSS1831":   PN = "Y55"  !CDS_PN = "Y55";
"VSS1832":   PN = "Y8"  !CDS_PN = "Y8";
"VSS1833":   PN = "Y73"  !CDS_PN = "Y73";
BODY = "SOCKET4677_AZIF0045P001C01CS","I11": LOCATION = "U2" #&CDS_LOCATION = "U2" &SEC = "41" #&CDS_SEC = "41";
"VSS1126":   PN = "E52"  !CDS_PN = "E52";
"VSS1129":   PN = "E74"  !CDS_PN = "E74";
"VSS1131":   PN = "E78"  !CDS_PN = "E78";
"VSS1272":   PN = "E76"  !CDS_PN = "E76";
"VSS1273":   PN = "E86"  !CDS_PN = "E86";
"VSS1494":   PN = "F12"  !CDS_PN = "F12";
"VSS1495":   PN = "F18"  !CDS_PN = "F18";
"VSS1502":   PN = "F42"  !CDS_PN = "F42";
"VSS1504":   PN = "F55"  !CDS_PN = "F55";
"VSS1507":   PN = "F6"  !CDS_PN = "F6";
"VSS1508":   PN = "F61"  !CDS_PN = "F61";
"VSS1509":   PN = "F67"  !CDS_PN = "F67";
"VSS1510":   PN = "F73"  !CDS_PN = "F73";
"VSS1511":   PN = "F79"  !CDS_PN = "F79";
"VSS1514":   PN = "G11"  !CDS_PN = "G11";
"VSS1516":   PN = "G17"  !CDS_PN = "G17";
"VSS1519":   PN = "G25"  !CDS_PN = "G25";
"VSS1521":   PN = "G3"  !CDS_PN = "G3";
"VSS1523":   PN = "G35"  !CDS_PN = "G35";
"VSS1527":   PN = "G48"  !CDS_PN = "G48";
"VSS1532":   PN = "G60"  !CDS_PN = "G60";
"VSS1534":   PN = "G66"  !CDS_PN = "G66";
"VSS1535":   PN = "G68"  !CDS_PN = "G68";
"VSS1536":   PN = "G7"  !CDS_PN = "G7";
"VSS1538":   PN = "G74"  !CDS_PN = "G74";
"VSS1544":   PN = "H14"  !CDS_PN = "H14";
"VSS1546":   PN = "H2"  !CDS_PN = "H2";
"VSS1558":   PN = "H51"  !CDS_PN = "H51";
"VSS1560":   PN = "H57"  !CDS_PN = "H57";
"VSS1564":   PN = "H65"  !CDS_PN = "H65";
"VSS1567":   PN = "H75"  !CDS_PN = "H75";
"VSS1570":   PN = "F24"  !CDS_PN = "F24";
"VSS1571":   PN = "F30"  !CDS_PN = "F30";
"VSS1572":   PN = "F36"  !CDS_PN = "F36";
"VSS1573":   PN = "F4"  !CDS_PN = "F4";
"VSS1574":   PN = "F49"  !CDS_PN = "F49";
"VSS1575":   PN = "J21"  !CDS_PN = "J21";
"VSS1576":   PN = "F83"  !CDS_PN = "F83";
"VSS1577":   PN = "F89"  !CDS_PN = "F89";
"VSS1578":   PN = "G13"  !CDS_PN = "G13";
"VSS1579":   PN = "G19"  !CDS_PN = "G19";
"VSS1580":   PN = "J39"  !CDS_PN = "J39";
"VSS1581":   PN = "G23"  !CDS_PN = "G23";
"VSS1582":   PN = "J5"  !CDS_PN = "J5";
"VSS1583":   PN = "G29"  !CDS_PN = "G29";
"VSS1584":   PN = "G31"  !CDS_PN = "G31";
"VSS1585":   PN = "G37"  !CDS_PN = "G37";
"VSS1586":   PN = "G41"  !CDS_PN = "G41";
"VSS1587":   PN = "J64"  !CDS_PN = "J64";
"VSS1588":   PN = "G43"  !CDS_PN = "G43";
"VSS1589":   PN = "J70"  !CDS_PN = "J70";
"VSS1590":   PN = "G50"  !CDS_PN = "G50";
"VSS1591":   PN = "G54"  !CDS_PN = "G54";
"VSS1592":   PN = "G56"  !CDS_PN = "G56";
"VSS1593":   PN = "G62"  !CDS_PN = "G62";
"VSS1594":   PN = "G72"  !CDS_PN = "G72";
"VSS1595":   PN = "J88"  !CDS_PN = "J88";
"VSS1596":   PN = "J9"  !CDS_PN = "J9";
"VSS1597":   PN = "K12"  !CDS_PN = "K12";
"VSS1598":   PN = "K14"  !CDS_PN = "K14";
"VSS1599":   PN = "K2"  !CDS_PN = "K2";
"VSS1600":   PN = "G84"  !CDS_PN = "G84";
"VSS1601":   PN = "G88"  !CDS_PN = "G88";
"VSS1602":   PN = "K42"  !CDS_PN = "K42";
"VSS1603":   PN = "K49"  !CDS_PN = "K49";
"VSS1604":   PN = "G90"  !CDS_PN = "G90";
"VSS1605":   PN = "H10"  !CDS_PN = "H10";
"VSS1606":   PN = "H16"  !CDS_PN = "H16";
"VSS1607":   PN = "H20"  !CDS_PN = "H20";
"VSS1608":   PN = "H22"  !CDS_PN = "H22";
"VSS1609":   PN = "H26"  !CDS_PN = "H26";
"VSS1610":   PN = "H28"  !CDS_PN = "H28";
"VSS1611":   PN = "H32"  !CDS_PN = "H32";
"VSS1612":   PN = "H34"  !CDS_PN = "H34";
"VSS1613":   PN = "H38"  !CDS_PN = "H38";
"VSS1614":   PN = "L19"  !CDS_PN = "L19";
"VSS1615":   PN = "H4"  !CDS_PN = "H4";
"VSS1616":   PN = "H40"  !CDS_PN = "H40";
"VSS1617":   PN = "H44"  !CDS_PN = "H44";
"VSS1618":   PN = "H47"  !CDS_PN = "H47";
"VSS1619":   PN = "H53"  !CDS_PN = "H53";
"VSS1620":   PN = "H59"  !CDS_PN = "H59";
"VSS1621":   PN = "H6"  !CDS_PN = "H6";
"VSS1622":   PN = "H63"  !CDS_PN = "H63";
"VSS1623":   PN = "H69"  !CDS_PN = "H69";
"VSS1624":   PN = "H71"  !CDS_PN = "H71";
"VSS1625":   PN = "H79"  !CDS_PN = "H79";
"VSS1626":   PN = "H8"  !CDS_PN = "H8";
"VSS1627":   PN = "H81"  !CDS_PN = "H81";
"VSS1628":   PN = "J15"  !CDS_PN = "J15";
"VSS1629":   PN = "J27"  !CDS_PN = "J27";
"VSS1630":   PN = "J33"  !CDS_PN = "J33";
"VSS1631":   PN = "J45"  !CDS_PN = "J45";
"VSS1632":   PN = "J52"  !CDS_PN = "J52";
"VSS1633":   PN = "J58"  !CDS_PN = "J58";
"VSS1634":   PN = "L58"  !CDS_PN = "L58";
"VSS1635":   PN = "J76"  !CDS_PN = "J76";
"VSS1636":   PN = "J78"  !CDS_PN = "J78";
"VSS1637":   PN = "J84"  !CDS_PN = "J84";
"VSS1638":   PN = "J86"  !CDS_PN = "J86";
"VSS1639":   PN = "K77"  !CDS_PN = "K77";
"VSS1640":   PN = "L70"  !CDS_PN = "L70";
"VSS1641":   PN = "K8"  !CDS_PN = "K8";
"VSS1642":   PN = "K83"  !CDS_PN = "K83";
"VSS1643":   PN = "K85"  !CDS_PN = "K85";
"VSS1644":   PN = "L13"  !CDS_PN = "L13";
"VSS1645":   PN = "L15"  !CDS_PN = "L15";
"VSS1646":   PN = "L88"  !CDS_PN = "L88";
"VSS1647":   PN = "L9"  !CDS_PN = "L9";
"VSS1648":   PN = "L90"  !CDS_PN = "L90";
"VSS1649":   PN = "M12"  !CDS_PN = "M12";
"VSS1650":   PN = "L17"  !CDS_PN = "L17";
"VSS1651":   PN = "L21"  !CDS_PN = "L21";
"VSS1652":   PN = "M4"  !CDS_PN = "M4";
"VSS1653":   PN = "M42"  !CDS_PN = "M42";
"VSS1654":   PN = "M49"  !CDS_PN = "M49";
"VSS1655":   PN = "L23"  !CDS_PN = "L23";
"VSS1656":   PN = "L25"  !CDS_PN = "L25";
"VSS1657":   PN = "M8"  !CDS_PN = "M8";
"VSS1658":   PN = "L27"  !CDS_PN = "L27";
"VSS1659":   PN = "L29"  !CDS_PN = "L29";
"VSS1660":   PN = "L31"  !CDS_PN = "L31";
"VSS1661":   PN = "L33"  !CDS_PN = "L33";
"VSS1662":   PN = "L35"  !CDS_PN = "L35";
"VSS1663":   PN = "L37"  !CDS_PN = "L37";
"VSS1664":   PN = "N21"  !CDS_PN = "N21";
"VSS1665":   PN = "L39"  !CDS_PN = "L39";
"VSS1666":   PN = "L41"  !CDS_PN = "L41";
"VSS1667":   PN = "L43"  !CDS_PN = "L43";
"VSS1668":   PN = "L45"  !CDS_PN = "L45";
"VSS1669":   PN = "N39"  !CDS_PN = "N39";
"VSS1670":   PN = "L48"  !CDS_PN = "L48";
"VSS1671":   PN = "L5"  !CDS_PN = "L5";
"VSS1672":   PN = "L50"  !CDS_PN = "L50";
"VSS1673":   PN = "L52"  !CDS_PN = "L52";
"VSS1674":   PN = "L54"  !CDS_PN = "L54";
"VSS1675":   PN = "N64"  !CDS_PN = "N64";
"VSS1676":   PN = "L56"  !CDS_PN = "L56";
"VSS1677":   PN = "L60"  !CDS_PN = "L60";
"VSS1678":   PN = "L62"  !CDS_PN = "L62";
"VSS1679":   PN = "L64"  !CDS_PN = "L64";
"VSS1680":   PN = "L66"  !CDS_PN = "L66";
"VSS1681":   PN = "L68"  !CDS_PN = "L68";
"VSS1682":   PN = "L72"  !CDS_PN = "L72";
"VSS1683":   PN = "L74"  !CDS_PN = "L74";
"VSS1684":   PN = "L76"  !CDS_PN = "L76";
"VSS1685":   PN = "L78"  !CDS_PN = "L78";
"VSS1686":   PN = "M81"  !CDS_PN = "M81";
"VSS1687":   PN = "M83"  !CDS_PN = "M83";
"VSS1688":   PN = "N15"  !CDS_PN = "N15";
"VSS1689":   PN = "N27"  !CDS_PN = "N27";
"VSS1691":   PN = "N33"  !CDS_PN = "N33";
"VSS1692":   PN = "N45"  !CDS_PN = "N45";
"VSS1693":   PN = "N52"  !CDS_PN = "N52";
"VSS1694":   PN = "N58"  !CDS_PN = "N58";
"VSS1695":   PN = "N70"  !CDS_PN = "N70";
BODY = "SOCKET4677_AZIF0045P001C01CS","I12": LOCATION = "U2" #&CDS_LOCATION = "U2" &SEC = "42" #&CDS_SEC = "42";
"VSS1":   PN = "A11"  !CDS_PN = "A11";
"VSS2":   PN = "A13"  !CDS_PN = "A13";
"VSS3":   PN = "A17"  !CDS_PN = "A17";
"VSS4":   PN = "A19"  !CDS_PN = "A19";
"VSS5":   PN = "A23"  !CDS_PN = "A23";
"VSS6":   PN = "A25"  !CDS_PN = "A25";
"VSS7":   PN = "A29"  !CDS_PN = "A29";
"VSS8":   PN = "A31"  !CDS_PN = "A31";
"VSS9":   PN = "A35"  !CDS_PN = "A35";
"VSS10":   PN = "A37"  !CDS_PN = "A37";
"VSS11":   PN = "A41"  !CDS_PN = "A41";
"VSS12":   PN = "A50"  !CDS_PN = "A50";
"VSS13":   PN = "A54"  !CDS_PN = "A54";
"VSS14":   PN = "A56"  !CDS_PN = "A56";
"VSS15":   PN = "A60"  !CDS_PN = "A60";
"VSS16":   PN = "A62"  !CDS_PN = "A62";
"VSS378":   PN = "B12"  !CDS_PN = "B12";
"VSS379":   PN = "B18"  !CDS_PN = "B18";
"VSS380":   PN = "B24"  !CDS_PN = "B24";
"VSS381":   PN = "B30"  !CDS_PN = "B30";
"VSS382":   PN = "B36"  !CDS_PN = "B36";
"VSS384":   PN = "B42"  !CDS_PN = "B42";
"VSS385":   PN = "B49"  !CDS_PN = "B49";
"VSS386":   PN = "B55"  !CDS_PN = "B55";
"VSS387":   PN = "B6"  !CDS_PN = "B6";
"VSS388":   PN = "B61"  !CDS_PN = "B61";
"VSS389":   PN = "B67"  !CDS_PN = "B67";
"VSS390":   PN = "B75"  !CDS_PN = "B75";
"VSS391":   PN = "B83"  !CDS_PN = "B83";
"VSS392":   PN = "B87"  !CDS_PN = "B87";
"VSS609":   PN = "C39"  !CDS_PN = "C39";
"VSS610":   PN = "C45"  !CDS_PN = "C45";
"VSS612":   PN = "C5"  !CDS_PN = "C5";
"VSS613":   PN = "C52"  !CDS_PN = "C52";
"VSS614":   PN = "C72"  !CDS_PN = "C72";
"VSS615":   PN = "C74"  !CDS_PN = "C74";
"VSS616":   PN = "C78"  !CDS_PN = "C78";
"VSS617":   PN = "C80"  !CDS_PN = "C80";
"VSS618":   PN = "C82"  !CDS_PN = "C82";
"VSS619":   PN = "C86"  !CDS_PN = "C86";
"VSS657":   PN = "D63"  !CDS_PN = "D63";
"VSS658":   PN = "D65"  !CDS_PN = "D65";
"VSS659":   PN = "D67"  !CDS_PN = "D67";
"VSS662":   PN = "D79"  !CDS_PN = "D79";
"VSS663":   PN = "D8"  !CDS_PN = "D8";
"VSS864":   PN = "D10"  !CDS_PN = "D10";
"VSS865":   PN = "D12"  !CDS_PN = "D12";
"VSS866":   PN = "D14"  !CDS_PN = "D14";
"VSS868":   PN = "D16"  !CDS_PN = "D16";
"VSS869":   PN = "D18"  !CDS_PN = "D18";
"VSS871":   PN = "D20"  !CDS_PN = "D20";
"VSS873":   PN = "D22"  !CDS_PN = "D22";
"VSS874":   PN = "D24"  !CDS_PN = "D24";
"VSS875":   PN = "D26"  !CDS_PN = "D26";
"VSS876":   PN = "D28"  !CDS_PN = "D28";
"VSS877":   PN = "D30"  !CDS_PN = "D30";
"VSS878":   PN = "D32"  !CDS_PN = "D32";
"VSS879":   PN = "D34"  !CDS_PN = "D34";
"VSS881":   PN = "D36"  !CDS_PN = "D36";
"VSS884":   PN = "D38"  !CDS_PN = "D38";
"VSS885":   PN = "D40"  !CDS_PN = "D40";
"VSS886":   PN = "D42"  !CDS_PN = "D42";
"VSS888":   PN = "D44"  !CDS_PN = "D44";
"VSS889":   PN = "D47"  !CDS_PN = "D47";
"VSS891":   PN = "D49"  !CDS_PN = "D49";
"VSS892":   PN = "D51"  !CDS_PN = "D51";
"VSS895":   PN = "D53"  !CDS_PN = "D53";
"VSS896":   PN = "D55"  !CDS_PN = "D55";
"VSS897":   PN = "D57"  !CDS_PN = "D57";
"VSS898":   PN = "D59"  !CDS_PN = "D59";
"VSS899":   PN = "D6"  !CDS_PN = "D6";
"VSS900":   PN = "D61"  !CDS_PN = "D61";
"VSS901":   PN = "D69"  !CDS_PN = "D69";
"VSS902":   PN = "D71"  !CDS_PN = "D71";
"VSS906":   PN = "D81"  !CDS_PN = "D81";
"VSS907":   PN = "D83"  !CDS_PN = "D83";
"VSS1125":   PN = "E5"  !CDS_PN = "E5";
"VSS1271":   PN = "E39"  !CDS_PN = "E39";
DRAWING = "@s9s_mb_2u_lib.s9s_mb_2u(sch_1):page43";
BODY = "Q_RES","I12": LOCATION = "R67" #&CDS_LOCATION = "R67" &SEC = "1" #&CDS_SEC = "1";
"A":   PN = "1"  !CDS_PN = "1";
"B":   PN = "2"  !CDS_PN = "2";
BODY = "Q_RES","I13": LOCATION = "R68" #&CDS_LOCATION = "R68" &SEC = "1" #&CDS_SEC = "1";
"A":   PN = "1"  !CDS_PN = "1";
"B":   PN = "2"  !CDS_PN = "2";
BODY = "Q_RES","I16": LOCATION = "R69" #&CDS_LOCATION = "R69" &SEC = "1" #&CDS_SEC = "1";
"A":   PN = "1"  !CDS_PN = "1";
"B":   PN = "2"  !CDS_PN = "2";
BODY = "Q_RES","I17": LOCATION = "R70" #&CDS_LOCATION = "R70" &SEC = "1" #&CDS_SEC = "1";
"A":   PN = "1"  !CDS_PN = "1";
"B":   PN = "2"  !CDS_PN = "2";
BODY = "Q_RES","I52": LOCATION = "R1226" #&CDS_LOCATION = "R1226" &SEC = "1" #&CDS_SEC = "1";
"A":   PN = "1"  !CDS_PN = "1";
"B":   PN = "2"  !CDS_PN = "2";
BODY = "Q_RES","I56": LOCATION = "R1227" #&CDS_LOCATION = "R1227" &SEC = "1" #&CDS_SEC = "1";
"A":   PN = "1"  !CDS_PN = "1";
"B":   PN = "2"  !CDS_PN = "2";
DRAWING = "@s9s_mb_2u_lib.s9s_mb_2u(sch_1):page44";
BODY = "Q_RES","I7": LOCATION = "R66" #&CDS_LOCATION = "R66" &SEC = "1" #&CDS_SEC = "1";
"A":   PN = "1"  !CDS_PN = "1";
"B":   PN = "2"  !CDS_PN = "2";
BODY = "Q_RES","I8": LOCATION = "R65" #&CDS_LOCATION = "R65" &SEC = "1" #&CDS_SEC = "1";
"A":   PN = "1"  !CDS_PN = "1";
"B":   PN = "2"  !CDS_PN = "2";
BODY = "Q_RES","I9": LOCATION = "R64" #&CDS_LOCATION = "R64" &SEC = "1" #&CDS_SEC = "1";
"A":   PN = "1"  !CDS_PN = "1";
"B":   PN = "2"  !CDS_PN = "2";
BODY = "Q_RES","I10": LOCATION = "R63" #&CDS_LOCATION = "R63" &SEC = "1" #&CDS_SEC = "1";
"A":   PN = "1"  !CDS_PN = "1";
"B":   PN = "2"  !CDS_PN = "2";
BODY = "Q_RES","I11": LOCATION = "R62" #&CDS_LOCATION = "R62" &SEC = "1" #&CDS_SEC = "1";
"A":   PN = "1"  !CDS_PN = "1";
"B":   PN = "2"  !CDS_PN = "2";
BODY = "Q_RES","I16": LOCATION = "R61" #&CDS_LOCATION = "R61" &SEC = "1" #&CDS_SEC = "1";
"A":   PN = "1"  !CDS_PN = "1";
"B":   PN = "2"  !CDS_PN = "2";
BODY = "SOCKET4677_AZIF0045P001C01CS","I51": LOCATION = "U1" #&CDS_LOCATION = "U1" &SEC = "1" #&CDS_SEC = "1";
"BCLK0_DN":   PN = "AT30"  !CDS_PN = "AT30";
"BCLK0_DP":   PN = "AV30"  !CDS_PN = "AV30";
"BCLK1_DN":   PN = "CY28"  !CDS_PN = "CY28";
"BCLK1_DP":   PN = "CW29"  !CDS_PN = "CW29";
"BCLK2_DN":   PN = "AU29"  !CDS_PN = "AU29";
"BCLK2_DP":   PN = "AV28"  !CDS_PN = "AV28";
"BCLK3_DN":   PN = "CW27"  !CDS_PN = "CW27";
"BCLK3_DP":   PN = "DA27"  !CDS_PN = "DA27";
"BIST_ENABLE":   PN = "AT18"  !CDS_PN = "AT18";
"BMCINIT":   PN = "BN23"  !CDS_PN = "BN23";
"DDR01_RESET_N":   PN = "AU50"  !CDS_PN = "AU50";
"DDR23_RESET_N":   PN = "AV51"  !CDS_PN = "AV51";
"DDR45_RESET_N":   PN = "CY42"  !CDS_PN = "CY42";
"DDR67_RESET_N":   PN = "CY55"  !CDS_PN = "CY55";
"DMIMODE_OVERRIDE":   PN = "AW17"  !CDS_PN = "AW17";
"FRMAGENT":   PN = "AU17"  !CDS_PN = "AU17";
"LEGACY_SKT":   PN = "CY59"  !CDS_PN = "CY59";
"PECI":   PN = "BH24"  !CDS_PN = "BH24";
"PKG_ID0":   PN = "BL64"  !CDS_PN = "BL64";
"PKG_ID1":   PN = "AY63"  !CDS_PN = "AY63";
"PKG_ID2":   PN = "BN64"  !CDS_PN = "BN64";
"PRDY_N":   PN = "BP26"  !CDS_PN = "BP26";
"PREQ_N":   PN = "AV22"  !CDS_PN = "AV22";
"PROC_ID0":   PN = "BG72"  !CDS_PN = "BG72";
"PROC_ID1":   PN = "BH71"  !CDS_PN = "BH71";
"PROCDIS_N":   PN = "DA52"  !CDS_PN = "DA52";
"SAFE_MODE_BOOT":   PN = "AU23"  !CDS_PN = "AU23";
"SOCKET_ID0":   PN = "CW60"  !CDS_PN = "CW60";
"SOCKET_ID1":   PN = "CY61"  !CDS_PN = "CY61";
"SOCKET_ID2":   PN = "CT61"  !CDS_PN = "CT61";
"TCK":   PN = "BT24"  !CDS_PN = "BT24";
"TDI":   PN = "BV24"  !CDS_PN = "BV24";
"TDO":   PN = "BW25"  !CDS_PN = "BW25";
"TMS":   PN = "BR25"  !CDS_PN = "BR25";
"TXT_AGENT":   PN = "BT26"  !CDS_PN = "BT26";
"TXT_PLTEN":   PN = "CT20"  !CDS_PN = "CT20";
"XTAL_CLK_DN":   PN = "CW31"  !CDS_PN = "CW31";
"XTAL_CLK_DP":   PN = "CY32"  !CDS_PN = "CY32";
"DDR0123_SPDSCL":   PN = "BT22"  !CDS_PN = "BT22";
"DDR0123_SPDSDA":   PN = "BY22"  !CDS_PN = "BY22";
"DDR4567_SPDSCL":   PN = "CU17"  !CDS_PN = "CU17";
"DDR4567_SPDSDA":   PN = "CT18"  !CDS_PN = "CT18";
"RSVD72":   PN = "BR23"  !CDS_PN = "BR23";
"RSVD76":   PN = "BY24"  !CDS_PN = "BY24";
"RSVD88":   PN = "CD71"  !CDS_PN = "CD71";
"RSVD91":   PN = "CE70"  !CDS_PN = "CE70";
"RSVD108":   PN = "CJ72"  !CDS_PN = "CJ72";
"RSVD120":   PN = "CL72"  !CDS_PN = "CL72";
"RSVD157":   PN = "D4"  !CDS_PN = "D4";
"RSVD161":   PN = "G5"  !CDS_PN = "G5";
BODY = "Q_RES","I55": LOCATION = "R1270" #&CDS_LOCATION = "R1270" &SEC = "1" #&CDS_SEC = "1";
"A":   PN = "1"  !CDS_PN = "1";
"B":   PN = "2"  !CDS_PN = "2";
DRAWING = "@s9s_mb_2u_lib.s9s_mb_2u(sch_1):page45";
BODY = "SOCKET4677_AZIF0045P001C01CS","I29": LOCATION = "U1" #&CDS_LOCATION = "U1" &SEC = "2" #&CDS_SEC = "2";
"CATERR_N":   PN = "BP24"  !CDS_PN = "BP24";
"CXPSMBUS_ALERT_N":   PN = "BV26"  !CDS_PN = "BV26";
"CXPSMBUSSCL":   PN = "CA25"  !CDS_PN = "CA25";
"CXPSMBUSSDA":   PN = "BY26"  !CDS_PN = "BY26";
"DDR01_DRAM_PWR_OK":   PN = "A43"  !CDS_PN = "A43";
"DDR23_DRAM_PWR_OK":   PN = "F47"  !CDS_PN = "F47";
"DDR45_DRAM_PWR_OK":   PN = "CY44"  !CDS_PN = "CY44";
"DDR67_DRAM_PWR_OK":   PN = "CW45"  !CDS_PN = "CW45";
"FBRK_N":   PN = "AV57"  !CDS_PN = "AV57";
"MEMHOT_IN_N":   PN = "AU21"  !CDS_PN = "AU21";
"MEMHOT_OUT_N":   PN = "CF26"  !CDS_PN = "CF26";
"MEMTRIP_N":   PN = "AV24"  !CDS_PN = "AV24";
"NMI":   PN = "AV18"  !CDS_PN = "AV18";
"PMDOWN0":   PN = "CW39"  !CDS_PN = "CW39";
"PMDOWN1":   PN = "CP26"  !CDS_PN = "CP26";
"PMDOWN2":   PN = "CM26"  !CDS_PN = "CM26";
"PMDOWN3":   PN = "CD24"  !CDS_PN = "CD24";
"PMDOWN4":   PN = "CV18"  !CDS_PN = "CV18";
"PMDOWN5":   PN = "CE23"  !CDS_PN = "CE23";
"PMDOWN6":   PN = "CC25"  !CDS_PN = "CC25";
"PMDOWN_PCH":   PN = "CY40"  !CDS_PN = "CY40";
"PMFAST_WAKE_N":   PN = "CP20"  !CDS_PN = "CP20";
"PMSYNC0":   PN = "CN25"  !CDS_PN = "CN25";
"PMSYNC1":   PN = "CL25"  !CDS_PN = "CL25";
"PMSYNC2":   PN = "CH26"  !CDS_PN = "CH26";
"PMSYNC3":   PN = "CE25"  !CDS_PN = "CE25";
"PMSYNC4":   PN = "CR19"  !CDS_PN = "CR19";
"PMSYNC5":   PN = "CH24"  !CDS_PN = "CH24";
"PMSYNC6":   PN = "CF24"  !CDS_PN = "CF24";
"PMSYNC_PCH":   PN = "DA39"  !CDS_PN = "DA39";
"PROCHOT_N":   PN = "AU19"  !CDS_PN = "AU19";
"RESET_N":   PN = "BH61"  !CDS_PN = "BH61";
"SKTOCC_N":   PN = "CG66"  !CDS_PN = "CG66";
"SVIDALERT0_N":   PN = "BK26"  !CDS_PN = "BK26";
"SVIDALERT1_N":   PN = "BJ25"  !CDS_PN = "BJ25";
"SVIDCLK0":   PN = "BH26"  !CDS_PN = "BH26";
"SVIDCLK1":   PN = "BF26"  !CDS_PN = "BF26";
"SVIDDATA0":   PN = "BD26"  !CDS_PN = "BD26";
"SVIDDATA1":   PN = "BL25"  !CDS_PN = "BL25";
"TAP_ODT_EN":   PN = "AY20"  !CDS_PN = "AY20";
"THERMTRIP_N":   PN = "BL62"  !CDS_PN = "BL62";
"ERROR_N0":   PN = "BF22"  !CDS_PN = "BF22";
"ERROR_N1":   PN = "AY22"  !CDS_PN = "AY22";
"ERROR_N2":   PN = "BD22"  !CDS_PN = "BD22";
"PIROM_AD0":   PN = "CR70"  !CDS_PN = "CR70";
"PIROM_AD1":   PN = "CT71"  !CDS_PN = "CT71";
"PIROM_AD2":   PN = "CP71"  !CDS_PN = "CP71";
"PIROM_SCL":   PN = "CU70"  !CDS_PN = "CU70";
"PIROM_SDA":   PN = "CM71"  !CDS_PN = "CM71";
"PIROM_SM_WP":   PN = "CR72"  !CDS_PN = "CR72";
"PWRGOOD":   PN = "AV20"  !CDS_PN = "AV20";
"RSVD4":   PN = "AT24"  !CDS_PN = "AT24";
"RSVD6":   PN = "AU25"  !CDS_PN = "AU25";
"RSVD15":   PN = "AV26"  !CDS_PN = "AV26";
"RSVD19":   PN = "AV59"  !CDS_PN = "AV59";
"RSVD27":   PN = "AY26"  !CDS_PN = "AY26";
"RSVD29":   PN = "AY65"  !CDS_PN = "AY65";
"RSVD59":   PN = "BJ70"  !CDS_PN = "BJ70";
"RSVD69":   PN = "BP67"  !CDS_PN = "BP67";
"RSVD70":   PN = "BP69"  !CDS_PN = "BP69";
"RSVD96":   PN = "CH22"  !CDS_PN = "CH22";
"RSVD104":   PN = "CJ62"  !CDS_PN = "CJ62";
"RSVD113":   PN = "CL21"  !CDS_PN = "CL21";
"RSVD116":   PN = "CL64"  !CDS_PN = "CL64";
"RSVD121":   PN = "CM63"  !CDS_PN = "CM63";
"RSVD126":   PN = "CN62"  !CDS_PN = "CN62";
"RSVD132":   PN = "CR23"  !CDS_PN = "CR23";
"RSVD141":   PN = "CV24"  !CDS_PN = "CV24";
"RSVD145":   PN = "CW23"  !CDS_PN = "CW23";
"RSVD146":   PN = "CW25"  !CDS_PN = "CW25";
"RSVD150":   PN = "CW68"  !CDS_PN = "CW68";
BODY = "Q_RES","I51": LOCATION = "R58" #&CDS_LOCATION = "R58" &SEC = "1" #&CDS_SEC = "1";
"A":   PN = "1"  !CDS_PN = "1";
"B":   PN = "2"  !CDS_PN = "2";
BODY = "Q_RES","I52": LOCATION = "R59" #&CDS_LOCATION = "R59" &SEC = "1" #&CDS_SEC = "1";
"A":   PN = "1"  !CDS_PN = "1";
"B":   PN = "2"  !CDS_PN = "2";
BODY = "Q_RES","I53": LOCATION = "R60" #&CDS_LOCATION = "R60" &SEC = "1" #&CDS_SEC = "1";
"A":   PN = "1"  !CDS_PN = "1";
"B":   PN = "2"  !CDS_PN = "2";
BODY = "Q_RES","I54": LOCATION = "R55" #&CDS_LOCATION = "R55" &SEC = "1" #&CDS_SEC = "1";
"A":   PN = "1"  !CDS_PN = "1";
"B":   PN = "2"  !CDS_PN = "2";
BODY = "Q_RES","I55": LOCATION = "R56" #&CDS_LOCATION = "R56" &SEC = "1" #&CDS_SEC = "1";
"A":   PN = "1"  !CDS_PN = "1";
"B":   PN = "2"  !CDS_PN = "2";
BODY = "Q_RES","I56": LOCATION = "R57" #&CDS_LOCATION = "R57" &SEC = "1" #&CDS_SEC = "1";
"A":   PN = "1"  !CDS_PN = "1";
"B":   PN = "2"  !CDS_PN = "2";
BODY = "Q_RES","I69": LOCATION = "R559" #&CDS_LOCATION = "R559" &SEC = "1" #&CDS_SEC = "1";
"A":   PN = "1"  !CDS_PN = "1";
"B":   PN = "2"  !CDS_PN = "2";
BODY = "Q_RES","I70": LOCATION = "R560" #&CDS_LOCATION = "R560" &SEC = "1" #&CDS_SEC = "1";
"A":   PN = "1"  !CDS_PN = "1";
"B":   PN = "2"  !CDS_PN = "2";
BODY = "Q_RES","I73": LOCATION = "R558" #&CDS_LOCATION = "R558" &SEC = "1" #&CDS_SEC = "1";
"A":   PN = "1"  !CDS_PN = "1";
"B":   PN = "2"  !CDS_PN = "2";
BODY = "Q_RES","I74": LOCATION = "R557" #&CDS_LOCATION = "R557" &SEC = "1" #&CDS_SEC = "1";
"A":   PN = "1"  !CDS_PN = "1";
"B":   PN = "2"  !CDS_PN = "2";
BODY = "Q_RES","I81": LOCATION = "R1934" #&CDS_LOCATION = "R1934" &SEC = "1" #&CDS_SEC = "1";
"A":   PN = "1"  !CDS_PN = "1";
"B":   PN = "2"  !CDS_PN = "2";
BODY = "Q_RES","I82": LOCATION = "R1935" #&CDS_LOCATION = "R1935" &SEC = "1" #&CDS_SEC = "1";
"A":   PN = "1"  !CDS_PN = "1";
"B":   PN = "2"  !CDS_PN = "2";
DRAWING = "@s9s_mb_2u_lib.s9s_mb_2u(sch_1):page46";
BODY = "SOCKET4677_AZIF0045P001C01CS","I5": LOCATION = "U1" #&CDS_LOCATION = "U1" &SEC = "3" #&CDS_SEC = "3";
"PLT_AUX_PWRGOOD":   PN = "CV20"  !CDS_PN = "CV20";
"SMB_CLK":   PN = "CE64"  !CDS_PN = "CE64";
"SMB_DATA":   PN = "CD63"  !CDS_PN = "CD63";
"CD_INIT_ERROR":   PN = "CY20"  !CDS_PN = "CY20";
"PARTITION_ID0":   PN = "BA70"  !CDS_PN = "BA70";
"PARTITION_ID1":   PN = "AV71"  !CDS_PN = "AV71";
"RSVD11":   PN = "AU62"  !CDS_PN = "AU62";
"RSVD12":   PN = "AU64"  !CDS_PN = "AU64";
"RSVD20":   PN = "AV63"  !CDS_PN = "AV63";
"RSVD23":   PN = "AW19"  !CDS_PN = "AW19";
"RSVD24":   PN = "AW64"  !CDS_PN = "AW64";
"RSVD25":   PN = "AW70"  !CDS_PN = "AW70";
"RSVD28":   PN = "AY61"  !CDS_PN = "AY61";
"RSVD30":   PN = "AY67"  !CDS_PN = "AY67";
"RSVD32":   PN = "BA62"  !CDS_PN = "BA62";
"RSVD33":   PN = "BA66"  !CDS_PN = "BA66";
"RSVD34":   PN = "BA68"  !CDS_PN = "BA68";
"RSVD35":   PN = "BB61"  !CDS_PN = "BB61";
"RSVD36":   PN = "BB67"  !CDS_PN = "BB67";
"RSVD38":   PN = "BC25"  !CDS_PN = "BC25";
"RSVD39":   PN = "BC64"  !CDS_PN = "BC64";
"RSVD40":   PN = "BD61"  !CDS_PN = "BD61";
"RSVD41":   PN = "BD63"  !CDS_PN = "BD63";
"RSVD42":   PN = "BD65"  !CDS_PN = "BD65";
"RSVD47":   PN = "BE25"  !CDS_PN = "BE25";
"RSVD48":   PN = "BE62"  !CDS_PN = "BE62";
"RSVD50":   PN = "BF65"  !CDS_PN = "BF65";
"RSVD52":   PN = "BG62"  !CDS_PN = "BG62";
"RSVD53":   PN = "BG64"  !CDS_PN = "BG64";
"RSVD55":   PN = "BH63"  !CDS_PN = "BH63";
"RSVD56":   PN = "BH65"  !CDS_PN = "BH65";
"RSVD58":   PN = "BJ64"  !CDS_PN = "BJ64";
"RSVD61":   PN = "BK63"  !CDS_PN = "BK63";
"RSVD64":   PN = "BM63"  !CDS_PN = "BM63";
"RSVD86":   PN = "CD65"  !CDS_PN = "CD65";
"RSVD93":   PN = "CF63"  !CDS_PN = "CF63";
"RSVD94":   PN = "CF65"  !CDS_PN = "CF65";
"RSVD98":   PN = "CH63"  !CDS_PN = "CH63";
"RSVD100":   PN = "CH71"  !CDS_PN = "CH71";
"RSVD101":   PN = "CJ21"  !CDS_PN = "CJ21";
"RSVD102":   PN = "CJ23"  !CDS_PN = "CJ23";
"RSVD103":   PN = "CJ25"  !CDS_PN = "CJ25";
"RSVD105":   PN = "CJ66"  !CDS_PN = "CJ66";
"RSVD109":   PN = "CK22"  !CDS_PN = "CK22";
"RSVD110":   PN = "CK24"  !CDS_PN = "CK24";
"RSVD114":   PN = "CL23"  !CDS_PN = "CL23";
"RSVD117":   PN = "CL66"  !CDS_PN = "CL66";
"RSVD123":   PN = "CN21"  !CDS_PN = "CN21";
"RSVD124":   PN = "CN23"  !CDS_PN = "CN23";
"RSVD127":   PN = "CP22"  !CDS_PN = "CP22";
"RSVD128":   PN = "CP24"  !CDS_PN = "CP24";
"RSVD131":   PN = "CR21"  !CDS_PN = "CR21";
"RSVD136":   PN = "CT22"  !CDS_PN = "CT22";
"RSVD137":   PN = "CT24"  !CDS_PN = "CT24";
"RSVD140":   PN = "CV22"  !CDS_PN = "CV22";
"RSVD142":   PN = "CV69"  !CDS_PN = "CV69";
"RSVD143":   PN = "CV71"  !CDS_PN = "CV71";
"RSVD144":   PN = "CW21"  !CDS_PN = "CW21";
"RSVD155":   PN = "CY69"  !CDS_PN = "CY69";
"RSVD156":   PN = "CY71"  !CDS_PN = "CY71";
"TEST_1":   PN = "CJ64"  !CDS_PN = "CJ64";
"TEST_2":   PN = "CK65"  !CDS_PN = "CK65";
"TEST_3":   PN = "CH65"  !CDS_PN = "CH65";
"TEST_5":   PN = "CY22"  !CDS_PN = "CY22";
"TEST_6":   PN = "CF61"  !CDS_PN = "CF61";
"TEST_7":   PN = "AV69"  !CDS_PN = "AV69";
"TEST_8":   PN = "AY69"  !CDS_PN = "AY69";
DRAWING = "@s9s_mb_2u_lib.s9s_mb_2u(sch_1):page47";
BODY = "SOCKET4677_AZIF0045P001C01CS","I16": LOCATION = "U1" #&CDS_LOCATION = "U1" &SEC = "4" #&CDS_SEC = "4";
"MBP0_N":   PN = "BL23"  !CDS_PN = "BL23";
"MBP1_N":   PN = "BN25"  !CDS_PN = "BN25";
"MBP2_N":   PN = "BJ23"  !CDS_PN = "BJ23";
"MBP3_N":   PN = "BK24"  !CDS_PN = "BK24";
"PMAX_TRIGGER_IO":   PN = "BD24"  !CDS_PN = "BD24";
"RMCA_N":   PN = "BH22"  !CDS_PN = "BH22";
"VCCD_HV_SENSE":   PN = "BU11"  !CDS_PN = "BU11";
"VCCFA_EHV_FIVRA_SENSE":   PN = "AY85"  !CDS_PN = "AY85";
"VCCFA_EHV_SENSE":   PN = "AU11"  !CDS_PN = "AU11";
"VCCIN_SENSE":   PN = "BD87"  !CDS_PN = "BD87";
"VCCINFAON_SENSE":   PN = "CA11"  !CDS_PN = "CA11";
"VSS_VCCD_HV_SENSE":   PN = "BN11"  !CDS_PN = "BN11";
"VSS_VCCFA_EHV_FIVRA_SENSE":   PN = "AT85"  !CDS_PN = "AT85";
"VSS_VCCFA_EHV_SENSE":   PN = "BA11"  !CDS_PN = "BA11";
"VSS_VCCIN_SENSE":   PN = "BC90"  !CDS_PN = "BC90";
"VSS_VCCINFAON_SENSE":   PN = "CE11"  !CDS_PN = "CE11";
"RSVD7":   PN = "AU33"  !CDS_PN = "AU33";
"RSVD9":   PN = "AU56"  !CDS_PN = "AU56";
"RSVD10":   PN = "AU58"  !CDS_PN = "AU58";
"RSVD16":   PN = "AV32"  !CDS_PN = "AV32";
"RSVD17":   PN = "AV38"  !CDS_PN = "AV38";
"RSVD18":   PN = "AV40"  !CDS_PN = "AV40";
"RSVD37":   PN = "BC23"  !CDS_PN = "BC23";
"RSVD46":   PN = "BE23"  !CDS_PN = "BE23";
"RSVD49":   PN = "BF24"  !CDS_PN = "BF24";
"RSVD81":   PN = "CC64"  !CDS_PN = "CC64";
"RSVD90":   PN = "CE62"  !CDS_PN = "CE62";
"RSVD125":   PN = "CN60"  !CDS_PN = "CN60";
"RSVD129":   PN = "CP61"  !CDS_PN = "CP61";
"RSVD134":   PN = "CR60"  !CDS_PN = "CR60";
"RSVD139":   PN = "CU62"  !CDS_PN = "CU62";
"RSVD151":   PN = "CY24"  !CDS_PN = "CY24";
"RSVD152":   PN = "CY38"  !CDS_PN = "CY38";
"RSVD153":   PN = "CY49"  !CDS_PN = "CY49";
"RSVD158":   PN = "DA45"  !CDS_PN = "DA45";
"RSVD162":   PN = "H12"  !CDS_PN = "H12";
BODY = "Q_RES","I22": LOCATION = "R54" #&CDS_LOCATION = "R54" &SEC = "1" #&CDS_SEC = "1";
"A":   PN = "1"  !CDS_PN = "1";
"B":   PN = "2"  !CDS_PN = "2";
BODY = "Q_RES","I23": LOCATION = "R53" #&CDS_LOCATION = "R53" &SEC = "1" #&CDS_SEC = "1";
"A":   PN = "1"  !CDS_PN = "1";
"B":   PN = "2"  !CDS_PN = "2";
BODY = "Q_RES","I24": LOCATION = "R51" #&CDS_LOCATION = "R51" &SEC = "1" #&CDS_SEC = "1";
"A":   PN = "1"  !CDS_PN = "1";
"B":   PN = "2"  !CDS_PN = "2";
BODY = "Q_RES","I25": LOCATION = "R52" #&CDS_LOCATION = "R52" &SEC = "1" #&CDS_SEC = "1";
"A":   PN = "1"  !CDS_PN = "1";
"B":   PN = "2"  !CDS_PN = "2";
BODY = "Q_RES","I34": LOCATION = "R49" #&CDS_LOCATION = "R49" &SEC = "1" #&CDS_SEC = "1";
"A":   PN = "1"  !CDS_PN = "1";
"B":   PN = "2"  !CDS_PN = "2";
BODY = "Q_RES","I35": LOCATION = "R50" #&CDS_LOCATION = "R50" &SEC = "1" #&CDS_SEC = "1";
"A":   PN = "1"  !CDS_PN = "1";
"B":   PN = "2"  !CDS_PN = "2";
DRAWING = "@s9s_mb_2u_lib.s9s_mb_2u(sch_1):page48";
BODY = "SOCKET4677_AZIF0045P001C01CS","I1": LOCATION = "U1" #&CDS_LOCATION = "U1" &SEC = "5" #&CDS_SEC = "5";
"RSVD0":   PN = "AC78"  !CDS_PN = "AC78";
"RSVD1":   PN = "AD77"  !CDS_PN = "AD77";
"RSVD21":   PN = "AV65"  !CDS_PN = "AV65";
"RSVD26":   PN = "AY24"  !CDS_PN = "AY24";
"RSVD31":   PN = "BA25"  !CDS_PN = "BA25";
"RSVD43":   PN = "BD71"  !CDS_PN = "BD71";
"RSVD45":   PN = "BE21"  !CDS_PN = "BE21";
"RSVD51":   PN = "BF71"  !CDS_PN = "BF71";
"RSVD54":   PN = "BG78"  !CDS_PN = "BG78";
"RSVD57":   PN = "BJ21"  !CDS_PN = "BJ21";
"RSVD60":   PN = "BK22"  !CDS_PN = "BK22";
"RSVD63":   PN = "BL60"  !CDS_PN = "BL60";
"RSVD65":   PN = "BM65"  !CDS_PN = "BM65";
"RSVD67":   PN = "BP22"  !CDS_PN = "BP22";
"RSVD68":   PN = "BP65"  !CDS_PN = "BP65";
"RSVD71":   PN = "BR21"  !CDS_PN = "BR21";
"RSVD82":   PN = "CC66"  !CDS_PN = "CC66";
"RSVD83":   PN = "CD22"  !CDS_PN = "CD22";
"RSVD84":   PN = "CD26"  !CDS_PN = "CD26";
"RSVD85":   PN = "CD30"  !CDS_PN = "CD30";
"RSVD92":   PN = "CF22"  !CDS_PN = "CF22";
"RSVD99":   PN = "CH69"  !CDS_PN = "CH69";
"RSVD106":   PN = "CJ68"  !CDS_PN = "CJ68";
"RSVD107":   PN = "CJ70"  !CDS_PN = "CJ70";
"RSVD112":   PN = "CK67"  !CDS_PN = "CK67";
"RSVD133":   PN = "CR25"  !CDS_PN = "CR25";
"RSVD138":   PN = "CT26"  !CDS_PN = "CT26";
"RSVD147":   PN = "CW41"  !CDS_PN = "CW41";
"RSVD149":   PN = "CW58"  !CDS_PN = "CW58";
"RSVD154":   PN = "CY57"  !CDS_PN = "CY57";
"RSVD160":   PN = "EG17"  !CDS_PN = "EG17";
"RSVD164":   PN = "U17"  !CDS_PN = "U17";
"RSVD165":   PN = "W17"  !CDS_PN = "W17";
DRAWING = "@s9s_mb_2u_lib.s9s_mb_2u(sch_1):page49";
BODY = "SOCKET4677_AZIF0045P001C01CS","I2": LOCATION = "U1" #&CDS_LOCATION = "U1" &SEC = "6" #&CDS_SEC = "6";
"RSVD8":   PN = "AU52"  !CDS_PN = "AU52";
"RSVD44":   PN = "BD77"  !CDS_PN = "BD77";
"RSVD87":   PN = "CD69"  !CDS_PN = "CD69";
"RSVD95":   PN = "CG60"  !CDS_PN = "CG60";
"RSVD97":   PN = "CH61"  !CDS_PN = "CH61";
"RSVD111":   PN = "CK61"  !CDS_PN = "CK61";
"RSVD115":   PN = "CL60"  !CDS_PN = "CL60";
"RSVD119":   PN = "CL70"  !CDS_PN = "CL70";
"RSVD148":   PN = "CW43"  !CDS_PN = "CW43";
"RSVD159":   PN = "DA70"  !CDS_PN = "DA70";
"RSVD163":   PN = "J13"  !CDS_PN = "J13";
DRAWING = "@s9s_mb_2u_lib.s9s_mb_2u(sch_1):page50";
BODY = "SOCKET4677_AZIF0045P001C01CS","I23": LOCATION = "U1" #&CDS_LOCATION = "U1" &SEC = "7" #&CDS_SEC = "7";
"PTI_DIE000":   PN = "CC29"  !CDS_PN = "CC29";
"PTI_DIE00_STB_0":   PN = "CB30"  !CDS_PN = "CB30";
"PTI_DIE00_STB_1":   PN = "BY28"  !CDS_PN = "BY28";
"PTI_DIE001":   PN = "CD28"  !CDS_PN = "CD28";
"PTI_DIE01_STB_0":   PN = "BF67"  !CDS_PN = "BF67";
"PTI_DIE01_STB_1":   PN = "BK67"  !CDS_PN = "BK67";
"PTI_DIE002":   PN = "CC27"  !CDS_PN = "CC27";
"PTI_DIE003":   PN = "BY30"  !CDS_PN = "BY30";
"PTI_DIE004":   PN = "CA29"  !CDS_PN = "CA29";
"PTI_DIE005":   PN = "BV30"  !CDS_PN = "BV30";
"PTI_DIE006":   PN = "CA27"  !CDS_PN = "CA27";
"PTI_DIE007":   PN = "BV28"  !CDS_PN = "BV28";
"PTI_DIE008":   PN = "BU27"  !CDS_PN = "BU27";
"PTI_DIE009":   PN = "BT28"  !CDS_PN = "BT28";
"PTI_DIE0010":   PN = "BU29"  !CDS_PN = "BU29";
"PTI_DIE010":   PN = "BC70"  !CDS_PN = "BC70";
"PTI_DIE0011":   PN = "BT30"  !CDS_PN = "BT30";
"PTI_DIE011":   PN = "BE70"  !CDS_PN = "BE70";
"PTI_DIE0012":   PN = "BN27"  !CDS_PN = "BN27";
"PTI_DIE012":   PN = "BD69"  !CDS_PN = "BD69";
"PTI_DIE0013":   PN = "BP28"  !CDS_PN = "BP28";
"PTI_DIE013":   PN = "BF69"  !CDS_PN = "BF69";
"PTI_DIE0014":   PN = "BN29"  !CDS_PN = "BN29";
"PTI_DIE014":   PN = "BH69"  !CDS_PN = "BH69";
"PTI_DIE0015":   PN = "BP30"  !CDS_PN = "BP30";
"PTI_DIE015":   PN = "BC68"  !CDS_PN = "BC68";
"PTI_DIE016":   PN = "BG68"  !CDS_PN = "BG68";
"PTI_DIE017":   PN = "BD67"  !CDS_PN = "BD67";
"PTI_DIE018":   PN = "BK69"  !CDS_PN = "BK69";
"PTI_DIE019":   PN = "BM69"  !CDS_PN = "BM69";
"PTI_DIE0110":   PN = "BN68"  !CDS_PN = "BN68";
"PTI_DIE0111":   PN = "BG66"  !CDS_PN = "BG66";
"PTI_DIE0112":   PN = "BJ66"  !CDS_PN = "BJ66";
"PTI_DIE0113":   PN = "BL66"  !CDS_PN = "BL66";
"PTI_DIE0114":   PN = "BM67"  !CDS_PN = "BM67";
"PTI_DIE0115":   PN = "BN66"  !CDS_PN = "BN66";
"UPI0_AC_COUPLING":   PN = "BA23"  !CDS_PN = "BA23";
"UPI1_AC_COUPLING":   PN = "CW19"  !CDS_PN = "CW19";
"UPI2_AC_COUPLING":   PN = "BB65"  !CDS_PN = "BB65";
"UPI3_AC_COUPLING":   PN = "CK71"  !CDS_PN = "CK71";
"RSVD2":   PN = "AN17"  !CDS_PN = "AN17";
"RSVD3":   PN = "AR17"  !CDS_PN = "AR17";
"RSVD5":   PN = "AT67"  !CDS_PN = "AT67";
"RSVD13":   PN = "AU66"  !CDS_PN = "AU66";
"RSVD14":   PN = "AU68"  !CDS_PN = "AU68";
"RSVD22":   PN = "AV67"  !CDS_PN = "AV67";
"RSVD62":   PN = "BL21"  !CDS_PN = "BL21";
"RSVD66":   PN = "BN21"  !CDS_PN = "BN21";
"RSVD73":   PN = "BV22"  !CDS_PN = "BV22";
"RSVD74":   PN = "BW21"  !CDS_PN = "BW21";
"RSVD75":   PN = "BW23"  !CDS_PN = "BW23";
"RSVD77":   PN = "CA21"  !CDS_PN = "CA21";
"RSVD78":   PN = "CA23"  !CDS_PN = "CA23";
"RSVD79":   PN = "CC21"  !CDS_PN = "CC21";
"RSVD80":   PN = "CC23"  !CDS_PN = "CC23";
"RSVD89":   PN = "CE21"  !CDS_PN = "CE21";
"RSVD118":   PN = "CL68"  !CDS_PN = "CL68";
"RSVD122":   PN = "CM69"  !CDS_PN = "CM69";
"RSVD130":   PN = "CP69"  !CDS_PN = "CP69";
"RSVD135":   PN = "CR68"  !CDS_PN = "CR68";
DRAWING = "@s9s_mb_2u_lib.s9s_mb_2u(sch_1):page51";
BODY = "SOCKET4677_AZIF0045P001C01CS","I2": LOCATION = "U1" #&CDS_LOCATION = "U1" &SEC = "8" #&CDS_SEC = "8";
"DDR0_A_RSP0":   PN = "AT42"  !CDS_PN = "AT42";
"DDR0_A_RSP1":   PN = "AU43"  !CDS_PN = "AU43";
"DDR0_ALERT_N":   PN = "AT49"  !CDS_PN = "AT49";
"DDR0_B_RSP0":   PN = "AV44"  !CDS_PN = "AV44";
"DDR0_B_RSP1":   PN = "AV42"  !CDS_PN = "AV42";
"DDR0_CLK_DN0":   PN = "B44"  !CDS_PN = "B44";
"DDR0_CLK_DN1":   PN = "G45"  !CDS_PN = "G45";
"DDR0_CLK_DP0":   PN = "C43"  !CDS_PN = "C43";
"DDR0_CLK_DP1":   PN = "E45"  !CDS_PN = "E45";
"DDR0_SA_CA0":   PN = "A52"  !CDS_PN = "A52";
"DDR0_SA_CA1":   PN = "G52"  !CDS_PN = "G52";
"DDR0_SA_CA2":   PN = "B51"  !CDS_PN = "B51";
"DDR0_SA_CA3":   PN = "F51"  !CDS_PN = "F51";
"DDR0_SA_CA4":   PN = "C50"  !CDS_PN = "C50";
"DDR0_SA_CA5":   PN = "E50"  !CDS_PN = "E50";
"DDR0_SA_CA6":   PN = "C48"  !CDS_PN = "C48";
"DDR0_SA_DQ0":   PN = "B81"  !CDS_PN = "B81";
"DDR0_SA_DQ1":   PN = "B79"  !CDS_PN = "B79";
"DDR0_SA_DQ2":   PN = "M77"  !CDS_PN = "M77";
"DDR0_SA_DQ3":   PN = "G78"  !CDS_PN = "G78";
"DDR0_SA_DQ4":   PN = "C76"  !CDS_PN = "C76";
"DDR0_SA_DQ5":   PN = "D75"  !CDS_PN = "D75";
"DDR0_SA_DQ6":   PN = "G76"  !CDS_PN = "G76";
"DDR0_SA_DQ7":   PN = "F75"  !CDS_PN = "F75";
"DDR0_SA_DQ8":   PN = "K69"  !CDS_PN = "K69";
"DDR0_SA_DQ9":   PN = "J68"  !CDS_PN = "J68";
"DDR0_SA_DQ10":   PN = "M69"  !CDS_PN = "M69";
"DDR0_SA_DQ11":   PN = "N68"  !CDS_PN = "N68";
"DDR0_SA_DQ12":   PN = "J66"  !CDS_PN = "J66";
"DDR0_SA_DQ13":   PN = "K65"  !CDS_PN = "K65";
"DDR0_SA_DQ14":   PN = "N66"  !CDS_PN = "N66";
"DDR0_SA_DQ15":   PN = "M65"  !CDS_PN = "M65";
"DDR0_SA_DQ16":   PN = "B73"  !CDS_PN = "B73";
"DDR0_SA_DQ17":   PN = "E72"  !CDS_PN = "E72";
"DDR0_SA_DQ18":   PN = "D73"  !CDS_PN = "D73";
"DDR0_SA_DQ19":   PN = "F71"  !CDS_PN = "F71";
"DDR0_SA_DQ20":   PN = "B69"  !CDS_PN = "B69";
"DDR0_SA_DQ21":   PN = "C68"  !CDS_PN = "C68";
"DDR0_SA_DQ22":   PN = "F69"  !CDS_PN = "F69";
"DDR0_SA_DQ23":   PN = "E68"  !CDS_PN = "E68";
"DDR0_SA_DQ24":   PN = "C66"  !CDS_PN = "C66";
"DDR0_SA_DQ25":   PN = "B65"  !CDS_PN = "B65";
"DDR0_SA_DQ26":   PN = "E66"  !CDS_PN = "E66";
"DDR0_SA_DQ27":   PN = "F65"  !CDS_PN = "F65";
"DDR0_SA_DQ28":   PN = "B63"  !CDS_PN = "B63";
"DDR0_SA_DQ29":   PN = "C62"  !CDS_PN = "C62";
"DDR0_SA_DQ30":   PN = "F63"  !CDS_PN = "F63";
"DDR0_SA_DQ31":   PN = "E62"  !CDS_PN = "E62";
"DDR0_SA_DQS_DN0":   PN = "B77"  !CDS_PN = "B77";
"DDR0_SA_DQS_DN1":   PN = "H67"  !CDS_PN = "H67";
"DDR0_SA_DQS_DN2":   PN = "B71"  !CDS_PN = "B71";
"DDR0_SA_DQS_DN3":   PN = "A64"  !CDS_PN = "A64";
"DDR0_SA_DQS_DN4":   PN = "A58"  !CDS_PN = "A58";
"DDR0_SA_DQS_DN5":   PN = "H77"  !CDS_PN = "H77";
"DDR0_SA_DQS_DN6":   PN = "P67"  !CDS_PN = "P67";
"DDR0_SA_DQS_DN7":   PN = "G70"  !CDS_PN = "G70";
"DDR0_SA_DQS_DN8":   PN = "G64"  !CDS_PN = "G64";
"DDR0_SA_DQS_DN9":   PN = "G58"  !CDS_PN = "G58";
"DDR0_SA_DQS_DP0":   PN = "D77"  !CDS_PN = "D77";
"DDR0_SA_DQS_DP1":   PN = "K67"  !CDS_PN = "K67";
"DDR0_SA_DQS_DP2":   PN = "C70"  !CDS_PN = "C70";
"DDR0_SA_DQS_DP3":   PN = "C64"  !CDS_PN = "C64";
"DDR0_SA_DQS_DP4":   PN = "C58"  !CDS_PN = "C58";
"DDR0_SA_DQS_DP5":   PN = "F77"  !CDS_PN = "F77";
"DDR0_SA_DQS_DP6":   PN = "M67"  !CDS_PN = "M67";
"DDR0_SA_DQS_DP7":   PN = "E70"  !CDS_PN = "E70";
"DDR0_SA_DQS_DP8":   PN = "E64"  !CDS_PN = "E64";
"DDR0_SA_DQS_DP9":   PN = "E58"  !CDS_PN = "E58";
"DDR0_SA_ECC0":   PN = "C60"  !CDS_PN = "C60";
"DDR0_SA_ECC1":   PN = "B59"  !CDS_PN = "B59";
"DDR0_SA_ECC2":   PN = "E60"  !CDS_PN = "E60";
"DDR0_SA_ECC3":   PN = "F59"  !CDS_PN = "F59";
"DDR0_SA_ECC4":   PN = "B57"  !CDS_PN = "B57";
"DDR0_SA_ECC5":   PN = "C56"  !CDS_PN = "C56";
"DDR0_SA_ECC6":   PN = "F57"  !CDS_PN = "F57";
"DDR0_SA_ECC7":   PN = "E56"  !CDS_PN = "E56";
"DDR0_SA_PAR":   PN = "E48"  !CDS_PN = "E48";
"DDR0_SB_CA0":   PN = "E43"  !CDS_PN = "E43";
"DDR0_SB_CA1":   PN = "F44"  !CDS_PN = "F44";
"DDR0_SB_CA2":   PN = "C41"  !CDS_PN = "C41";
"DDR0_SB_CA3":   PN = "E41"  !CDS_PN = "E41";
"DDR0_SB_CA4":   PN = "B40"  !CDS_PN = "B40";
"DDR0_SB_CA5":   PN = "F40"  !CDS_PN = "F40";
"DDR0_SB_CA6":   PN = "A39"  !CDS_PN = "A39";
"DDR0_SB_DQ0":   PN = "K32"  !CDS_PN = "K32";
"DDR0_SB_DQ1":   PN = "J31"  !CDS_PN = "J31";
"DDR0_SB_DQ2":   PN = "M32"  !CDS_PN = "M32";
"DDR0_SB_DQ3":   PN = "N31"  !CDS_PN = "N31";
"DDR0_SB_DQ4":   PN = "J29"  !CDS_PN = "J29";
"DDR0_SB_DQ5":   PN = "K28"  !CDS_PN = "K28";
"DDR0_SB_DQ6":   PN = "N29"  !CDS_PN = "N29";
"DDR0_SB_DQ7":   PN = "M28"  !CDS_PN = "M28";
"DDR0_SB_DQ8":   PN = "C29"  !CDS_PN = "C29";
"DDR0_SB_DQ9":   PN = "B28"  !CDS_PN = "B28";
"DDR0_SB_DQ10":   PN = "E29"  !CDS_PN = "E29";
"DDR0_SB_DQ11":   PN = "F28"  !CDS_PN = "F28";
"DDR0_SB_DQ12":   PN = "B26"  !CDS_PN = "B26";
"DDR0_SB_DQ13":   PN = "C25"  !CDS_PN = "C25";
"DDR0_SB_DQ14":   PN = "F26"  !CDS_PN = "F26";
"DDR0_SB_DQ15":   PN = "E25"  !CDS_PN = "E25";
"DDR0_SB_DQ16":   PN = "C23"  !CDS_PN = "C23";
"DDR0_SB_DQ17":   PN = "B22"  !CDS_PN = "B22";
"DDR0_SB_DQ18":   PN = "E23"  !CDS_PN = "E23";
"DDR0_SB_DQ19":   PN = "F22"  !CDS_PN = "F22";
"DDR0_SB_DQ20":   PN = "B20"  !CDS_PN = "B20";
"DDR0_SB_DQ21":   PN = "C19"  !CDS_PN = "C19";
"DDR0_SB_DQ22":   PN = "F20"  !CDS_PN = "F20";
"DDR0_SB_DQ23":   PN = "E19"  !CDS_PN = "E19";
"DDR0_SB_DQ24":   PN = "C11"  !CDS_PN = "C11";
"DDR0_SB_DQ25":   PN = "B10"  !CDS_PN = "B10";
"DDR0_SB_DQ26":   PN = "E11"  !CDS_PN = "E11";
"DDR0_SB_DQ27":   PN = "F10"  !CDS_PN = "F10";
"DDR0_SB_DQ28":   PN = "B8"  !CDS_PN = "B8";
"DDR0_SB_DQ29":   PN = "C7"  !CDS_PN = "C7";
"DDR0_SB_DQ30":   PN = "F8"  !CDS_PN = "F8";
"DDR0_SB_DQ31":   PN = "E7"  !CDS_PN = "E7";
"DDR0_SB_DQS_DN0":   PN = "H30"  !CDS_PN = "H30";
"DDR0_SB_DQS_DN1":   PN = "A27"  !CDS_PN = "A27";
"DDR0_SB_DQS_DN2":   PN = "A21"  !CDS_PN = "A21";
"DDR0_SB_DQS_DN3":   PN = "A9"  !CDS_PN = "A9";
"DDR0_SB_DQS_DN4":   PN = "G33"  !CDS_PN = "G33";
"DDR0_SB_DQS_DN5":   PN = "M30"  !CDS_PN = "M30";
"DDR0_SB_DQS_DN6":   PN = "G27"  !CDS_PN = "G27";
"DDR0_SB_DQS_DN7":   PN = "G21"  !CDS_PN = "G21";
"DDR0_SB_DQS_DN8":   PN = "G9"  !CDS_PN = "G9";
"DDR0_SB_DQS_DN9":   PN = "A33"  !CDS_PN = "A33";
"DDR0_SB_DQS_DP0":   PN = "K30"  !CDS_PN = "K30";
"DDR0_SB_DQS_DP1":   PN = "C27"  !CDS_PN = "C27";
"DDR0_SB_DQS_DP2":   PN = "C21"  !CDS_PN = "C21";
"DDR0_SB_DQS_DP3":   PN = "C9"  !CDS_PN = "C9";
"DDR0_SB_DQS_DP4":   PN = "E33"  !CDS_PN = "E33";
"DDR0_SB_DQS_DP5":   PN = "P30"  !CDS_PN = "P30";
"DDR0_SB_DQS_DP6":   PN = "E27"  !CDS_PN = "E27";
"DDR0_SB_DQS_DP7":   PN = "E21"  !CDS_PN = "E21";
"DDR0_SB_DQS_DP8":   PN = "E9"  !CDS_PN = "E9";
"DDR0_SB_DQS_DP9":   PN = "C33"  !CDS_PN = "C33";
"DDR0_SB_ECC0":   PN = "B32"  !CDS_PN = "B32";
"DDR0_SB_ECC1":   PN = "C31"  !CDS_PN = "C31";
"DDR0_SB_ECC2":   PN = "F32"  !CDS_PN = "F32";
"DDR0_SB_ECC3":   PN = "E31"  !CDS_PN = "E31";
"DDR0_SB_ECC4":   PN = "C35"  !CDS_PN = "C35";
"DDR0_SB_ECC5":   PN = "B34"  !CDS_PN = "B34";
"DDR0_SB_ECC6":   PN = "E35"  !CDS_PN = "E35";
"DDR0_SB_ECC7":   PN = "F34"  !CDS_PN = "F34";
"DDR0_SB_PAR":   PN = "G39"  !CDS_PN = "G39";
"DDR0_SA_CS_N0":   PN = "C54"  !CDS_PN = "C54";
"DDR0_SA_CS_N1":   PN = "B53"  !CDS_PN = "B53";
"DDR0_SA_CS_N2":   PN = "E54"  !CDS_PN = "E54";
"DDR0_SA_CS_N3":   PN = "F53"  !CDS_PN = "F53";
"DDR0_SB_CS_N0":   PN = "B38"  !CDS_PN = "B38";
"DDR0_SB_CS_N1":   PN = "C37"  !CDS_PN = "C37";
"DDR0_SB_CS_N2":   PN = "F38"  !CDS_PN = "F38";
"DDR0_SB_CS_N3":   PN = "E37"  !CDS_PN = "E37";
DRAWING = "@s9s_mb_2u_lib.s9s_mb_2u(sch_1):page52";
BODY = "SOCKET4677_AZIF0045P001C01CS","I91": LOCATION = "U1" #&CDS_LOCATION = "U1" &SEC = "9" #&CDS_SEC = "9";
"DDR1_A_RSP0":   PN = "AL48"  !CDS_PN = "AL48";
"DDR1_A_RSP1":   PN = "AK47"  !CDS_PN = "AK47";
"DDR1_ALERT_N":   PN = "AV49"  !CDS_PN = "AV49";
"DDR1_B_RSP0":   PN = "AN48"  !CDS_PN = "AN48";
"DDR1_B_RSP1":   PN = "AP47"  !CDS_PN = "AP47";
"DDR1_CLK_DN0":   PN = "R45"  !CDS_PN = "R45";
"DDR1_CLK_DN1":   PN = "W45"  !CDS_PN = "W45";
"DDR1_CLK_DP0":   PN = "U45"  !CDS_PN = "U45";
"DDR1_CLK_DP1":   PN = "AA45"  !CDS_PN = "AA45";
"DDR1_SA_CA0":   PN = "H49"  !CDS_PN = "H49";
"DDR1_SA_CA1":   PN = "P49"  !CDS_PN = "P49";
"DDR1_SA_CA2":   PN = "J48"  !CDS_PN = "J48";
"DDR1_SA_CA3":   PN = "N48"  !CDS_PN = "N48";
"DDR1_SA_CA4":   PN = "K47"  !CDS_PN = "K47";
"DDR1_SA_CA5":   PN = "M47"  !CDS_PN = "M47";
"DDR1_SA_CA6":   PN = "Y44"  !CDS_PN = "Y44";
"DDR1_SA_DQ0":   PN = "K75"  !CDS_PN = "K75";
"DDR1_SA_DQ1":   PN = "J74"  !CDS_PN = "J74";
"DDR1_SA_DQ2":   PN = "M75"  !CDS_PN = "M75";
"DDR1_SA_DQ3":   PN = "N74"  !CDS_PN = "N74";
"DDR1_SA_DQ4":   PN = "J72"  !CDS_PN = "J72";
"DDR1_SA_DQ5":   PN = "K71"  !CDS_PN = "K71";
"DDR1_SA_DQ6":   PN = "N72"  !CDS_PN = "N72";
"DDR1_SA_DQ7":   PN = "M71"  !CDS_PN = "M71";
"DDR1_SA_DQ8":   PN = "U72"  !CDS_PN = "U72";
"DDR1_SA_DQ9":   PN = "T71"  !CDS_PN = "T71";
"DDR1_SA_DQ10":   PN = "W72"  !CDS_PN = "W72";
"DDR1_SA_DQ11":   PN = "Y71"  !CDS_PN = "Y71";
"DDR1_SA_DQ12":   PN = "T69"  !CDS_PN = "T69";
"DDR1_SA_DQ13":   PN = "U68"  !CDS_PN = "U68";
"DDR1_SA_DQ14":   PN = "Y69"  !CDS_PN = "Y69";
"DDR1_SA_DQ15":   PN = "W68"  !CDS_PN = "W68";
"DDR1_SA_DQ16":   PN = "K63"  !CDS_PN = "K63";
"DDR1_SA_DQ17":   PN = "J62"  !CDS_PN = "J62";
"DDR1_SA_DQ18":   PN = "M63"  !CDS_PN = "M63";
"DDR1_SA_DQ19":   PN = "N62"  !CDS_PN = "N62";
"DDR1_SA_DQ20":   PN = "J60"  !CDS_PN = "J60";
"DDR1_SA_DQ21":   PN = "K59"  !CDS_PN = "K59";
"DDR1_SA_DQ22":   PN = "N60"  !CDS_PN = "N60";
"DDR1_SA_DQ23":   PN = "M59"  !CDS_PN = "M59";
"DDR1_SA_DQ24":   PN = "U60"  !CDS_PN = "U60";
"DDR1_SA_DQ25":   PN = "T59"  !CDS_PN = "T59";
"DDR1_SA_DQ26":   PN = "W60"  !CDS_PN = "W60";
"DDR1_SA_DQ27":   PN = "Y59"  !CDS_PN = "Y59";
"DDR1_SA_DQ28":   PN = "T57"  !CDS_PN = "T57";
"DDR1_SA_DQ29":   PN = "U56"  !CDS_PN = "U56";
"DDR1_SA_DQ30":   PN = "Y57"  !CDS_PN = "Y57";
"DDR1_SA_DQ31":   PN = "W56"  !CDS_PN = "W56";
"DDR1_SA_DQS_DN0":   PN = "H73"  !CDS_PN = "H73";
"DDR1_SA_DQS_DN1":   PN = "R70"  !CDS_PN = "R70";
"DDR1_SA_DQS_DN2":   PN = "H61"  !CDS_PN = "H61";
"DDR1_SA_DQS_DN3":   PN = "R58"  !CDS_PN = "R58";
"DDR1_SA_DQS_DN4":   PN = "H55"  !CDS_PN = "H55";
"DDR1_SA_DQS_DN5":   PN = "M73"  !CDS_PN = "M73";
"DDR1_SA_DQS_DN6":   PN = "AA70"  !CDS_PN = "AA70";
"DDR1_SA_DQS_DN7":   PN = "M61"  !CDS_PN = "M61";
"DDR1_SA_DQS_DN8":   PN = "AA58"  !CDS_PN = "AA58";
"DDR1_SA_DQS_DN9":   PN = "M55"  !CDS_PN = "M55";
"DDR1_SA_DQS_DP0":   PN = "K73"  !CDS_PN = "K73";
"DDR1_SA_DQS_DP1":   PN = "U70"  !CDS_PN = "U70";
"DDR1_SA_DQS_DP2":   PN = "K61"  !CDS_PN = "K61";
"DDR1_SA_DQS_DP3":   PN = "U58"  !CDS_PN = "U58";
"DDR1_SA_DQS_DP4":   PN = "K55"  !CDS_PN = "K55";
"DDR1_SA_DQS_DP5":   PN = "P73"  !CDS_PN = "P73";
"DDR1_SA_DQS_DP6":   PN = "W70"  !CDS_PN = "W70";
"DDR1_SA_DQS_DP7":   PN = "P61"  !CDS_PN = "P61";
"DDR1_SA_DQS_DP8":   PN = "W58"  !CDS_PN = "W58";
"DDR1_SA_DQS_DP9":   PN = "P55"  !CDS_PN = "P55";
"DDR1_SA_ECC0":   PN = "K57"  !CDS_PN = "K57";
"DDR1_SA_ECC1":   PN = "J56"  !CDS_PN = "J56";
"DDR1_SA_ECC2":   PN = "M57"  !CDS_PN = "M57";
"DDR1_SA_ECC3":   PN = "N56"  !CDS_PN = "N56";
"DDR1_SA_ECC4":   PN = "J54"  !CDS_PN = "J54";
"DDR1_SA_ECC5":   PN = "K53"  !CDS_PN = "K53";
"DDR1_SA_ECC6":   PN = "N54"  !CDS_PN = "N54";
"DDR1_SA_ECC7":   PN = "M53"  !CDS_PN = "M53";
"DDR1_SA_PAR":   PN = "W43"  !CDS_PN = "W43";
"DDR1_SB_CA0":   PN = "T44"  !CDS_PN = "T44";
"DDR1_SB_CA1":   PN = "U43"  !CDS_PN = "U43";
"DDR1_SB_CA2":   PN = "K44"  !CDS_PN = "K44";
"DDR1_SB_CA3":   PN = "M44"  !CDS_PN = "M44";
"DDR1_SB_CA4":   PN = "J43"  !CDS_PN = "J43";
"DDR1_SB_CA5":   PN = "N43"  !CDS_PN = "N43";
"DDR1_SB_CA6":   PN = "H42"  !CDS_PN = "H42";
"DDR1_SB_DQ0":   PN = "U29"  !CDS_PN = "U29";
"DDR1_SB_DQ1":   PN = "T28"  !CDS_PN = "T28";
"DDR1_SB_DQ2":   PN = "W29"  !CDS_PN = "W29";
"DDR1_SB_DQ3":   PN = "Y28"  !CDS_PN = "Y28";
"DDR1_SB_DQ4":   PN = "T26"  !CDS_PN = "T26";
"DDR1_SB_DQ5":   PN = "U25"  !CDS_PN = "U25";
"DDR1_SB_DQ6":   PN = "Y26"  !CDS_PN = "Y26";
"DDR1_SB_DQ7":   PN = "W25"  !CDS_PN = "W25";
"DDR1_SB_DQ8":   PN = "K26"  !CDS_PN = "K26";
"DDR1_SB_DQ9":   PN = "J25"  !CDS_PN = "J25";
"DDR1_SB_DQ10":   PN = "M26"  !CDS_PN = "M26";
"DDR1_SB_DQ11":   PN = "N25"  !CDS_PN = "N25";
"DDR1_SB_DQ12":   PN = "J23"  !CDS_PN = "J23";
"DDR1_SB_DQ13":   PN = "K22"  !CDS_PN = "K22";
"DDR1_SB_DQ14":   PN = "N23"  !CDS_PN = "N23";
"DDR1_SB_DQ15":   PN = "M22"  !CDS_PN = "M22";
"DDR1_SB_DQ16":   PN = "K20"  !CDS_PN = "K20";
"DDR1_SB_DQ17":   PN = "J19"  !CDS_PN = "J19";
"DDR1_SB_DQ18":   PN = "M20"  !CDS_PN = "M20";
"DDR1_SB_DQ19":   PN = "N19"  !CDS_PN = "N19";
"DDR1_SB_DQ20":   PN = "J17"  !CDS_PN = "J17";
"DDR1_SB_DQ21":   PN = "K16"  !CDS_PN = "K16";
"DDR1_SB_DQ22":   PN = "N17"  !CDS_PN = "N17";
"DDR1_SB_DQ23":   PN = "M16"  !CDS_PN = "M16";
"DDR1_SB_DQ24":   PN = "C17"  !CDS_PN = "C17";
"DDR1_SB_DQ25":   PN = "B16"  !CDS_PN = "B16";
"DDR1_SB_DQ26":   PN = "E17"  !CDS_PN = "E17";
"DDR1_SB_DQ27":   PN = "F16"  !CDS_PN = "F16";
"DDR1_SB_DQ28":   PN = "C13"  !CDS_PN = "C13";
"DDR1_SB_DQ29":   PN = "E13"  !CDS_PN = "E13";
"DDR1_SB_DQ30":   PN = "B14"  !CDS_PN = "B14";
"DDR1_SB_DQ31":   PN = "F14"  !CDS_PN = "F14";
"DDR1_SB_DQS_DN0":   PN = "R27"  !CDS_PN = "R27";
"DDR1_SB_DQS_DN1":   PN = "H24"  !CDS_PN = "H24";
"DDR1_SB_DQS_DN2":   PN = "H18"  !CDS_PN = "H18";
"DDR1_SB_DQS_DN3":   PN = "A15"  !CDS_PN = "A15";
"DDR1_SB_DQS_DN4":   PN = "P36"  !CDS_PN = "P36";
"DDR1_SB_DQS_DN5":   PN = "W27"  !CDS_PN = "W27";
"DDR1_SB_DQS_DN6":   PN = "M24"  !CDS_PN = "M24";
"DDR1_SB_DQS_DN7":   PN = "M18"  !CDS_PN = "M18";
"DDR1_SB_DQS_DN8":   PN = "E15"  !CDS_PN = "E15";
"DDR1_SB_DQS_DN9":   PN = "K36"  !CDS_PN = "K36";
"DDR1_SB_DQS_DP0":   PN = "U27"  !CDS_PN = "U27";
"DDR1_SB_DQS_DP1":   PN = "K24"  !CDS_PN = "K24";
"DDR1_SB_DQS_DP2":   PN = "K18"  !CDS_PN = "K18";
"DDR1_SB_DQS_DP3":   PN = "C15"  !CDS_PN = "C15";
"DDR1_SB_DQS_DP4":   PN = "M36"  !CDS_PN = "M36";
"DDR1_SB_DQS_DP5":   PN = "AA27"  !CDS_PN = "AA27";
"DDR1_SB_DQS_DP6":   PN = "P24"  !CDS_PN = "P24";
"DDR1_SB_DQS_DP7":   PN = "P18"  !CDS_PN = "P18";
"DDR1_SB_DQS_DP8":   PN = "G15"  !CDS_PN = "G15";
"DDR1_SB_DQS_DP9":   PN = "H36"  !CDS_PN = "H36";
"DDR1_SB_ECC0":   PN = "J35"  !CDS_PN = "J35";
"DDR1_SB_ECC1":   PN = "K34"  !CDS_PN = "K34";
"DDR1_SB_ECC2":   PN = "N35"  !CDS_PN = "N35";
"DDR1_SB_ECC3":   PN = "M34"  !CDS_PN = "M34";
"DDR1_SB_ECC4":   PN = "K38"  !CDS_PN = "K38";
"DDR1_SB_ECC5":   PN = "J37"  !CDS_PN = "J37";
"DDR1_SB_ECC6":   PN = "M38"  !CDS_PN = "M38";
"DDR1_SB_ECC7":   PN = "N37"  !CDS_PN = "N37";
"DDR1_SB_PAR":   PN = "P42"  !CDS_PN = "P42";
"DDR1_SA_CS_N0":   PN = "K51"  !CDS_PN = "K51";
"DDR1_SA_CS_N1":   PN = "J50"  !CDS_PN = "J50";
"DDR1_SA_CS_N2":   PN = "M51"  !CDS_PN = "M51";
"DDR1_SA_CS_N3":   PN = "N50"  !CDS_PN = "N50";
"DDR1_SB_CS_N0":   PN = "J41"  !CDS_PN = "J41";
"DDR1_SB_CS_N1":   PN = "K40"  !CDS_PN = "K40";
"DDR1_SB_CS_N2":   PN = "N41"  !CDS_PN = "N41";
"DDR1_SB_CS_N3":   PN = "M40"  !CDS_PN = "M40";
DRAWING = "@s9s_mb_2u_lib.s9s_mb_2u(sch_1):page53";
BODY = "SOCKET4677_AZIF0045P001C01CS","I91": LOCATION = "U1" #&CDS_LOCATION = "U1" &SEC = "10" #&CDS_SEC = "10";
"DDR2_A_RSP0":   PN = "AC48"  !CDS_PN = "AC48";
"DDR2_A_RSP1":   PN = "AD47"  !CDS_PN = "AD47";
"DDR2_ALERT_N":   PN = "AT47"  !CDS_PN = "AT47";
"DDR2_B_RSP0":   PN = "AG48"  !CDS_PN = "AG48";
"DDR2_B_RSP1":   PN = "AF47"  !CDS_PN = "AF47";
"DDR2_CLK_DN0":   PN = "AB49"  !CDS_PN = "AB49";
"DDR2_CLK_DN1":   PN = "AF49"  !CDS_PN = "AF49";
"DDR2_CLK_DP0":   PN = "AD49"  !CDS_PN = "AD49";
"DDR2_CLK_DP1":   PN = "AH49"  !CDS_PN = "AH49";
"DDR2_SA_CA0":   PN = "R52"  !CDS_PN = "R52";
"DDR2_SA_CA1":   PN = "AA52"  !CDS_PN = "AA52";
"DDR2_SA_CA2":   PN = "T51"  !CDS_PN = "T51";
"DDR2_SA_CA3":   PN = "Y51"  !CDS_PN = "Y51";
"DDR2_SA_CA4":   PN = "U50"  !CDS_PN = "U50";
"DDR2_SA_CA5":   PN = "W50"  !CDS_PN = "W50";
"DDR2_SA_CA6":   PN = "U48"  !CDS_PN = "U48";
"DDR2_SA_DQ0":   PN = "U78"  !CDS_PN = "U78";
"DDR2_SA_DQ1":   PN = "T77"  !CDS_PN = "T77";
"DDR2_SA_DQ2":   PN = "W78"  !CDS_PN = "W78";
"DDR2_SA_DQ3":   PN = "Y77"  !CDS_PN = "Y77";
"DDR2_SA_DQ4":   PN = "T75"  !CDS_PN = "T75";
"DDR2_SA_DQ5":   PN = "U74"  !CDS_PN = "U74";
"DDR2_SA_DQ6":   PN = "Y75"  !CDS_PN = "Y75";
"DDR2_SA_DQ7":   PN = "W74"  !CDS_PN = "W74";
"DDR2_SA_DQ8":   PN = "AD69"  !CDS_PN = "AD69";
"DDR2_SA_DQ9":   PN = "AC68"  !CDS_PN = "AC68";
"DDR2_SA_DQ10":   PN = "AF69"  !CDS_PN = "AF69";
"DDR2_SA_DQ11":   PN = "AG68"  !CDS_PN = "AG68";
"DDR2_SA_DQ12":   PN = "AC66"  !CDS_PN = "AC66";
"DDR2_SA_DQ13":   PN = "AD65"  !CDS_PN = "AD65";
"DDR2_SA_DQ14":   PN = "AG66"  !CDS_PN = "AG66";
"DDR2_SA_DQ15":   PN = "AF65"  !CDS_PN = "AF65";
"DDR2_SA_DQ16":   PN = "U66"  !CDS_PN = "U66";
"DDR2_SA_DQ17":   PN = "T65"  !CDS_PN = "T65";
"DDR2_SA_DQ18":   PN = "W66"  !CDS_PN = "W66";
"DDR2_SA_DQ19":   PN = "Y65"  !CDS_PN = "Y65";
"DDR2_SA_DQ20":   PN = "T63"  !CDS_PN = "T63";
"DDR2_SA_DQ21":   PN = "U62"  !CDS_PN = "U62";
"DDR2_SA_DQ22":   PN = "Y63"  !CDS_PN = "Y63";
"DDR2_SA_DQ23":   PN = "W62"  !CDS_PN = "W62";
"DDR2_SA_DQ24":   PN = "AD63"  !CDS_PN = "AD63";
"DDR2_SA_DQ25":   PN = "AC62"  !CDS_PN = "AC62";
"DDR2_SA_DQ26":   PN = "AF63"  !CDS_PN = "AF63";
"DDR2_SA_DQ27":   PN = "AG62"  !CDS_PN = "AG62";
"DDR2_SA_DQ28":   PN = "AC60"  !CDS_PN = "AC60";
"DDR2_SA_DQ29":   PN = "AD59"  !CDS_PN = "AD59";
"DDR2_SA_DQ30":   PN = "AG60"  !CDS_PN = "AG60";
"DDR2_SA_DQ31":   PN = "AF59"  !CDS_PN = "AF59";
"DDR2_SA_DQS_DN0":   PN = "R76"  !CDS_PN = "R76";
"DDR2_SA_DQS_DN1":   PN = "AB67"  !CDS_PN = "AB67";
"DDR2_SA_DQS_DN2":   PN = "R64"  !CDS_PN = "R64";
"DDR2_SA_DQS_DN3":   PN = "AB61"  !CDS_PN = "AB61";
"DDR2_SA_DQS_DN4":   PN = "AD55"  !CDS_PN = "AD55";
"DDR2_SA_DQS_DN5":   PN = "W76"  !CDS_PN = "W76";
"DDR2_SA_DQS_DN6":   PN = "AH67"  !CDS_PN = "AH67";
"DDR2_SA_DQS_DN7":   PN = "AA64"  !CDS_PN = "AA64";
"DDR2_SA_DQS_DN8":   PN = "AF61"  !CDS_PN = "AF61";
"DDR2_SA_DQS_DN9":   PN = "AH55"  !CDS_PN = "AH55";
"DDR2_SA_DQS_DP0":   PN = "U76"  !CDS_PN = "U76";
"DDR2_SA_DQS_DP1":   PN = "AD67"  !CDS_PN = "AD67";
"DDR2_SA_DQS_DP2":   PN = "U64"  !CDS_PN = "U64";
"DDR2_SA_DQS_DP3":   PN = "AD61"  !CDS_PN = "AD61";
"DDR2_SA_DQS_DP4":   PN = "AB55"  !CDS_PN = "AB55";
"DDR2_SA_DQS_DP5":   PN = "AA76"  !CDS_PN = "AA76";
"DDR2_SA_DQS_DP6":   PN = "AF67"  !CDS_PN = "AF67";
"DDR2_SA_DQS_DP7":   PN = "W64"  !CDS_PN = "W64";
"DDR2_SA_DQS_DP8":   PN = "AH61"  !CDS_PN = "AH61";
"DDR2_SA_DQS_DP9":   PN = "AF55"  !CDS_PN = "AF55";
"DDR2_SA_ECC0":   PN = "AD57"  !CDS_PN = "AD57";
"DDR2_SA_ECC1":   PN = "AC56"  !CDS_PN = "AC56";
"DDR2_SA_ECC2":   PN = "AF57"  !CDS_PN = "AF57";
"DDR2_SA_ECC3":   PN = "AG56"  !CDS_PN = "AG56";
"DDR2_SA_ECC4":   PN = "AC54"  !CDS_PN = "AC54";
"DDR2_SA_ECC5":   PN = "AD53"  !CDS_PN = "AD53";
"DDR2_SA_ECC6":   PN = "AG54"  !CDS_PN = "AG54";
"DDR2_SA_ECC7":   PN = "AF53"  !CDS_PN = "AF53";
"DDR2_SA_PAR":   PN = "T47"  !CDS_PN = "T47";
"DDR2_SB_CA0":   PN = "W48"  !CDS_PN = "W48";
"DDR2_SB_CA1":   PN = "Y47"  !CDS_PN = "Y47";
"DDR2_SB_CA2":   PN = "U41"  !CDS_PN = "U41";
"DDR2_SB_CA3":   PN = "W41"  !CDS_PN = "W41";
"DDR2_SB_CA4":   PN = "T40"  !CDS_PN = "T40";
"DDR2_SB_CA5":   PN = "Y40"  !CDS_PN = "Y40";
"DDR2_SB_CA6":   PN = "R39"  !CDS_PN = "R39";
"DDR2_SB_DQ0":   PN = "AD38"  !CDS_PN = "AD38";
"DDR2_SB_DQ1":   PN = "AC37"  !CDS_PN = "AC37";
"DDR2_SB_DQ2":   PN = "AF38"  !CDS_PN = "AF38";
"DDR2_SB_DQ3":   PN = "AG37"  !CDS_PN = "AG37";
"DDR2_SB_DQ4":   PN = "AC35"  !CDS_PN = "AC35";
"DDR2_SB_DQ5":   PN = "AD34"  !CDS_PN = "AD34";
"DDR2_SB_DQ6":   PN = "AG35"  !CDS_PN = "AG35";
"DDR2_SB_DQ7":   PN = "AF34"  !CDS_PN = "AF34";
"DDR2_SB_DQ8":   PN = "AD32"  !CDS_PN = "AD32";
"DDR2_SB_DQ9":   PN = "AC31"  !CDS_PN = "AC31";
"DDR2_SB_DQ10":   PN = "AF32"  !CDS_PN = "AF32";
"DDR2_SB_DQ11":   PN = "AG31"  !CDS_PN = "AG31";
"DDR2_SB_DQ12":   PN = "AC29"  !CDS_PN = "AC29";
"DDR2_SB_DQ13":   PN = "AD28"  !CDS_PN = "AD28";
"DDR2_SB_DQ14":   PN = "AG29"  !CDS_PN = "AG29";
"DDR2_SB_DQ15":   PN = "AF28"  !CDS_PN = "AF28";
"DDR2_SB_DQ16":   PN = "U23"  !CDS_PN = "U23";
"DDR2_SB_DQ17":   PN = "T22"  !CDS_PN = "T22";
"DDR2_SB_DQ18":   PN = "W23"  !CDS_PN = "W23";
"DDR2_SB_DQ19":   PN = "Y22"  !CDS_PN = "Y22";
"DDR2_SB_DQ20":   PN = "T20"  !CDS_PN = "T20";
"DDR2_SB_DQ21":   PN = "U19"  !CDS_PN = "U19";
"DDR2_SB_DQ22":   PN = "Y20"  !CDS_PN = "Y20";
"DDR2_SB_DQ23":   PN = "W19"  !CDS_PN = "W19";
"DDR2_SB_DQ24":   PN = "AD20"  !CDS_PN = "AD20";
"DDR2_SB_DQ25":   PN = "AC19"  !CDS_PN = "AC19";
"DDR2_SB_DQ26":   PN = "AF20"  !CDS_PN = "AF20";
"DDR2_SB_DQ27":   PN = "AG19"  !CDS_PN = "AG19";
"DDR2_SB_DQ28":   PN = "AA17"  !CDS_PN = "AA17";
"DDR2_SB_DQ29":   PN = "AG17"  !CDS_PN = "AG17";
"DDR2_SB_DQ30":   PN = "AC17"  !CDS_PN = "AC17";
"DDR2_SB_DQ31":   PN = "AJ17"  !CDS_PN = "AJ17";
"DDR2_SB_DQS_DN0":   PN = "AB36"  !CDS_PN = "AB36";
"DDR2_SB_DQS_DN1":   PN = "AB30"  !CDS_PN = "AB30";
"DDR2_SB_DQS_DN2":   PN = "R21"  !CDS_PN = "R21";
"DDR2_SB_DQS_DN3":   PN = "AB18"  !CDS_PN = "AB18";
"DDR2_SB_DQS_DN4":   PN = "W33"  !CDS_PN = "W33";
"DDR2_SB_DQS_DN5":   PN = "AF36"  !CDS_PN = "AF36";
"DDR2_SB_DQS_DN6":   PN = "AF30"  !CDS_PN = "AF30";
"DDR2_SB_DQS_DN7":   PN = "W21"  !CDS_PN = "W21";
"DDR2_SB_DQS_DN8":   PN = "AF18"  !CDS_PN = "AF18";
"DDR2_SB_DQS_DN9":   PN = "R33"  !CDS_PN = "R33";
"DDR2_SB_DQS_DP0":   PN = "AD36"  !CDS_PN = "AD36";
"DDR2_SB_DQS_DP1":   PN = "AD30"  !CDS_PN = "AD30";
"DDR2_SB_DQS_DP2":   PN = "U21"  !CDS_PN = "U21";
"DDR2_SB_DQS_DP3":   PN = "AD18"  !CDS_PN = "AD18";
"DDR2_SB_DQS_DP4":   PN = "AA33"  !CDS_PN = "AA33";
"DDR2_SB_DQS_DP5":   PN = "AH36"  !CDS_PN = "AH36";
"DDR2_SB_DQS_DP6":   PN = "AH30"  !CDS_PN = "AH30";
"DDR2_SB_DQS_DP7":   PN = "AA21"  !CDS_PN = "AA21";
"DDR2_SB_DQS_DP8":   PN = "AH18"  !CDS_PN = "AH18";
"DDR2_SB_DQS_DP9":   PN = "U33"  !CDS_PN = "U33";
"DDR2_SB_ECC0":   PN = "T32"  !CDS_PN = "T32";
"DDR2_SB_ECC1":   PN = "U31"  !CDS_PN = "U31";
"DDR2_SB_ECC2":   PN = "Y32"  !CDS_PN = "Y32";
"DDR2_SB_ECC3":   PN = "W31"  !CDS_PN = "W31";
"DDR2_SB_ECC4":   PN = "U35"  !CDS_PN = "U35";
"DDR2_SB_ECC5":   PN = "T34"  !CDS_PN = "T34";
"DDR2_SB_ECC6":   PN = "W35"  !CDS_PN = "W35";
"DDR2_SB_ECC7":   PN = "Y34"  !CDS_PN = "Y34";
"DDR2_SB_PAR":   PN = "AA39"  !CDS_PN = "AA39";
"DDR2_SA_CS_N0":   PN = "U54"  !CDS_PN = "U54";
"DDR2_SA_CS_N1":   PN = "T53"  !CDS_PN = "T53";
"DDR2_SA_CS_N2":   PN = "W54"  !CDS_PN = "W54";
"DDR2_SA_CS_N3":   PN = "Y53"  !CDS_PN = "Y53";
"DDR2_SB_CS_N0":   PN = "T38"  !CDS_PN = "T38";
"DDR2_SB_CS_N1":   PN = "U37"  !CDS_PN = "U37";
"DDR2_SB_CS_N2":   PN = "Y38"  !CDS_PN = "Y38";
"DDR2_SB_CS_N3":   PN = "W37"  !CDS_PN = "W37";
DRAWING = "@s9s_mb_2u_lib.s9s_mb_2u(sch_1):page54";
BODY = "SOCKET4677_AZIF0045P001C01CS","I91": LOCATION = "U1" #&CDS_LOCATION = "U1" &SEC = "11" #&CDS_SEC = "11";
"DDR3_A_RSP0":   PN = "AD51"  !CDS_PN = "AD51";
"DDR3_A_RSP1":   PN = "AC50"  !CDS_PN = "AC50";
"DDR3_ALERT_N":   PN = "AV47"  !CDS_PN = "AV47";
"DDR3_B_RSP0":   PN = "AF51"  !CDS_PN = "AF51";
"DDR3_B_RSP1":   PN = "AG50"  !CDS_PN = "AG50";
"DDR3_CLK_DN0":   PN = "AJ45"  !CDS_PN = "AJ45";
"DDR3_CLK_DN1":   PN = "AN45"  !CDS_PN = "AN45";
"DDR3_CLK_DP0":   PN = "AL45"  !CDS_PN = "AL45";
"DDR3_CLK_DP1":   PN = "AR45"  !CDS_PN = "AR45";
"DDR3_SA_CA0":   PN = "AJ52"  !CDS_PN = "AJ52";
"DDR3_SA_CA1":   PN = "AR52"  !CDS_PN = "AR52";
"DDR3_SA_CA2":   PN = "AK51"  !CDS_PN = "AK51";
"DDR3_SA_CA3":   PN = "AP51"  !CDS_PN = "AP51";
"DDR3_SA_CA4":   PN = "AL50"  !CDS_PN = "AL50";
"DDR3_SA_CA5":   PN = "AN50"  !CDS_PN = "AN50";
"DDR3_SA_CA6":   PN = "AN43"  !CDS_PN = "AN43";
"DDR3_SA_DQ0":   PN = "AD75"  !CDS_PN = "AD75";
"DDR3_SA_DQ1":   PN = "AC74"  !CDS_PN = "AC74";
"DDR3_SA_DQ2":   PN = "AF75"  !CDS_PN = "AF75";
"DDR3_SA_DQ3":   PN = "AG74"  !CDS_PN = "AG74";
"DDR3_SA_DQ4":   PN = "AC72"  !CDS_PN = "AC72";
"DDR3_SA_DQ5":   PN = "AD71"  !CDS_PN = "AD71";
"DDR3_SA_DQ6":   PN = "AG72"  !CDS_PN = "AG72";
"DDR3_SA_DQ7":   PN = "AF71"  !CDS_PN = "AF71";
"DDR3_SA_DQ8":   PN = "AL78"  !CDS_PN = "AL78";
"DDR3_SA_DQ9":   PN = "AK77"  !CDS_PN = "AK77";
"DDR3_SA_DQ10":   PN = "AN78"  !CDS_PN = "AN78";
"DDR3_SA_DQ11":   PN = "AP77"  !CDS_PN = "AP77";
"DDR3_SA_DQ12":   PN = "AK75"  !CDS_PN = "AK75";
"DDR3_SA_DQ13":   PN = "AL74"  !CDS_PN = "AL74";
"DDR3_SA_DQ14":   PN = "AP75"  !CDS_PN = "AP75";
"DDR3_SA_DQ15":   PN = "AN74"  !CDS_PN = "AN74";
"DDR3_SA_DQ16":   PN = "AL72"  !CDS_PN = "AL72";
"DDR3_SA_DQ17":   PN = "AK71"  !CDS_PN = "AK71";
"DDR3_SA_DQ18":   PN = "AN72"  !CDS_PN = "AN72";
"DDR3_SA_DQ19":   PN = "AP71"  !CDS_PN = "AP71";
"DDR3_SA_DQ20":   PN = "AK69"  !CDS_PN = "AK69";
"DDR3_SA_DQ21":   PN = "AL68"  !CDS_PN = "AL68";
"DDR3_SA_DQ22":   PN = "AP69"  !CDS_PN = "AP69";
"DDR3_SA_DQ23":   PN = "AN68"  !CDS_PN = "AN68";
"DDR3_SA_DQ24":   PN = "AL66"  !CDS_PN = "AL66";
"DDR3_SA_DQ25":   PN = "AK65"  !CDS_PN = "AK65";
"DDR3_SA_DQ26":   PN = "AN66"  !CDS_PN = "AN66";
"DDR3_SA_DQ27":   PN = "AP65"  !CDS_PN = "AP65";
"DDR3_SA_DQ28":   PN = "AK63"  !CDS_PN = "AK63";
"DDR3_SA_DQ29":   PN = "AL62"  !CDS_PN = "AL62";
"DDR3_SA_DQ30":   PN = "AP63"  !CDS_PN = "AP63";
"DDR3_SA_DQ31":   PN = "AN62"  !CDS_PN = "AN62";
"DDR3_SA_DQS_DN0":   PN = "AB73"  !CDS_PN = "AB73";
"DDR3_SA_DQS_DN1":   PN = "AJ76"  !CDS_PN = "AJ76";
"DDR3_SA_DQS_DN2":   PN = "AJ70"  !CDS_PN = "AJ70";
"DDR3_SA_DQS_DN3":   PN = "AJ64"  !CDS_PN = "AJ64";
"DDR3_SA_DQS_DN4":   PN = "AJ58"  !CDS_PN = "AJ58";
"DDR3_SA_DQS_DN5":   PN = "AH73"  !CDS_PN = "AH73";
"DDR3_SA_DQS_DN6":   PN = "AN76"  !CDS_PN = "AN76";
"DDR3_SA_DQS_DN7":   PN = "AN70"  !CDS_PN = "AN70";
"DDR3_SA_DQS_DN8":   PN = "AN64"  !CDS_PN = "AN64";
"DDR3_SA_DQS_DN9":   PN = "AN58"  !CDS_PN = "AN58";
"DDR3_SA_DQS_DP0":   PN = "AD73"  !CDS_PN = "AD73";
"DDR3_SA_DQS_DP1":   PN = "AL76"  !CDS_PN = "AL76";
"DDR3_SA_DQS_DP2":   PN = "AL70"  !CDS_PN = "AL70";
"DDR3_SA_DQS_DP3":   PN = "AL64"  !CDS_PN = "AL64";
"DDR3_SA_DQS_DP4":   PN = "AL58"  !CDS_PN = "AL58";
"DDR3_SA_DQS_DP5":   PN = "AF73"  !CDS_PN = "AF73";
"DDR3_SA_DQS_DP6":   PN = "AR76"  !CDS_PN = "AR76";
"DDR3_SA_DQS_DP7":   PN = "AR70"  !CDS_PN = "AR70";
"DDR3_SA_DQS_DP8":   PN = "AR64"  !CDS_PN = "AR64";
"DDR3_SA_DQS_DP9":   PN = "AR58"  !CDS_PN = "AR58";
"DDR3_SA_ECC0":   PN = "AL60"  !CDS_PN = "AL60";
"DDR3_SA_ECC1":   PN = "AK59"  !CDS_PN = "AK59";
"DDR3_SA_ECC2":   PN = "AN60"  !CDS_PN = "AN60";
"DDR3_SA_ECC3":   PN = "AP59"  !CDS_PN = "AP59";
"DDR3_SA_ECC4":   PN = "AK57"  !CDS_PN = "AK57";
"DDR3_SA_ECC5":   PN = "AL56"  !CDS_PN = "AL56";
"DDR3_SA_ECC6":   PN = "AP57"  !CDS_PN = "AP57";
"DDR3_SA_ECC7":   PN = "AN56"  !CDS_PN = "AN56";
"DDR3_SA_PAR":   PN = "AP44"  !CDS_PN = "AP44";
"DDR3_SB_CA0":   PN = "AK44"  !CDS_PN = "AK44";
"DDR3_SB_CA1":   PN = "AL43"  !CDS_PN = "AL43";
"DDR3_SB_CA2":   PN = "AD44"  !CDS_PN = "AD44";
"DDR3_SB_CA3":   PN = "AF44"  !CDS_PN = "AF44";
"DDR3_SB_CA4":   PN = "AC43"  !CDS_PN = "AC43";
"DDR3_SB_CA5":   PN = "AG43"  !CDS_PN = "AG43";
"DDR3_SB_CA6":   PN = "AB42"  !CDS_PN = "AB42";
"DDR3_SB_DQ0":   PN = "AL35"  !CDS_PN = "AL35";
"DDR3_SB_DQ1":   PN = "AK34"  !CDS_PN = "AK34";
"DDR3_SB_DQ2":   PN = "AN35"  !CDS_PN = "AN35";
"DDR3_SB_DQ3":   PN = "AP34"  !CDS_PN = "AP34";
"DDR3_SB_DQ4":   PN = "AK32"  !CDS_PN = "AK32";
"DDR3_SB_DQ5":   PN = "AL31"  !CDS_PN = "AL31";
"DDR3_SB_DQ6":   PN = "AP32"  !CDS_PN = "AP32";
"DDR3_SB_DQ7":   PN = "AN31"  !CDS_PN = "AN31";
"DDR3_SB_DQ8":   PN = "AL29"  !CDS_PN = "AL29";
"DDR3_SB_DQ9":   PN = "AK28"  !CDS_PN = "AK28";
"DDR3_SB_DQ10":   PN = "AN29"  !CDS_PN = "AN29";
"DDR3_SB_DQ11":   PN = "AP28"  !CDS_PN = "AP28";
"DDR3_SB_DQ12":   PN = "AK26"  !CDS_PN = "AK26";
"DDR3_SB_DQ13":   PN = "AL25"  !CDS_PN = "AL25";
"DDR3_SB_DQ14":   PN = "AP26"  !CDS_PN = "AP26";
"DDR3_SB_DQ15":   PN = "AN25"  !CDS_PN = "AN25";
"DDR3_SB_DQ16":   PN = "AD26"  !CDS_PN = "AD26";
"DDR3_SB_DQ17":   PN = "AC25"  !CDS_PN = "AC25";
"DDR3_SB_DQ18":   PN = "AF26"  !CDS_PN = "AF26";
"DDR3_SB_DQ19":   PN = "AG25"  !CDS_PN = "AG25";
"DDR3_SB_DQ20":   PN = "AC23"  !CDS_PN = "AC23";
"DDR3_SB_DQ21":   PN = "AD22"  !CDS_PN = "AD22";
"DDR3_SB_DQ22":   PN = "AG23"  !CDS_PN = "AG23";
"DDR3_SB_DQ23":   PN = "AF22"  !CDS_PN = "AF22";
"DDR3_SB_DQ24":   PN = "AL23"  !CDS_PN = "AL23";
"DDR3_SB_DQ25":   PN = "AK22"  !CDS_PN = "AK22";
"DDR3_SB_DQ26":   PN = "AN23"  !CDS_PN = "AN23";
"DDR3_SB_DQ27":   PN = "AP22"  !CDS_PN = "AP22";
"DDR3_SB_DQ28":   PN = "AK20"  !CDS_PN = "AK20";
"DDR3_SB_DQ29":   PN = "AL19"  !CDS_PN = "AL19";
"DDR3_SB_DQ30":   PN = "AP20"  !CDS_PN = "AP20";
"DDR3_SB_DQ31":   PN = "AN19"  !CDS_PN = "AN19";
"DDR3_SB_DQS_DN0":   PN = "AJ33"  !CDS_PN = "AJ33";
"DDR3_SB_DQS_DN1":   PN = "AJ27"  !CDS_PN = "AJ27";
"DDR3_SB_DQS_DN2":   PN = "AB24"  !CDS_PN = "AB24";
"DDR3_SB_DQS_DN3":   PN = "AJ21"  !CDS_PN = "AJ21";
"DDR3_SB_DQS_DN4":   PN = "AR39"  !CDS_PN = "AR39";
"DDR3_SB_DQS_DN5":   PN = "AN33"  !CDS_PN = "AN33";
"DDR3_SB_DQS_DN6":   PN = "AN27"  !CDS_PN = "AN27";
"DDR3_SB_DQS_DN7":   PN = "AF24"  !CDS_PN = "AF24";
"DDR3_SB_DQS_DN8":   PN = "AN21"  !CDS_PN = "AN21";
"DDR3_SB_DQS_DN9":   PN = "AJ39"  !CDS_PN = "AJ39";
"DDR3_SB_DQS_DP0":   PN = "AL33"  !CDS_PN = "AL33";
"DDR3_SB_DQS_DP1":   PN = "AL27"  !CDS_PN = "AL27";
"DDR3_SB_DQS_DP2":   PN = "AD24"  !CDS_PN = "AD24";
"DDR3_SB_DQS_DP3":   PN = "AL21"  !CDS_PN = "AL21";
"DDR3_SB_DQS_DP4":   PN = "AN39"  !CDS_PN = "AN39";
"DDR3_SB_DQS_DP5":   PN = "AR33"  !CDS_PN = "AR33";
"DDR3_SB_DQS_DP6":   PN = "AR27"  !CDS_PN = "AR27";
"DDR3_SB_DQS_DP7":   PN = "AH24"  !CDS_PN = "AH24";
"DDR3_SB_DQS_DP8":   PN = "AR21"  !CDS_PN = "AR21";
"DDR3_SB_DQS_DP9":   PN = "AL39"  !CDS_PN = "AL39";
"DDR3_SB_ECC0":   PN = "AK38"  !CDS_PN = "AK38";
"DDR3_SB_ECC1":   PN = "AL37"  !CDS_PN = "AL37";
"DDR3_SB_ECC2":   PN = "AP38"  !CDS_PN = "AP38";
"DDR3_SB_ECC3":   PN = "AN37"  !CDS_PN = "AN37";
"DDR3_SB_ECC4":   PN = "AL41"  !CDS_PN = "AL41";
"DDR3_SB_ECC5":   PN = "AK40"  !CDS_PN = "AK40";
"DDR3_SB_ECC6":   PN = "AN41"  !CDS_PN = "AN41";
"DDR3_SB_ECC7":   PN = "AP40"  !CDS_PN = "AP40";
"DDR3_SB_PAR":   PN = "AH42"  !CDS_PN = "AH42";
"DDR3_SA_CS_N0":   PN = "AL54"  !CDS_PN = "AL54";
"DDR3_SA_CS_N1":   PN = "AK53"  !CDS_PN = "AK53";
"DDR3_SA_CS_N2":   PN = "AN54"  !CDS_PN = "AN54";
"DDR3_SA_CS_N3":   PN = "AP53"  !CDS_PN = "AP53";
"DDR3_SB_CS_N0":   PN = "AC41"  !CDS_PN = "AC41";
"DDR3_SB_CS_N1":   PN = "AG41"  !CDS_PN = "AG41";
"DDR3_SB_CS_N2":   PN = "AF40"  !CDS_PN = "AF40";
"DDR3_SB_CS_N3":   PN = "AD40"  !CDS_PN = "AD40";
DRAWING = "@s9s_mb_2u_lib.s9s_mb_2u(sch_1):page55";
BODY = "SOCKET4677_AZIF0045P001C01CS","I7": LOCATION = "U1" #&CDS_LOCATION = "U1" &SEC = "12" #&CDS_SEC = "12";
"DDR4_A_RSP0":   PN = "DD44"  !CDS_PN = "DD44";
"DDR4_A_RSP1":   PN = "DC43"  !CDS_PN = "DC43";
"DDR4_ALERT_N":   PN = "CY47"  !CDS_PN = "CY47";
"DDR4_B_RSP0":   PN = "DF44"  !CDS_PN = "DF44";
"DDR4_B_RSP1":   PN = "DG43"  !CDS_PN = "DG43";
"DDR4_CLK_DN0":   PN = "EJ45"  !CDS_PN = "EJ45";
"DDR4_CLK_DN1":   PN = "EE45"  !CDS_PN = "EE45";
"DDR4_CLK_DP0":   PN = "EG45"  !CDS_PN = "EG45";
"DDR4_CLK_DP1":   PN = "EC45"  !CDS_PN = "EC45";
"DDR4_SA_CA0":   PN = "EP49"  !CDS_PN = "EP49";
"DDR4_SA_CA1":   PN = "ET49"  !CDS_PN = "ET49";
"DDR4_SA_CA2":   PN = "EK49"  !CDS_PN = "EK49";
"DDR4_SA_CA3":   PN = "EL48"  !CDS_PN = "EL48";
"DDR4_SA_CA4":   PN = "EM47"  !CDS_PN = "EM47";
"DDR4_SA_CA5":   PN = "EP47"  !CDS_PN = "EP47";
"DDR4_SA_CA6":   PN = "ED44"  !CDS_PN = "ED44";
"DDR4_SA_DQ0":   PN = "EL78"  !CDS_PN = "EL78";
"DDR4_SA_DQ1":   PN = "EM77"  !CDS_PN = "EM77";
"DDR4_SA_DQ2":   PN = "EP79"  !CDS_PN = "EP79";
"DDR4_SA_DQ3":   PN = "ER76"  !CDS_PN = "ER76";
"DDR4_SA_DQ4":   PN = "EL74"  !CDS_PN = "EL74";
"DDR4_SA_DQ5":   PN = "EK73"  !CDS_PN = "EK73";
"DDR4_SA_DQ6":   PN = "EP73"  !CDS_PN = "EP73";
"DDR4_SA_DQ7":   PN = "ER72"  !CDS_PN = "ER72";
"DDR4_SA_DQ8":   PN = "EE72"  !CDS_PN = "EE72";
"DDR4_SA_DQ9":   PN = "ED71"  !CDS_PN = "ED71";
"DDR4_SA_DQ10":   PN = "EG72"  !CDS_PN = "EG72";
"DDR4_SA_DQ11":   PN = "EH71"  !CDS_PN = "EH71";
"DDR4_SA_DQ12":   PN = "ED69"  !CDS_PN = "ED69";
"DDR4_SA_DQ13":   PN = "EE68"  !CDS_PN = "EE68";
"DDR4_SA_DQ14":   PN = "EH69"  !CDS_PN = "EH69";
"DDR4_SA_DQ15":   PN = "EG68"  !CDS_PN = "EG68";
"DDR4_SA_DQ16":   PN = "EM71"  !CDS_PN = "EM71";
"DDR4_SA_DQ17":   PN = "EM69"  !CDS_PN = "EM69";
"DDR4_SA_DQ18":   PN = "EN70"  !CDS_PN = "EN70";
"DDR4_SA_DQ19":   PN = "ER68"  !CDS_PN = "ER68";
"DDR4_SA_DQ20":   PN = "ER66"  !CDS_PN = "ER66";
"DDR4_SA_DQ21":   PN = "EM65"  !CDS_PN = "EM65";
"DDR4_SA_DQ22":   PN = "EL66"  !CDS_PN = "EL66";
"DDR4_SA_DQ23":   PN = "EP65"  !CDS_PN = "EP65";
"DDR4_SA_DQ24":   PN = "EM63"  !CDS_PN = "EM63";
"DDR4_SA_DQ25":   PN = "EL62"  !CDS_PN = "EL62";
"DDR4_SA_DQ26":   PN = "EP63"  !CDS_PN = "EP63";
"DDR4_SA_DQ27":   PN = "ER62"  !CDS_PN = "ER62";
"DDR4_SA_DQ28":   PN = "EL60"  !CDS_PN = "EL60";
"DDR4_SA_DQ29":   PN = "EM59"  !CDS_PN = "EM59";
"DDR4_SA_DQ30":   PN = "ER60"  !CDS_PN = "ER60";
"DDR4_SA_DQ31":   PN = "EP59"  !CDS_PN = "EP59";
"DDR4_SA_DQS_DN0":   PN = "EP75"  !CDS_PN = "EP75";
"DDR4_SA_DQS_DN1":   PN = "EC70"  !CDS_PN = "EC70";
"DDR4_SA_DQS_DN2":   PN = "EK67"  !CDS_PN = "EK67";
"DDR4_SA_DQS_DN3":   PN = "EK61"  !CDS_PN = "EK61";
"DDR4_SA_DQS_DN4":   PN = "EM55"  !CDS_PN = "EM55";
"DDR4_SA_DQS_DN5":   PN = "EM75"  !CDS_PN = "EM75";
"DDR4_SA_DQS_DN6":   PN = "EJ70"  !CDS_PN = "EJ70";
"DDR4_SA_DQS_DN7":   PN = "EN68"  !CDS_PN = "EN68";
"DDR4_SA_DQS_DN8":   PN = "ET61"  !CDS_PN = "ET61";
"DDR4_SA_DQS_DN9":   PN = "ET55"  !CDS_PN = "ET55";
"DDR4_SA_DQS_DP0":   PN = "EN76"  !CDS_PN = "EN76";
"DDR4_SA_DQS_DP1":   PN = "EE70"  !CDS_PN = "EE70";
"DDR4_SA_DQS_DP2":   PN = "EL68"  !CDS_PN = "EL68";
"DDR4_SA_DQS_DP3":   PN = "EM61"  !CDS_PN = "EM61";
"DDR4_SA_DQS_DP4":   PN = "EK55"  !CDS_PN = "EK55";
"DDR4_SA_DQS_DP5":   PN = "EN74"  !CDS_PN = "EN74";
"DDR4_SA_DQS_DP6":   PN = "EG70"  !CDS_PN = "EG70";
"DDR4_SA_DQS_DP7":   PN = "EM67"  !CDS_PN = "EM67";
"DDR4_SA_DQS_DP8":   PN = "EP61"  !CDS_PN = "EP61";
"DDR4_SA_DQS_DP9":   PN = "EP55"  !CDS_PN = "EP55";
"DDR4_SA_ECC0":   PN = "EM57"  !CDS_PN = "EM57";
"DDR4_SA_ECC1":   PN = "EL56"  !CDS_PN = "EL56";
"DDR4_SA_ECC2":   PN = "EP57"  !CDS_PN = "EP57";
"DDR4_SA_ECC3":   PN = "ER56"  !CDS_PN = "ER56";
"DDR4_SA_ECC4":   PN = "EL54"  !CDS_PN = "EL54";
"DDR4_SA_ECC5":   PN = "EM53"  !CDS_PN = "EM53";
"DDR4_SA_ECC6":   PN = "ER54"  !CDS_PN = "ER54";
"DDR4_SA_ECC7":   PN = "EP53"  !CDS_PN = "EP53";
"DDR4_SA_PAR":   PN = "EE43"  !CDS_PN = "EE43";
"DDR4_SB_CA0":   PN = "EG43"  !CDS_PN = "EG43";
"DDR4_SB_CA1":   PN = "EH44"  !CDS_PN = "EH44";
"DDR4_SB_CA2":   PN = "EM44"  !CDS_PN = "EM44";
"DDR4_SB_CA3":   PN = "EP44"  !CDS_PN = "EP44";
"DDR4_SB_CA4":   PN = "EL43"  !CDS_PN = "EL43";
"DDR4_SB_CA5":   PN = "ET42"  !CDS_PN = "ET42";
"DDR4_SB_CA6":   PN = "EK42"  !CDS_PN = "EK42";
"DDR4_SB_DQ0":   PN = "EE29"  !CDS_PN = "EE29";
"DDR4_SB_DQ1":   PN = "ED28"  !CDS_PN = "ED28";
"DDR4_SB_DQ2":   PN = "EG29"  !CDS_PN = "EG29";
"DDR4_SB_DQ3":   PN = "EH28"  !CDS_PN = "EH28";
"DDR4_SB_DQ4":   PN = "ED26"  !CDS_PN = "ED26";
"DDR4_SB_DQ5":   PN = "EE25"  !CDS_PN = "EE25";
"DDR4_SB_DQ6":   PN = "EH26"  !CDS_PN = "EH26";
"DDR4_SB_DQ7":   PN = "EG25"  !CDS_PN = "EG25";
"DDR4_SB_DQ8":   PN = "EM32"  !CDS_PN = "EM32";
"DDR4_SB_DQ9":   PN = "EL31"  !CDS_PN = "EL31";
"DDR4_SB_DQ10":   PN = "EP32"  !CDS_PN = "EP32";
"DDR4_SB_DQ11":   PN = "ER31"  !CDS_PN = "ER31";
"DDR4_SB_DQ12":   PN = "EL29"  !CDS_PN = "EL29";
"DDR4_SB_DQ13":   PN = "EM28"  !CDS_PN = "EM28";
"DDR4_SB_DQ14":   PN = "ER29"  !CDS_PN = "ER29";
"DDR4_SB_DQ15":   PN = "EP28"  !CDS_PN = "EP28";
"DDR4_SB_DQ16":   PN = "EM26"  !CDS_PN = "EM26";
"DDR4_SB_DQ17":   PN = "EL25"  !CDS_PN = "EL25";
"DDR4_SB_DQ18":   PN = "EP26"  !CDS_PN = "EP26";
"DDR4_SB_DQ19":   PN = "ER25"  !CDS_PN = "ER25";
"DDR4_SB_DQ20":   PN = "EL23"  !CDS_PN = "EL23";
"DDR4_SB_DQ21":   PN = "EM22"  !CDS_PN = "EM22";
"DDR4_SB_DQ22":   PN = "ER23"  !CDS_PN = "ER23";
"DDR4_SB_DQ23":   PN = "EP22"  !CDS_PN = "EP22";
"DDR4_SB_DQ24":   PN = "EM20"  !CDS_PN = "EM20";
"DDR4_SB_DQ25":   PN = "EL19"  !CDS_PN = "EL19";
"DDR4_SB_DQ26":   PN = "EP20"  !CDS_PN = "EP20";
"DDR4_SB_DQ27":   PN = "ER19"  !CDS_PN = "ER19";
"DDR4_SB_DQ28":   PN = "EL17"  !CDS_PN = "EL17";
"DDR4_SB_DQ29":   PN = "EM16"  !CDS_PN = "EM16";
"DDR4_SB_DQ30":   PN = "ER17"  !CDS_PN = "ER17";
"DDR4_SB_DQ31":   PN = "EP16"  !CDS_PN = "EP16";
"DDR4_SB_DQS_DN0":   PN = "EE27"  !CDS_PN = "EE27";
"DDR4_SB_DQS_DN1":   PN = "EK30"  !CDS_PN = "EK30";
"DDR4_SB_DQS_DN2":   PN = "EK24"  !CDS_PN = "EK24";
"DDR4_SB_DQS_DN3":   PN = "EK18"  !CDS_PN = "EK18";
"DDR4_SB_DQS_DN4":   PN = "ET36"  !CDS_PN = "ET36";
"DDR4_SB_DQS_DN5":   PN = "EJ27"  !CDS_PN = "EJ27";
"DDR4_SB_DQS_DN6":   PN = "ET30"  !CDS_PN = "ET30";
"DDR4_SB_DQS_DN7":   PN = "ET24"  !CDS_PN = "ET24";
"DDR4_SB_DQS_DN8":   PN = "ET18"  !CDS_PN = "ET18";
"DDR4_SB_DQS_DN9":   PN = "EK36"  !CDS_PN = "EK36";
"DDR4_SB_DQS_DP0":   PN = "EC27"  !CDS_PN = "EC27";
"DDR4_SB_DQS_DP1":   PN = "EM30"  !CDS_PN = "EM30";
"DDR4_SB_DQS_DP2":   PN = "EM24"  !CDS_PN = "EM24";
"DDR4_SB_DQS_DP3":   PN = "EM18"  !CDS_PN = "EM18";
"DDR4_SB_DQS_DP4":   PN = "EP36"  !CDS_PN = "EP36";
"DDR4_SB_DQS_DP5":   PN = "EG27"  !CDS_PN = "EG27";
"DDR4_SB_DQS_DP6":   PN = "EP30"  !CDS_PN = "EP30";
"DDR4_SB_DQS_DP7":   PN = "EP24"  !CDS_PN = "EP24";
"DDR4_SB_DQS_DP8":   PN = "EP18"  !CDS_PN = "EP18";
"DDR4_SB_DQS_DP9":   PN = "EM36"  !CDS_PN = "EM36";
"DDR4_SB_ECC0":   PN = "EL35"  !CDS_PN = "EL35";
"DDR4_SB_ECC1":   PN = "EM34"  !CDS_PN = "EM34";
"DDR4_SB_ECC2":   PN = "ER35"  !CDS_PN = "ER35";
"DDR4_SB_ECC3":   PN = "EP34"  !CDS_PN = "EP34";
"DDR4_SB_ECC4":   PN = "EM38"  !CDS_PN = "EM38";
"DDR4_SB_ECC5":   PN = "EL37"  !CDS_PN = "EL37";
"DDR4_SB_ECC6":   PN = "EP38"  !CDS_PN = "EP38";
"DDR4_SB_ECC7":   PN = "ER37"  !CDS_PN = "ER37";
"DDR4_SB_PAR":   PN = "EP42"  !CDS_PN = "EP42";
"DDR4_SA_CS_N0":   PN = "EP51"  !CDS_PN = "EP51";
"DDR4_SA_CS_N1":   PN = "ET51"  !CDS_PN = "ET51";
"DDR4_SA_CS_N2":   PN = "EM51"  !CDS_PN = "EM51";
"DDR4_SA_CS_N3":   PN = "EL50"  !CDS_PN = "EL50";
"DDR4_SB_CS_N0":   PN = "EP40"  !CDS_PN = "EP40";
"DDR4_SB_CS_N1":   PN = "ET40"  !CDS_PN = "ET40";
"DDR4_SB_CS_N2":   PN = "EM40"  !CDS_PN = "EM40";
"DDR4_SB_CS_N3":   PN = "EL41"  !CDS_PN = "EL41";
DRAWING = "@s9s_mb_2u_lib.s9s_mb_2u(sch_1):page56";
BODY = "SOCKET4677_AZIF0045P001C01CS","I168": LOCATION = "U1" #&CDS_LOCATION = "U1" &SEC = "13" #&CDS_SEC = "13";
"DDR5_A_RSP0":   PN = "DN48"  !CDS_PN = "DN48";
"DDR5_A_RSP1":   PN = "DP47"  !CDS_PN = "DP47";
"DDR5_ALERT_N":   PN = "CW48"  !CDS_PN = "CW48";
"DDR5_B_RSP0":   PN = "DL48"  !CDS_PN = "DL48";
"DDR5_B_RSP1":   PN = "DK47"  !CDS_PN = "DK47";
"DDR5_CLK_DN0":   PN = "DY49"  !CDS_PN = "DY49";
"DDR5_CLK_DN1":   PN = "DV49"  !CDS_PN = "DV49";
"DDR5_CLK_DP0":   PN = "EB49"  !CDS_PN = "EB49";
"DDR5_CLK_DP1":   PN = "DT49"  !CDS_PN = "DT49";
"DDR5_SA_CA0":   PN = "EC52"  !CDS_PN = "EC52";
"DDR5_SA_CA1":   PN = "EJ52"  !CDS_PN = "EJ52";
"DDR5_SA_CA2":   PN = "ED51"  !CDS_PN = "ED51";
"DDR5_SA_CA3":   PN = "EH51"  !CDS_PN = "EH51";
"DDR5_SA_CA4":   PN = "EE50"  !CDS_PN = "EE50";
"DDR5_SA_CA5":   PN = "EG50"  !CDS_PN = "EG50";
"DDR5_SA_CA6":   PN = "DY51"  !CDS_PN = "DY51";
"DDR5_SA_DQ0":   PN = "EB77"  !CDS_PN = "EB77";
"DDR5_SA_DQ1":   PN = "EH77"  !CDS_PN = "EH77";
"DDR5_SA_DQ2":   PN = "ED77"  !CDS_PN = "ED77";
"DDR5_SA_DQ3":   PN = "EG78"  !CDS_PN = "EG78";
"DDR5_SA_DQ4":   PN = "ED75"  !CDS_PN = "ED75";
"DDR5_SA_DQ5":   PN = "EE74"  !CDS_PN = "EE74";
"DDR5_SA_DQ6":   PN = "EH75"  !CDS_PN = "EH75";
"DDR5_SA_DQ7":   PN = "EG74"  !CDS_PN = "EG74";
"DDR5_SA_DQ8":   PN = "DV69"  !CDS_PN = "DV69";
"DDR5_SA_DQ9":   PN = "DU68"  !CDS_PN = "DU68";
"DDR5_SA_DQ10":   PN = "DY69"  !CDS_PN = "DY69";
"DDR5_SA_DQ11":   PN = "EA68"  !CDS_PN = "EA68";
"DDR5_SA_DQ12":   PN = "DU66"  !CDS_PN = "DU66";
"DDR5_SA_DQ13":   PN = "DV65"  !CDS_PN = "DV65";
"DDR5_SA_DQ14":   PN = "EA66"  !CDS_PN = "EA66";
"DDR5_SA_DQ15":   PN = "DY65"  !CDS_PN = "DY65";
"DDR5_SA_DQ16":   PN = "EE66"  !CDS_PN = "EE66";
"DDR5_SA_DQ17":   PN = "ED65"  !CDS_PN = "ED65";
"DDR5_SA_DQ18":   PN = "EG66"  !CDS_PN = "EG66";
"DDR5_SA_DQ19":   PN = "EH65"  !CDS_PN = "EH65";
"DDR5_SA_DQ20":   PN = "ED63"  !CDS_PN = "ED63";
"DDR5_SA_DQ21":   PN = "EE62"  !CDS_PN = "EE62";
"DDR5_SA_DQ22":   PN = "EH63"  !CDS_PN = "EH63";
"DDR5_SA_DQ23":   PN = "EG62"  !CDS_PN = "EG62";
"DDR5_SA_DQ24":   PN = "DV57"  !CDS_PN = "DV57";
"DDR5_SA_DQ25":   PN = "DU56"  !CDS_PN = "DU56";
"DDR5_SA_DQ26":   PN = "DY57"  !CDS_PN = "DY57";
"DDR5_SA_DQ27":   PN = "EA56"  !CDS_PN = "EA56";
"DDR5_SA_DQ28":   PN = "DU54"  !CDS_PN = "DU54";
"DDR5_SA_DQ29":   PN = "DV53"  !CDS_PN = "DV53";
"DDR5_SA_DQ30":   PN = "EA54"  !CDS_PN = "EA54";
"DDR5_SA_DQ31":   PN = "DY53"  !CDS_PN = "DY53";
"DDR5_SA_DQS_DN0":   PN = "EE76"  !CDS_PN = "EE76";
"DDR5_SA_DQS_DN1":   PN = "DT67"  !CDS_PN = "DT67";
"DDR5_SA_DQS_DN2":   PN = "EC64"  !CDS_PN = "EC64";
"DDR5_SA_DQS_DN3":   PN = "DV55"  !CDS_PN = "DV55";
"DDR5_SA_DQS_DN4":   PN = "EE58"  !CDS_PN = "EE58";
"DDR5_SA_DQS_DN5":   PN = "EJ76"  !CDS_PN = "EJ76";
"DDR5_SA_DQS_DN6":   PN = "EB67"  !CDS_PN = "EB67";
"DDR5_SA_DQS_DN7":   PN = "EJ64"  !CDS_PN = "EJ64";
"DDR5_SA_DQS_DN8":   PN = "EB55"  !CDS_PN = "EB55";
"DDR5_SA_DQS_DN9":   PN = "EJ58"  !CDS_PN = "EJ58";
"DDR5_SA_DQS_DP0":   PN = "EC76"  !CDS_PN = "EC76";
"DDR5_SA_DQS_DP1":   PN = "DV67"  !CDS_PN = "DV67";
"DDR5_SA_DQS_DP2":   PN = "EE64"  !CDS_PN = "EE64";
"DDR5_SA_DQS_DP3":   PN = "DT55"  !CDS_PN = "DT55";
"DDR5_SA_DQS_DP4":   PN = "EC58"  !CDS_PN = "EC58";
"DDR5_SA_DQS_DP5":   PN = "EG76"  !CDS_PN = "EG76";
"DDR5_SA_DQS_DP6":   PN = "DY67"  !CDS_PN = "DY67";
"DDR5_SA_DQS_DP7":   PN = "EG64"  !CDS_PN = "EG64";
"DDR5_SA_DQS_DP8":   PN = "DY55"  !CDS_PN = "DY55";
"DDR5_SA_DQS_DP9":   PN = "EG58"  !CDS_PN = "EG58";
"DDR5_SA_ECC0":   PN = "EE60"  !CDS_PN = "EE60";
"DDR5_SA_ECC1":   PN = "ED59"  !CDS_PN = "ED59";
"DDR5_SA_ECC2":   PN = "EG60"  !CDS_PN = "EG60";
"DDR5_SA_ECC3":   PN = "EH59"  !CDS_PN = "EH59";
"DDR5_SA_ECC4":   PN = "ED57"  !CDS_PN = "ED57";
"DDR5_SA_ECC5":   PN = "EE56"  !CDS_PN = "EE56";
"DDR5_SA_ECC6":   PN = "EH57"  !CDS_PN = "EH57";
"DDR5_SA_ECC7":   PN = "EG56"  !CDS_PN = "EG56";
"DDR5_SA_PAR":   PN = "EA50"  !CDS_PN = "EA50";
"DDR5_SB_CA0":   PN = "DV51"  !CDS_PN = "DV51";
"DDR5_SB_CA1":   PN = "DU50"  !CDS_PN = "DU50";
"DDR5_SB_CA2":   PN = "EE41"  !CDS_PN = "EE41";
"DDR5_SB_CA3":   PN = "EG41"  !CDS_PN = "EG41";
"DDR5_SB_CA4":   PN = "ED40"  !CDS_PN = "ED40";
"DDR5_SB_CA5":   PN = "EH40"  !CDS_PN = "EH40";
"DDR5_SB_CA6":   PN = "EC39"  !CDS_PN = "EC39";
"DDR5_SB_DQ0":   PN = "DV32"  !CDS_PN = "DV32";
"DDR5_SB_DQ1":   PN = "DU31"  !CDS_PN = "DU31";
"DDR5_SB_DQ2":   PN = "DY32"  !CDS_PN = "DY32";
"DDR5_SB_DQ3":   PN = "EA31"  !CDS_PN = "EA31";
"DDR5_SB_DQ4":   PN = "DU29"  !CDS_PN = "DU29";
"DDR5_SB_DQ5":   PN = "DV28"  !CDS_PN = "DV28";
"DDR5_SB_DQ6":   PN = "EA29"  !CDS_PN = "EA29";
"DDR5_SB_DQ7":   PN = "DY28"  !CDS_PN = "DY28";
"DDR5_SB_DQ8":   PN = "EE23"  !CDS_PN = "EE23";
"DDR5_SB_DQ9":   PN = "ED22"  !CDS_PN = "ED22";
"DDR5_SB_DQ10":   PN = "EG23"  !CDS_PN = "EG23";
"DDR5_SB_DQ11":   PN = "EH22"  !CDS_PN = "EH22";
"DDR5_SB_DQ12":   PN = "ED20"  !CDS_PN = "ED20";
"DDR5_SB_DQ13":   PN = "EE19"  !CDS_PN = "EE19";
"DDR5_SB_DQ14":   PN = "EH20"  !CDS_PN = "EH20";
"DDR5_SB_DQ15":   PN = "EG19"  !CDS_PN = "EG19";
"DDR5_SB_DQ16":   PN = "EM14"  !CDS_PN = "EM14";
"DDR5_SB_DQ17":   PN = "EL13"  !CDS_PN = "EL13";
"DDR5_SB_DQ18":   PN = "EP14"  !CDS_PN = "EP14";
"DDR5_SB_DQ19":   PN = "ER13"  !CDS_PN = "ER13";
"DDR5_SB_DQ20":   PN = "EL11"  !CDS_PN = "EL11";
"DDR5_SB_DQ21":   PN = "EM10"  !CDS_PN = "EM10";
"DDR5_SB_DQ22":   PN = "ER11"  !CDS_PN = "ER11";
"DDR5_SB_DQ23":   PN = "EP10"  !CDS_PN = "EP10";
"DDR5_SB_DQ24":   PN = "DV20"  !CDS_PN = "DV20";
"DDR5_SB_DQ25":   PN = "DU19"  !CDS_PN = "DU19";
"DDR5_SB_DQ26":   PN = "DY20"  !CDS_PN = "DY20";
"DDR5_SB_DQ27":   PN = "EA19"  !CDS_PN = "EA19";
"DDR5_SB_DQ28":   PN = "EA17"  !CDS_PN = "EA17";
"DDR5_SB_DQ29":   PN = "DU17"  !CDS_PN = "DU17";
"DDR5_SB_DQ30":   PN = "EC17"  !CDS_PN = "EC17";
"DDR5_SB_DQ31":   PN = "DR17"  !CDS_PN = "DR17";
"DDR5_SB_DQS_DN0":   PN = "DV30"  !CDS_PN = "DV30";
"DDR5_SB_DQS_DN1":   PN = "EE21"  !CDS_PN = "EE21";
"DDR5_SB_DQS_DN2":   PN = "EM12"  !CDS_PN = "EM12";
"DDR5_SB_DQS_DN3":   PN = "DT18"  !CDS_PN = "DT18";
"DDR5_SB_DQS_DN4":   PN = "EJ33"  !CDS_PN = "EJ33";
"DDR5_SB_DQS_DN5":   PN = "EB30"  !CDS_PN = "EB30";
"DDR5_SB_DQS_DN6":   PN = "EJ21"  !CDS_PN = "EJ21";
"DDR5_SB_DQS_DN7":   PN = "ET12"  !CDS_PN = "ET12";
"DDR5_SB_DQS_DN8":   PN = "DY18"  !CDS_PN = "DY18";
"DDR5_SB_DQS_DN9":   PN = "EE33"  !CDS_PN = "EE33";
"DDR5_SB_DQS_DP0":   PN = "DT30"  !CDS_PN = "DT30";
"DDR5_SB_DQS_DP1":   PN = "EC21"  !CDS_PN = "EC21";
"DDR5_SB_DQS_DP2":   PN = "EK12"  !CDS_PN = "EK12";
"DDR5_SB_DQS_DP3":   PN = "DV18"  !CDS_PN = "DV18";
"DDR5_SB_DQS_DP4":   PN = "EG33"  !CDS_PN = "EG33";
"DDR5_SB_DQS_DP5":   PN = "DY30"  !CDS_PN = "DY30";
"DDR5_SB_DQS_DP6":   PN = "EG21"  !CDS_PN = "EG21";
"DDR5_SB_DQS_DP7":   PN = "EP12"  !CDS_PN = "EP12";
"DDR5_SB_DQS_DP8":   PN = "EB18"  !CDS_PN = "EB18";
"DDR5_SB_DQS_DP9":   PN = "EC33"  !CDS_PN = "EC33";
"DDR5_SB_ECC0":   PN = "ED32"  !CDS_PN = "ED32";
"DDR5_SB_ECC1":   PN = "EE31"  !CDS_PN = "EE31";
"DDR5_SB_ECC2":   PN = "EH32"  !CDS_PN = "EH32";
"DDR5_SB_ECC3":   PN = "EG31"  !CDS_PN = "EG31";
"DDR5_SB_ECC4":   PN = "EE35"  !CDS_PN = "EE35";
"DDR5_SB_ECC5":   PN = "ED34"  !CDS_PN = "ED34";
"DDR5_SB_ECC6":   PN = "EG35"  !CDS_PN = "EG35";
"DDR5_SB_ECC7":   PN = "EH34"  !CDS_PN = "EH34";
"DDR5_SB_PAR":   PN = "EJ39"  !CDS_PN = "EJ39";
"DDR5_SA_CS_N0":   PN = "EG54"  !CDS_PN = "EG54";
"DDR5_SA_CS_N1":   PN = "EH53"  !CDS_PN = "EH53";
"DDR5_SA_CS_N2":   PN = "EE54"  !CDS_PN = "EE54";
"DDR5_SA_CS_N3":   PN = "ED53"  !CDS_PN = "ED53";
"DDR5_SB_CS_N0":   PN = "EH38"  !CDS_PN = "EH38";
"DDR5_SB_CS_N1":   PN = "EG37"  !CDS_PN = "EG37";
"DDR5_SB_CS_N2":   PN = "ED38"  !CDS_PN = "ED38";
"DDR5_SB_CS_N3":   PN = "EE37"  !CDS_PN = "EE37";
DRAWING = "@s9s_mb_2u_lib.s9s_mb_2u(sch_1):page57";
BODY = "SOCKET4677_AZIF0045P001C01CS","I168": LOCATION = "U1" #&CDS_LOCATION = "U1" &SEC = "14" #&CDS_SEC = "14";
"DDR6_A_RSP0":   PN = "EA48"  !CDS_PN = "EA48";
"DDR6_A_RSP1":   PN = "DY47"  !CDS_PN = "DY47";
"DDR6_ALERT_N":   PN = "CW50"  !CDS_PN = "CW50";
"DDR6_B_RSP0":   PN = "DU48"  !CDS_PN = "DU48";
"DDR6_B_RSP1":   PN = "DV47"  !CDS_PN = "DV47";
"DDR6_CLK_DN0":   PN = "DR45"  !CDS_PN = "DR45";
"DDR6_CLK_DN1":   PN = "DL45"  !CDS_PN = "DL45";
"DDR6_CLK_DP0":   PN = "DN45"  !CDS_PN = "DN45";
"DDR6_CLK_DP1":   PN = "DJ45"  !CDS_PN = "DJ45";
"DDR6_SA_CA0":   PN = "DJ52"  !CDS_PN = "DJ52";
"DDR6_SA_CA1":   PN = "DR52"  !CDS_PN = "DR52";
"DDR6_SA_CA2":   PN = "DK51"  !CDS_PN = "DK51";
"DDR6_SA_CA3":   PN = "DP51"  !CDS_PN = "DP51";
"DDR6_SA_CA4":   PN = "DL50"  !CDS_PN = "DL50";
"DDR6_SA_CA5":   PN = "DN50"  !CDS_PN = "DN50";
"DDR6_SA_CA6":   PN = "DK44"  !CDS_PN = "DK44";
"DDR6_SA_DQ0":   PN = "DV75"  !CDS_PN = "DV75";
"DDR6_SA_DQ1":   PN = "DU74"  !CDS_PN = "DU74";
"DDR6_SA_DQ2":   PN = "DY75"  !CDS_PN = "DY75";
"DDR6_SA_DQ3":   PN = "EA74"  !CDS_PN = "EA74";
"DDR6_SA_DQ4":   PN = "DU72"  !CDS_PN = "DU72";
"DDR6_SA_DQ5":   PN = "DV71"  !CDS_PN = "DV71";
"DDR6_SA_DQ6":   PN = "EA72"  !CDS_PN = "EA72";
"DDR6_SA_DQ7":   PN = "DY71"  !CDS_PN = "DY71";
"DDR6_SA_DQ8":   PN = "DL72"  !CDS_PN = "DL72";
"DDR6_SA_DQ9":   PN = "DK71"  !CDS_PN = "DK71";
"DDR6_SA_DQ10":   PN = "DN72"  !CDS_PN = "DN72";
"DDR6_SA_DQ11":   PN = "DP71"  !CDS_PN = "DP71";
"DDR6_SA_DQ12":   PN = "DK69"  !CDS_PN = "DK69";
"DDR6_SA_DQ13":   PN = "DL68"  !CDS_PN = "DL68";
"DDR6_SA_DQ14":   PN = "DP69"  !CDS_PN = "DP69";
"DDR6_SA_DQ15":   PN = "DN68"  !CDS_PN = "DN68";
"DDR6_SA_DQ16":   PN = "DV63"  !CDS_PN = "DV63";
"DDR6_SA_DQ17":   PN = "DU62"  !CDS_PN = "DU62";
"DDR6_SA_DQ18":   PN = "DY63"  !CDS_PN = "DY63";
"DDR6_SA_DQ19":   PN = "EA62"  !CDS_PN = "EA62";
"DDR6_SA_DQ20":   PN = "DU60"  !CDS_PN = "DU60";
"DDR6_SA_DQ21":   PN = "DV59"  !CDS_PN = "DV59";
"DDR6_SA_DQ22":   PN = "EA60"  !CDS_PN = "EA60";
"DDR6_SA_DQ23":   PN = "DY59"  !CDS_PN = "DY59";
"DDR6_SA_DQ24":   PN = "DL66"  !CDS_PN = "DL66";
"DDR6_SA_DQ25":   PN = "DK65"  !CDS_PN = "DK65";
"DDR6_SA_DQ26":   PN = "DN66"  !CDS_PN = "DN66";
"DDR6_SA_DQ27":   PN = "DP65"  !CDS_PN = "DP65";
"DDR6_SA_DQ28":   PN = "DK63"  !CDS_PN = "DK63";
"DDR6_SA_DQ29":   PN = "DL62"  !CDS_PN = "DL62";
"DDR6_SA_DQ30":   PN = "DP63"  !CDS_PN = "DP63";
"DDR6_SA_DQ31":   PN = "DN62"  !CDS_PN = "DN62";
"DDR6_SA_DQS_DN0":   PN = "DV73"  !CDS_PN = "DV73";
"DDR6_SA_DQS_DN1":   PN = "DJ70"  !CDS_PN = "DJ70";
"DDR6_SA_DQS_DN2":   PN = "DT61"  !CDS_PN = "DT61";
"DDR6_SA_DQS_DN3":   PN = "DL64"  !CDS_PN = "DL64";
"DDR6_SA_DQS_DN4":   PN = "DL58"  !CDS_PN = "DL58";
"DDR6_SA_DQS_DN5":   PN = "EB73"  !CDS_PN = "EB73";
"DDR6_SA_DQS_DN6":   PN = "DR70"  !CDS_PN = "DR70";
"DDR6_SA_DQS_DN7":   PN = "EB61"  !CDS_PN = "EB61";
"DDR6_SA_DQS_DN8":   PN = "DR64"  !CDS_PN = "DR64";
"DDR6_SA_DQS_DN9":   PN = "DR58"  !CDS_PN = "DR58";
"DDR6_SA_DQS_DP0":   PN = "DT73"  !CDS_PN = "DT73";
"DDR6_SA_DQS_DP1":   PN = "DL70"  !CDS_PN = "DL70";
"DDR6_SA_DQS_DP2":   PN = "DV61"  !CDS_PN = "DV61";
"DDR6_SA_DQS_DP3":   PN = "DJ64"  !CDS_PN = "DJ64";
"DDR6_SA_DQS_DP4":   PN = "DJ58"  !CDS_PN = "DJ58";
"DDR6_SA_DQS_DP5":   PN = "DY73"  !CDS_PN = "DY73";
"DDR6_SA_DQS_DP6":   PN = "DN70"  !CDS_PN = "DN70";
"DDR6_SA_DQS_DP7":   PN = "DY61"  !CDS_PN = "DY61";
"DDR6_SA_DQS_DP8":   PN = "DN64"  !CDS_PN = "DN64";
"DDR6_SA_DQS_DP9":   PN = "DN58"  !CDS_PN = "DN58";
"DDR6_SA_ECC0":   PN = "DL60"  !CDS_PN = "DL60";
"DDR6_SA_ECC1":   PN = "DK59"  !CDS_PN = "DK59";
"DDR6_SA_ECC2":   PN = "DN60"  !CDS_PN = "DN60";
"DDR6_SA_ECC3":   PN = "DP59"  !CDS_PN = "DP59";
"DDR6_SA_ECC4":   PN = "DK57"  !CDS_PN = "DK57";
"DDR6_SA_ECC5":   PN = "DL56"  !CDS_PN = "DL56";
"DDR6_SA_ECC6":   PN = "DP57"  !CDS_PN = "DP57";
"DDR6_SA_ECC7":   PN = "DN56"  !CDS_PN = "DN56";
"DDR6_SA_PAR":   PN = "DL43"  !CDS_PN = "DL43";
"DDR6_SB_CA0":   PN = "DN43"  !CDS_PN = "DN43";
"DDR6_SB_CA1":   PN = "DP44"  !CDS_PN = "DP44";
"DDR6_SB_CA2":   PN = "DV44"  !CDS_PN = "DV44";
"DDR6_SB_CA3":   PN = "DY44"  !CDS_PN = "DY44";
"DDR6_SB_CA4":   PN = "DU43"  !CDS_PN = "DU43";
"DDR6_SB_CA5":   PN = "EA43"  !CDS_PN = "EA43";
"DDR6_SB_CA6":   PN = "DT42"  !CDS_PN = "DT42";
"DDR6_SB_DQ0":   PN = "DL35"  !CDS_PN = "DL35";
"DDR6_SB_DQ1":   PN = "DK34"  !CDS_PN = "DK34";
"DDR6_SB_DQ2":   PN = "DN35"  !CDS_PN = "DN35";
"DDR6_SB_DQ3":   PN = "DP34"  !CDS_PN = "DP34";
"DDR6_SB_DQ4":   PN = "DK32"  !CDS_PN = "DK32";
"DDR6_SB_DQ5":   PN = "DL31"  !CDS_PN = "DL31";
"DDR6_SB_DQ6":   PN = "DP32"  !CDS_PN = "DP32";
"DDR6_SB_DQ7":   PN = "DN31"  !CDS_PN = "DN31";
"DDR6_SB_DQ8":   PN = "DN29"  !CDS_PN = "DN29";
"DDR6_SB_DQ9":   PN = "DK28"  !CDS_PN = "DK28";
"DDR6_SB_DQ10":   PN = "DL29"  !CDS_PN = "DL29";
"DDR6_SB_DQ11":   PN = "DP28"  !CDS_PN = "DP28";
"DDR6_SB_DQ12":   PN = "DK26"  !CDS_PN = "DK26";
"DDR6_SB_DQ13":   PN = "DL25"  !CDS_PN = "DL25";
"DDR6_SB_DQ14":   PN = "DP26"  !CDS_PN = "DP26";
"DDR6_SB_DQ15":   PN = "DN25"  !CDS_PN = "DN25";
"DDR6_SB_DQ16":   PN = "DV26"  !CDS_PN = "DV26";
"DDR6_SB_DQ17":   PN = "DU25"  !CDS_PN = "DU25";
"DDR6_SB_DQ18":   PN = "DY26"  !CDS_PN = "DY26";
"DDR6_SB_DQ19":   PN = "EA25"  !CDS_PN = "EA25";
"DDR6_SB_DQ20":   PN = "DU23"  !CDS_PN = "DU23";
"DDR6_SB_DQ21":   PN = "DV22"  !CDS_PN = "DV22";
"DDR6_SB_DQ22":   PN = "EA23"  !CDS_PN = "EA23";
"DDR6_SB_DQ23":   PN = "DY22"  !CDS_PN = "DY22";
"DDR6_SB_DQ24":   PN = "EK8"  !CDS_PN = "EK8";
"DDR6_SB_DQ25":   PN = "EH8"  !CDS_PN = "EH8";
"DDR6_SB_DQ26":   PN = "EP8"  !CDS_PN = "EP8";
"DDR6_SB_DQ27":   PN = "ET8"  !CDS_PN = "ET8";
"DDR6_SB_DQ28":   PN = "EK6"  !CDS_PN = "EK6";
"DDR6_SB_DQ29":   PN = "EJ5"  !CDS_PN = "EJ5";
"DDR6_SB_DQ30":   PN = "EP4"  !CDS_PN = "EP4";
"DDR6_SB_DQ31":   PN = "EM4"  !CDS_PN = "EM4";
"DDR6_SB_DQS_DN0":   PN = "DJ33"  !CDS_PN = "DJ33";
"DDR6_SB_DQS_DN1":   PN = "DJ27"  !CDS_PN = "DJ27";
"DDR6_SB_DQS_DN2":   PN = "DV24"  !CDS_PN = "DV24";
"DDR6_SB_DQS_DN3":   PN = "EP6"  !CDS_PN = "EP6";
"DDR6_SB_DQS_DN4":   PN = "EB36"  !CDS_PN = "EB36";
"DDR6_SB_DQS_DN5":   PN = "DR33"  !CDS_PN = "DR33";
"DDR6_SB_DQS_DN6":   PN = "DN27"  !CDS_PN = "DN27";
"DDR6_SB_DQS_DN7":   PN = "EB24"  !CDS_PN = "EB24";
"DDR6_SB_DQS_DN8":   PN = "EM6"  !CDS_PN = "EM6";
"DDR6_SB_DQS_DN9":   PN = "DV36"  !CDS_PN = "DV36";
"DDR6_SB_DQS_DP0":   PN = "DL33"  !CDS_PN = "DL33";
"DDR6_SB_DQS_DP1":   PN = "DL27"  !CDS_PN = "DL27";
"DDR6_SB_DQS_DP2":   PN = "DT24"  !CDS_PN = "DT24";
"DDR6_SB_DQS_DP3":   PN = "EN7"  !CDS_PN = "EN7";
"DDR6_SB_DQS_DP4":   PN = "DY36"  !CDS_PN = "DY36";
"DDR6_SB_DQS_DP5":   PN = "DN33"  !CDS_PN = "DN33";
"DDR6_SB_DQS_DP6":   PN = "DR27"  !CDS_PN = "DR27";
"DDR6_SB_DQS_DP7":   PN = "DY24"  !CDS_PN = "DY24";
"DDR6_SB_DQS_DP8":   PN = "EN5"  !CDS_PN = "EN5";
"DDR6_SB_DQS_DP9":   PN = "DT36"  !CDS_PN = "DT36";
"DDR6_SB_ECC0":   PN = "DU35"  !CDS_PN = "DU35";
"DDR6_SB_ECC1":   PN = "DV34"  !CDS_PN = "DV34";
"DDR6_SB_ECC2":   PN = "EA35"  !CDS_PN = "EA35";
"DDR6_SB_ECC3":   PN = "DY34"  !CDS_PN = "DY34";
"DDR6_SB_ECC4":   PN = "DV38"  !CDS_PN = "DV38";
"DDR6_SB_ECC5":   PN = "DU37"  !CDS_PN = "DU37";
"DDR6_SB_ECC6":   PN = "DY38"  !CDS_PN = "DY38";
"DDR6_SB_ECC7":   PN = "EA37"  !CDS_PN = "EA37";
"DDR6_SB_PAR":   PN = "EB42"  !CDS_PN = "EB42";
"DDR6_SA_CS_N0":   PN = "DN54"  !CDS_PN = "DN54";
"DDR6_SA_CS_N1":   PN = "DP53"  !CDS_PN = "DP53";
"DDR6_SA_CS_N2":   PN = "DL54"  !CDS_PN = "DL54";
"DDR6_SA_CS_N3":   PN = "DK53"  !CDS_PN = "DK53";
"DDR6_SB_CS_N0":   PN = "EA41"  !CDS_PN = "EA41";
"DDR6_SB_CS_N1":   PN = "DY40"  !CDS_PN = "DY40";
"DDR6_SB_CS_N2":   PN = "DU41"  !CDS_PN = "DU41";
"DDR6_SB_CS_N3":   PN = "DV40"  !CDS_PN = "DV40";
DRAWING = "@s9s_mb_2u_lib.s9s_mb_2u(sch_1):page58";
BODY = "SOCKET4677_AZIF0045P001C01CS","I20": LOCATION = "U1" #&CDS_LOCATION = "U1" &SEC = "15" #&CDS_SEC = "15";
"DDR7_A_RSP0":   PN = "EG48"  !CDS_PN = "EG48";
"DDR7_A_RSP1":   PN = "EH47"  !CDS_PN = "EH47";
"DDR7_ALERT_N":   PN = "CY51"  !CDS_PN = "CY51";
"DDR7_B_RSP0":   PN = "EE48"  !CDS_PN = "EE48";
"DDR7_B_RSP1":   PN = "ED47"  !CDS_PN = "ED47";
"DDR7_CLK_DN0":   PN = "DH42"  !CDS_PN = "DH42";
"DDR7_CLK_DN1":   PN = "DD42"  !CDS_PN = "DD42";
"DDR7_CLK_DP0":   PN = "DF42"  !CDS_PN = "DF42";
"DDR7_CLK_DP1":   PN = "DB42"  !CDS_PN = "DB42";
"DDR7_SA_CA0":   PN = "DB49"  !CDS_PN = "DB49";
"DDR7_SA_CA1":   PN = "DH49"  !CDS_PN = "DH49";
"DDR7_SA_CA2":   PN = "DC48"  !CDS_PN = "DC48";
"DDR7_SA_CA3":   PN = "DG48"  !CDS_PN = "DG48";
"DDR7_SA_CA4":   PN = "DD47"  !CDS_PN = "DD47";
"DDR7_SA_CA5":   PN = "DF47"  !CDS_PN = "DF47";
"DDR7_SA_CA6":   PN = "DC41"  !CDS_PN = "DC41";
"DDR7_SA_DQ0":   PN = "DY79"  !CDS_PN = "DY79";
"DDR7_SA_DQ1":   PN = "DT77"  !CDS_PN = "DT77";
"DDR7_SA_DQ2":   PN = "DW78"  !CDS_PN = "DW78";
"DDR7_SA_DQ3":   PN = "DP77"  !CDS_PN = "DP77";
"DDR7_SA_DQ4":   PN = "DK75"  !CDS_PN = "DK75";
"DDR7_SA_DQ5":   PN = "DL74"  !CDS_PN = "DL74";
"DDR7_SA_DQ6":   PN = "DP75"  !CDS_PN = "DP75";
"DDR7_SA_DQ7":   PN = "DN74"  !CDS_PN = "DN74";
"DDR7_SA_DQ8":   PN = "DD75"  !CDS_PN = "DD75";
"DDR7_SA_DQ9":   PN = "DC74"  !CDS_PN = "DC74";
"DDR7_SA_DQ10":   PN = "DF75"  !CDS_PN = "DF75";
"DDR7_SA_DQ11":   PN = "DG74"  !CDS_PN = "DG74";
"DDR7_SA_DQ12":   PN = "DC72"  !CDS_PN = "DC72";
"DDR7_SA_DQ13":   PN = "DD71"  !CDS_PN = "DD71";
"DDR7_SA_DQ14":   PN = "DG72"  !CDS_PN = "DG72";
"DDR7_SA_DQ15":   PN = "DF71"  !CDS_PN = "DF71";
"DDR7_SA_DQ16":   PN = "DD69"  !CDS_PN = "DD69";
"DDR7_SA_DQ17":   PN = "DC68"  !CDS_PN = "DC68";
"DDR7_SA_DQ18":   PN = "DF69"  !CDS_PN = "DF69";
"DDR7_SA_DQ19":   PN = "DG68"  !CDS_PN = "DG68";
"DDR7_SA_DQ20":   PN = "DC66"  !CDS_PN = "DC66";
"DDR7_SA_DQ21":   PN = "DD65"  !CDS_PN = "DD65";
"DDR7_SA_DQ22":   PN = "DG66"  !CDS_PN = "DG66";
"DDR7_SA_DQ23":   PN = "DF65"  !CDS_PN = "DF65";
"DDR7_SA_DQ24":   PN = "DD63"  !CDS_PN = "DD63";
"DDR7_SA_DQ25":   PN = "DC62"  !CDS_PN = "DC62";
"DDR7_SA_DQ26":   PN = "DF63"  !CDS_PN = "DF63";
"DDR7_SA_DQ27":   PN = "DG62"  !CDS_PN = "DG62";
"DDR7_SA_DQ28":   PN = "DC60"  !CDS_PN = "DC60";
"DDR7_SA_DQ29":   PN = "DD59"  !CDS_PN = "DD59";
"DDR7_SA_DQ30":   PN = "DG60"  !CDS_PN = "DG60";
"DDR7_SA_DQ31":   PN = "DF59"  !CDS_PN = "DF59";
"DDR7_SA_DQS_DN0":   PN = "DJ76"  !CDS_PN = "DJ76";
"DDR7_SA_DQS_DN1":   PN = "DB73"  !CDS_PN = "DB73";
"DDR7_SA_DQS_DN2":   PN = "DD67"  !CDS_PN = "DD67";
"DDR7_SA_DQS_DN3":   PN = "DD61"  !CDS_PN = "DD61";
"DDR7_SA_DQS_DN4":   PN = "DD55"  !CDS_PN = "DD55";
"DDR7_SA_DQS_DN5":   PN = "DR76"  !CDS_PN = "DR76";
"DDR7_SA_DQS_DN6":   PN = "DH73"  !CDS_PN = "DH73";
"DDR7_SA_DQS_DN7":   PN = "DH67"  !CDS_PN = "DH67";
"DDR7_SA_DQS_DN8":   PN = "DH61"  !CDS_PN = "DH61";
"DDR7_SA_DQS_DN9":   PN = "DH55"  !CDS_PN = "DH55";
"DDR7_SA_DQS_DP0":   PN = "DL76"  !CDS_PN = "DL76";
"DDR7_SA_DQS_DP1":   PN = "DD73"  !CDS_PN = "DD73";
"DDR7_SA_DQS_DP2":   PN = "DB67"  !CDS_PN = "DB67";
"DDR7_SA_DQS_DP3":   PN = "DB61"  !CDS_PN = "DB61";
"DDR7_SA_DQS_DP4":   PN = "DB55"  !CDS_PN = "DB55";
"DDR7_SA_DQS_DP5":   PN = "DN76"  !CDS_PN = "DN76";
"DDR7_SA_DQS_DP6":   PN = "DF73"  !CDS_PN = "DF73";
"DDR7_SA_DQS_DP7":   PN = "DF67"  !CDS_PN = "DF67";
"DDR7_SA_DQS_DP8":   PN = "DF61"  !CDS_PN = "DF61";
"DDR7_SA_DQS_DP9":   PN = "DF55"  !CDS_PN = "DF55";
"DDR7_SA_ECC0":   PN = "DD57"  !CDS_PN = "DD57";
"DDR7_SA_ECC1":   PN = "DC56"  !CDS_PN = "DC56";
"DDR7_SA_ECC2":   PN = "DF57"  !CDS_PN = "DF57";
"DDR7_SA_ECC3":   PN = "DG56"  !CDS_PN = "DG56";
"DDR7_SA_ECC4":   PN = "DC54"  !CDS_PN = "DC54";
"DDR7_SA_ECC5":   PN = "DD53"  !CDS_PN = "DD53";
"DDR7_SA_ECC6":   PN = "DG54"  !CDS_PN = "DG54";
"DDR7_SA_ECC7":   PN = "DF53"  !CDS_PN = "DF53";
"DDR7_SA_PAR":   PN = "DD40"  !CDS_PN = "DD40";
"DDR7_SB_CA0":   PN = "DF40"  !CDS_PN = "DF40";
"DDR7_SB_CA1":   PN = "DG41"  !CDS_PN = "DG41";
"DDR7_SB_CA2":   PN = "DL41"  !CDS_PN = "DL41";
"DDR7_SB_CA3":   PN = "DN41"  !CDS_PN = "DN41";
"DDR7_SB_CA4":   PN = "DK40"  !CDS_PN = "DK40";
"DDR7_SB_CA5":   PN = "DP40"  !CDS_PN = "DP40";
"DDR7_SB_CA6":   PN = "DJ39"  !CDS_PN = "DJ39";
"DDR7_SB_DQ0":   PN = "DD32"  !CDS_PN = "DD32";
"DDR7_SB_DQ1":   PN = "DC31"  !CDS_PN = "DC31";
"DDR7_SB_DQ2":   PN = "DF32"  !CDS_PN = "DF32";
"DDR7_SB_DQ3":   PN = "DG31"  !CDS_PN = "DG31";
"DDR7_SB_DQ4":   PN = "DC29"  !CDS_PN = "DC29";
"DDR7_SB_DQ5":   PN = "DF28"  !CDS_PN = "DF28";
"DDR7_SB_DQ6":   PN = "DG29"  !CDS_PN = "DG29";
"DDR7_SB_DQ7":   PN = "DD28"  !CDS_PN = "DD28";
"DDR7_SB_DQ8":   PN = "DD26"  !CDS_PN = "DD26";
"DDR7_SB_DQ9":   PN = "DC25"  !CDS_PN = "DC25";
"DDR7_SB_DQ10":   PN = "DF26"  !CDS_PN = "DF26";
"DDR7_SB_DQ11":   PN = "DG25"  !CDS_PN = "DG25";
"DDR7_SB_DQ12":   PN = "DC23"  !CDS_PN = "DC23";
"DDR7_SB_DQ13":   PN = "DD22"  !CDS_PN = "DD22";
"DDR7_SB_DQ14":   PN = "DG23"  !CDS_PN = "DG23";
"DDR7_SB_DQ15":   PN = "DF22"  !CDS_PN = "DF22";
"DDR7_SB_DQ16":   PN = "DL23"  !CDS_PN = "DL23";
"DDR7_SB_DQ17":   PN = "DK22"  !CDS_PN = "DK22";
"DDR7_SB_DQ18":   PN = "DN23"  !CDS_PN = "DN23";
"DDR7_SB_DQ19":   PN = "DP22"  !CDS_PN = "DP22";
"DDR7_SB_DQ20":   PN = "DK20"  !CDS_PN = "DK20";
"DDR7_SB_DQ21":   PN = "DL19"  !CDS_PN = "DL19";
"DDR7_SB_DQ22":   PN = "DP20"  !CDS_PN = "DP20";
"DDR7_SB_DQ23":   PN = "DN19"  !CDS_PN = "DN19";
"DDR7_SB_DQ24":   PN = "DD20"  !CDS_PN = "DD20";
"DDR7_SB_DQ25":   PN = "DC19"  !CDS_PN = "DC19";
"DDR7_SB_DQ26":   PN = "DF20"  !CDS_PN = "DF20";
"DDR7_SB_DQ27":   PN = "DG19"  !CDS_PN = "DG19";
"DDR7_SB_DQ28":   PN = "DG17"  !CDS_PN = "DG17";
"DDR7_SB_DQ29":   PN = "DA17"  !CDS_PN = "DA17";
"DDR7_SB_DQ30":   PN = "DJ17"  !CDS_PN = "DJ17";
"DDR7_SB_DQ31":   PN = "DC17"  !CDS_PN = "DC17";
"DDR7_SB_DQS_DN0":   PN = "DD30"  !CDS_PN = "DD30";
"DDR7_SB_DQS_DN1":   PN = "DD24"  !CDS_PN = "DD24";
"DDR7_SB_DQS_DN2":   PN = "DL21"  !CDS_PN = "DL21";
"DDR7_SB_DQS_DN3":   PN = "DB18"  !CDS_PN = "DB18";
"DDR7_SB_DQS_DN4":   PN = "DH36"  !CDS_PN = "DH36";
"DDR7_SB_DQS_DN5":   PN = "DH30"  !CDS_PN = "DH30";
"DDR7_SB_DQS_DN6":   PN = "DH24"  !CDS_PN = "DH24";
"DDR7_SB_DQS_DN7":   PN = "DR21"  !CDS_PN = "DR21";
"DDR7_SB_DQS_DN8":   PN = "DF18"  !CDS_PN = "DF18";
"DDR7_SB_DQS_DN9":   PN = "DD36"  !CDS_PN = "DD36";
"DDR7_SB_DQS_DP0":   PN = "DB30"  !CDS_PN = "DB30";
"DDR7_SB_DQS_DP1":   PN = "DB24"  !CDS_PN = "DB24";
"DDR7_SB_DQS_DP2":   PN = "DJ21"  !CDS_PN = "DJ21";
"DDR7_SB_DQS_DP3":   PN = "DD18"  !CDS_PN = "DD18";
"DDR7_SB_DQS_DP4":   PN = "DF36"  !CDS_PN = "DF36";
"DDR7_SB_DQS_DP5":   PN = "DF30"  !CDS_PN = "DF30";
"DDR7_SB_DQS_DP6":   PN = "DF24"  !CDS_PN = "DF24";
"DDR7_SB_DQS_DP7":   PN = "DN21"  !CDS_PN = "DN21";
"DDR7_SB_DQS_DP8":   PN = "DH18"  !CDS_PN = "DH18";
"DDR7_SB_DQS_DP9":   PN = "DB36"  !CDS_PN = "DB36";
"DDR7_SB_ECC0":   PN = "DC35"  !CDS_PN = "DC35";
"DDR7_SB_ECC1":   PN = "DD34"  !CDS_PN = "DD34";
"DDR7_SB_ECC2":   PN = "DG35"  !CDS_PN = "DG35";
"DDR7_SB_ECC3":   PN = "DF34"  !CDS_PN = "DF34";
"DDR7_SB_ECC4":   PN = "DF38"  !CDS_PN = "DF38";
"DDR7_SB_ECC5":   PN = "DG37"  !CDS_PN = "DG37";
"DDR7_SB_ECC6":   PN = "DD38"  !CDS_PN = "DD38";
"DDR7_SB_ECC7":   PN = "DC37"  !CDS_PN = "DC37";
"DDR7_SB_PAR":   PN = "DR39"  !CDS_PN = "DR39";
"DDR7_SA_CS_N0":   PN = "DF51"  !CDS_PN = "DF51";
"DDR7_SA_CS_N1":   PN = "DG50"  !CDS_PN = "DG50";
"DDR7_SA_CS_N2":   PN = "DD51"  !CDS_PN = "DD51";
"DDR7_SA_CS_N3":   PN = "DC50"  !CDS_PN = "DC50";
"DDR7_SB_CS_N0":   PN = "DL37"  !CDS_PN = "DL37";
"DDR7_SB_CS_N1":   PN = "DN37"  !CDS_PN = "DN37";
"DDR7_SB_CS_N2":   PN = "DK38"  !CDS_PN = "DK38";
"DDR7_SB_CS_N3":   PN = "DP38"  !CDS_PN = "DP38";
DRAWING = "@s9s_mb_2u_lib.s9s_mb_2u(sch_1):page59";
BODY = "SOCKET4677_AZIF0045P001C01CS","I20": LOCATION = "U1" #&CDS_LOCATION = "U1" &SEC = "16" #&CDS_SEC = "16";
"DMI_RX_DN0":   PN = "BB18"  !CDS_PN = "BB18";
"DMI_RX_DN1":   PN = "BE17"  !CDS_PN = "BE17";
"DMI_RX_DN2":   PN = "BF18"  !CDS_PN = "BF18";
"DMI_RX_DN3":   PN = "BJ17"  !CDS_PN = "BJ17";
"DMI_RX_DN4":   PN = "BK18"  !CDS_PN = "BK18";
"DMI_RX_DN5":   PN = "BN17"  !CDS_PN = "BN17";
"DMI_RX_DN6":   PN = "BP18"  !CDS_PN = "BP18";
"DMI_RX_DN7":   PN = "BU17"  !CDS_PN = "BU17";
"DMI_RX_DP0":   PN = "BC19"  !CDS_PN = "BC19";
"DMI_RX_DP1":   PN = "BD18"  !CDS_PN = "BD18";
"DMI_RX_DP2":   PN = "BG19"  !CDS_PN = "BG19";
"DMI_RX_DP3":   PN = "BH18"  !CDS_PN = "BH18";
"DMI_RX_DP4":   PN = "BL19"  !CDS_PN = "BL19";
"DMI_RX_DP5":   PN = "BM18"  !CDS_PN = "BM18";
"DMI_RX_DP6":   PN = "BR19"  !CDS_PN = "BR19";
"DMI_RX_DP7":   PN = "BT18"  !CDS_PN = "BT18";
"DMI_TX_DN0":   PN = "BW19"  !CDS_PN = "BW19";
"DMI_TX_DN1":   PN = "CA17"  !CDS_PN = "CA17";
"DMI_TX_DN2":   PN = "CB18"  !CDS_PN = "CB18";
"DMI_TX_DN3":   PN = "CE17"  !CDS_PN = "CE17";
"DMI_TX_DN4":   PN = "CF18"  !CDS_PN = "CF18";
"DMI_TX_DN5":   PN = "CJ17"  !CDS_PN = "CJ17";
"DMI_TX_DN6":   PN = "CK18"  !CDS_PN = "CK18";
"DMI_TX_DN7":   PN = "CN17"  !CDS_PN = "CN17";
"DMI_TX_DP0":   PN = "CA19"  !CDS_PN = "CA19";
"DMI_TX_DP1":   PN = "BY18"  !CDS_PN = "BY18";
"DMI_TX_DP2":   PN = "CC19"  !CDS_PN = "CC19";
"DMI_TX_DP3":   PN = "CD18"  !CDS_PN = "CD18";
"DMI_TX_DP4":   PN = "CG19"  !CDS_PN = "CG19";
"DMI_TX_DP5":   PN = "CH18"  !CDS_PN = "CH18";
"DMI_TX_DP6":   PN = "CL19"  !CDS_PN = "CL19";
"DMI_TX_DP7":   PN = "CM18"  !CDS_PN = "CM18";
DRAWING = "@s9s_mb_2u_lib.s9s_mb_2u(sch_1):page60";
BODY = "SOCKET4677_AZIF0045P001C01CS","I69": LOCATION = "U1" #&CDS_LOCATION = "U1" &SEC = "18" #&CDS_SEC = "18";
"PE1_RX_DN0":   PN = "CP10"  !CDS_PN = "CP10";
"PE1_RX_DN1":   PN = "CL11"  !CDS_PN = "CL11";
"PE1_RX_DN2":   PN = "CK10"  !CDS_PN = "CK10";
"PE1_RX_DN3":   PN = "CG11"  !CDS_PN = "CG11";
"PE1_RX_DN4":   PN = "CF10"  !CDS_PN = "CF10";
"PE1_RX_DN5":   PN = "CC11"  !CDS_PN = "CC11";
"PE1_RX_DN6":   PN = "CB10"  !CDS_PN = "CB10";
"PE1_RX_DN7":   PN = "BW11"  !CDS_PN = "BW11";
"PE1_RX_DN8":   PN = "BV10"  !CDS_PN = "BV10";
"PE1_RX_DN9":   PN = "BR11"  !CDS_PN = "BR11";
"PE1_RX_DN10":   PN = "BP10"  !CDS_PN = "BP10";
"PE1_RX_DN11":   PN = "BL11"  !CDS_PN = "BL11";
"PE1_RX_DN12":   PN = "BK10"  !CDS_PN = "BK10";
"PE1_RX_DN13":   PN = "BG11"  !CDS_PN = "BG11";
"PE1_RX_DN14":   PN = "BF10"  !CDS_PN = "BF10";
"PE1_RX_DN15":   PN = "BC11"  !CDS_PN = "BC11";
"PE1_RX_DP0":   PN = "CN9"  !CDS_PN = "CN9";
"PE1_RX_DP1":   PN = "CM10"  !CDS_PN = "CM10";
"PE1_RX_DP2":   PN = "CJ9"  !CDS_PN = "CJ9";
"PE1_RX_DP3":   PN = "CH10"  !CDS_PN = "CH10";
"PE1_RX_DP4":   PN = "CE9"  !CDS_PN = "CE9";
"PE1_RX_DP5":   PN = "CD10"  !CDS_PN = "CD10";
"PE1_RX_DP6":   PN = "CA9"  !CDS_PN = "CA9";
"PE1_RX_DP7":   PN = "BY10"  !CDS_PN = "BY10";
"PE1_RX_DP8":   PN = "BU9"  !CDS_PN = "BU9";
"PE1_RX_DP9":   PN = "BT10"  !CDS_PN = "BT10";
"PE1_RX_DP10":   PN = "BN9"  !CDS_PN = "BN9";
"PE1_RX_DP11":   PN = "BM10"  !CDS_PN = "BM10";
"PE1_RX_DP12":   PN = "BJ9"  !CDS_PN = "BJ9";
"PE1_RX_DP13":   PN = "BH10"  !CDS_PN = "BH10";
"PE1_RX_DP14":   PN = "BE9"  !CDS_PN = "BE9";
"PE1_RX_DP15":   PN = "BD10"  !CDS_PN = "BD10";
"PE1_TX_DN0":   PN = "CP14"  !CDS_PN = "CP14";
"PE1_TX_DN1":   PN = "CN13"  !CDS_PN = "CN13";
"PE1_TX_DN2":   PN = "CK14"  !CDS_PN = "CK14";
"PE1_TX_DN3":   PN = "CJ13"  !CDS_PN = "CJ13";
"PE1_TX_DN4":   PN = "CF14"  !CDS_PN = "CF14";
"PE1_TX_DN5":   PN = "CE13"  !CDS_PN = "CE13";
"PE1_TX_DN6":   PN = "CB14"  !CDS_PN = "CB14";
"PE1_TX_DN7":   PN = "CA13"  !CDS_PN = "CA13";
"PE1_TX_DN8":   PN = "BV14"  !CDS_PN = "BV14";
"PE1_TX_DN9":   PN = "BU13"  !CDS_PN = "BU13";
"PE1_TX_DN10":   PN = "BP14"  !CDS_PN = "BP14";
"PE1_TX_DN11":   PN = "BN13"  !CDS_PN = "BN13";
"PE1_TX_DN12":   PN = "BK14"  !CDS_PN = "BK14";
"PE1_TX_DN13":   PN = "BJ13"  !CDS_PN = "BJ13";
"PE1_TX_DN14":   PN = "BF14"  !CDS_PN = "BF14";
"PE1_TX_DN15":   PN = "BE13"  !CDS_PN = "BE13";
"PE1_TX_DP0":   PN = "CR15"  !CDS_PN = "CR15";
"PE1_TX_DP1":   PN = "CM14"  !CDS_PN = "CM14";
"PE1_TX_DP2":   PN = "CL15"  !CDS_PN = "CL15";
"PE1_TX_DP3":   PN = "CH14"  !CDS_PN = "CH14";
"PE1_TX_DP4":   PN = "CG15"  !CDS_PN = "CG15";
"PE1_TX_DP5":   PN = "CD14"  !CDS_PN = "CD14";
"PE1_TX_DP6":   PN = "CC15"  !CDS_PN = "CC15";
"PE1_TX_DP7":   PN = "BY14"  !CDS_PN = "BY14";
"PE1_TX_DP8":   PN = "BW15"  !CDS_PN = "BW15";
"PE1_TX_DP9":   PN = "BT14"  !CDS_PN = "BT14";
"PE1_TX_DP10":   PN = "BR15"  !CDS_PN = "BR15";
"PE1_TX_DP11":   PN = "BM14"  !CDS_PN = "BM14";
"PE1_TX_DP12":   PN = "BL15"  !CDS_PN = "BL15";
"PE1_TX_DP13":   PN = "BH14"  !CDS_PN = "BH14";
"PE1_TX_DP14":   PN = "BG15"  !CDS_PN = "BG15";
"PE1_TX_DP15":   PN = "BD14"  !CDS_PN = "BD14";
BODY = "SOCKET4677_AZIF0045P001C01CS","I80": LOCATION = "U1" #&CDS_LOCATION = "U1" &SEC = "17" #&CDS_SEC = "17";
"PE0_RX_DN0":   PN = "K10"  !CDS_PN = "K10";
"PE0_RX_DN1":   PN = "M10"  !CDS_PN = "M10";
"PE0_RX_DN2":   PN = "P10"  !CDS_PN = "P10";
"PE0_RX_DN3":   PN = "T10"  !CDS_PN = "T10";
"PE0_RX_DN4":   PN = "V10"  !CDS_PN = "V10";
"PE0_RX_DN5":   PN = "AA9"  !CDS_PN = "AA9";
"PE0_RX_DN6":   PN = "AB10"  !CDS_PN = "AB10";
"PE0_RX_DN7":   PN = "AE9"  !CDS_PN = "AE9";
"PE0_RX_DN8":   PN = "AF10"  !CDS_PN = "AF10";
"PE0_RX_DN9":   PN = "AJ9"  !CDS_PN = "AJ9";
"PE0_RX_DN10":   PN = "AK10"  !CDS_PN = "AK10";
"PE0_RX_DN11":   PN = "AM10"  !CDS_PN = "AM10";
"PE0_RX_DN12":   PN = "AP10"  !CDS_PN = "AP10";
"PE0_RX_DN13":   PN = "AU9"  !CDS_PN = "AU9";
"PE0_RX_DN14":   PN = "AV10"  !CDS_PN = "AV10";
"PE0_RX_DN15":   PN = "BA9"  !CDS_PN = "BA9";
"PE0_RX_DP0":   PN = "L11"  !CDS_PN = "L11";
"PE0_RX_DP1":   PN = "N9"  !CDS_PN = "N9";
"PE0_RX_DP2":   PN = "R11"  !CDS_PN = "R11";
"PE0_RX_DP3":   PN = "U9"  !CDS_PN = "U9";
"PE0_RX_DP4":   PN = "W11"  !CDS_PN = "W11";
"PE0_RX_DP5":   PN = "Y10"  !CDS_PN = "Y10";
"PE0_RX_DP6":   PN = "AC11"  !CDS_PN = "AC11";
"PE0_RX_DP7":   PN = "AD10"  !CDS_PN = "AD10";
"PE0_RX_DP8":   PN = "AG11"  !CDS_PN = "AG11";
"PE0_RX_DP9":   PN = "AH10"  !CDS_PN = "AH10";
"PE0_RX_DP10":   PN = "AL11"  !CDS_PN = "AL11";
"PE0_RX_DP11":   PN = "AN9"  !CDS_PN = "AN9";
"PE0_RX_DP12":   PN = "AR11"  !CDS_PN = "AR11";
"PE0_RX_DP13":   PN = "AT10"  !CDS_PN = "AT10";
"PE0_RX_DP14":   PN = "AW11"  !CDS_PN = "AW11";
"PE0_RX_DP15":   PN = "AY10"  !CDS_PN = "AY10";
"PE0_TX_DN0":   PN = "N13"  !CDS_PN = "N13";
"PE0_TX_DN1":   PN = "P14"  !CDS_PN = "P14";
"PE0_TX_DN2":   PN = "U13"  !CDS_PN = "U13";
"PE0_TX_DN3":   PN = "V14"  !CDS_PN = "V14";
"PE0_TX_DN4":   PN = "AA13"  !CDS_PN = "AA13";
"PE0_TX_DN5":   PN = "AB14"  !CDS_PN = "AB14";
"PE0_TX_DN6":   PN = "AE13"  !CDS_PN = "AE13";
"PE0_TX_DN7":   PN = "AF14"  !CDS_PN = "AF14";
"PE0_TX_DN8":   PN = "AJ13"  !CDS_PN = "AJ13";
"PE0_TX_DN9":   PN = "AK14"  !CDS_PN = "AK14";
"PE0_TX_DN10":   PN = "AN13"  !CDS_PN = "AN13";
"PE0_TX_DN11":   PN = "AP14"  !CDS_PN = "AP14";
"PE0_TX_DN12":   PN = "AU13"  !CDS_PN = "AU13";
"PE0_TX_DN13":   PN = "AV14"  !CDS_PN = "AV14";
"PE0_TX_DN14":   PN = "BA13"  !CDS_PN = "BA13";
"PE0_TX_DN15":   PN = "BB14"  !CDS_PN = "BB14";
"PE0_TX_DP0":   PN = "M14"  !CDS_PN = "M14";
"PE0_TX_DP1":   PN = "R15"  !CDS_PN = "R15";
"PE0_TX_DP2":   PN = "T14"  !CDS_PN = "T14";
"PE0_TX_DP3":   PN = "W15"  !CDS_PN = "W15";
"PE0_TX_DP4":   PN = "Y14"  !CDS_PN = "Y14";
"PE0_TX_DP5":   PN = "AC15"  !CDS_PN = "AC15";
"PE0_TX_DP6":   PN = "AD14"  !CDS_PN = "AD14";
"PE0_TX_DP7":   PN = "AG15"  !CDS_PN = "AG15";
"PE0_TX_DP8":   PN = "AH14"  !CDS_PN = "AH14";
"PE0_TX_DP9":   PN = "AL15"  !CDS_PN = "AL15";
"PE0_TX_DP10":   PN = "AM14"  !CDS_PN = "AM14";
"PE0_TX_DP11":   PN = "AR15"  !CDS_PN = "AR15";
"PE0_TX_DP12":   PN = "AT14"  !CDS_PN = "AT14";
"PE0_TX_DP13":   PN = "AW15"  !CDS_PN = "AW15";
"PE0_TX_DP14":   PN = "AY14"  !CDS_PN = "AY14";
"PE0_TX_DP15":   PN = "BC15"  !CDS_PN = "BC15";
DRAWING = "@s9s_mb_2u_lib.s9s_mb_2u(sch_1):page61";
BODY = "SOCKET4677_AZIF0045P001C01CS","I12": LOCATION = "U1" #&CDS_LOCATION = "U1" &SEC = "20" #&CDS_SEC = "20";
"PE3_RX_DN0":   PN = "EH89"  !CDS_PN = "EH89";
"PE3_RX_DN1":   PN = "ED91"  !CDS_PN = "ED91";
"PE3_RX_DN2":   PN = "EC90"  !CDS_PN = "EC90";
"PE3_RX_DN3":   PN = "DY91"  !CDS_PN = "DY91";
"PE3_RX_DN4":   PN = "DV89"  !CDS_PN = "DV89";
"PE3_RX_DN5":   PN = "DU90"  !CDS_PN = "DU90";
"PE3_RX_DN6":   PN = "DP89"  !CDS_PN = "DP89";
"PE3_RX_DN7":   PN = "DN90"  !CDS_PN = "DN90";
"PE3_RX_DN8":   PN = "DL90"  !CDS_PN = "DL90";
"PE3_RX_DN9":   PN = "DH91"  !CDS_PN = "DH91";
"PE3_RX_DN10":   PN = "DG90"  !CDS_PN = "DG90";
"PE3_RX_DN11":   PN = "DD91"  !CDS_PN = "DD91";
"PE3_RX_DN12":   PN = "DB89"  !CDS_PN = "DB89";
"PE3_RX_DN13":   PN = "DA90"  !CDS_PN = "DA90";
"PE3_RX_DN14":   PN = "CV89"  !CDS_PN = "CV89";
"PE3_RX_DN15":   PN = "CU90"  !CDS_PN = "CU90";
"PE3_RX_DP0":   PN = "EJ90"  !CDS_PN = "EJ90";
"PE3_RX_DP1":   PN = "EE90"  !CDS_PN = "EE90";
"PE3_RX_DP2":   PN = "EB89"  !CDS_PN = "EB89";
"PE3_RX_DP3":   PN = "EA90"  !CDS_PN = "EA90";
"PE3_RX_DP4":   PN = "DW90"  !CDS_PN = "DW90";
"PE3_RX_DP5":   PN = "DT91"  !CDS_PN = "DT91";
"PE3_RX_DP6":   PN = "DR90"  !CDS_PN = "DR90";
"PE3_RX_DP7":   PN = "DM91"  !CDS_PN = "DM91";
"PE3_RX_DP8":   PN = "DK89"  !CDS_PN = "DK89";
"PE3_RX_DP9":   PN = "DJ90"  !CDS_PN = "DJ90";
"PE3_RX_DP10":   PN = "DF89"  !CDS_PN = "DF89";
"PE3_RX_DP11":   PN = "DE90"  !CDS_PN = "DE90";
"PE3_RX_DP12":   PN = "DC90"  !CDS_PN = "DC90";
"PE3_RX_DP13":   PN = "CY91"  !CDS_PN = "CY91";
"PE3_RX_DP14":   PN = "CW90"  !CDS_PN = "CW90";
"PE3_RX_DP15":   PN = "CT91"  !CDS_PN = "CT91";
"PE3_TX_DN0":   PN = "EE86"  !CDS_PN = "EE86";
"PE3_TX_DN1":   PN = "EB85"  !CDS_PN = "EB85";
"PE3_TX_DN2":   PN = "DY87"  !CDS_PN = "DY87";
"PE3_TX_DN3":   PN = "DV85"  !CDS_PN = "DV85";
"PE3_TX_DN4":   PN = "DT87"  !CDS_PN = "DT87";
"PE3_TX_DN5":   PN = "DP85"  !CDS_PN = "DP85";
"PE3_TX_DN6":   PN = "DM87"  !CDS_PN = "DM87";
"PE3_TX_DN7":   PN = "DK85"  !CDS_PN = "DK85";
"PE3_TX_DN8":   PN = "DH87"  !CDS_PN = "DH87";
"PE3_TX_DN9":   PN = "DF85"  !CDS_PN = "DF85";
"PE3_TX_DN10":   PN = "DD87"  !CDS_PN = "DD87";
"PE3_TX_DN11":   PN = "DB85"  !CDS_PN = "DB85";
"PE3_TX_DN12":   PN = "CY87"  !CDS_PN = "CY87";
"PE3_TX_DN13":   PN = "CV85"  !CDS_PN = "CV85";
"PE3_TX_DN14":   PN = "CT87"  !CDS_PN = "CT87";
"PE3_TX_DN15":   PN = "CP85"  !CDS_PN = "CP85";
"PE3_TX_DP0":   PN = "ED87"  !CDS_PN = "ED87";
"PE3_TX_DP1":   PN = "EC86"  !CDS_PN = "EC86";
"PE3_TX_DP2":   PN = "EA86"  !CDS_PN = "EA86";
"PE3_TX_DP3":   PN = "DW86"  !CDS_PN = "DW86";
"PE3_TX_DP4":   PN = "DU86"  !CDS_PN = "DU86";
"PE3_TX_DP5":   PN = "DR86"  !CDS_PN = "DR86";
"PE3_TX_DP6":   PN = "DN86"  !CDS_PN = "DN86";
"PE3_TX_DP7":   PN = "DL86"  !CDS_PN = "DL86";
"PE3_TX_DP8":   PN = "DJ86"  !CDS_PN = "DJ86";
"PE3_TX_DP9":   PN = "DG86"  !CDS_PN = "DG86";
"PE3_TX_DP10":   PN = "DE86"  !CDS_PN = "DE86";
"PE3_TX_DP11":   PN = "DC86"  !CDS_PN = "DC86";
"PE3_TX_DP12":   PN = "DA86"  !CDS_PN = "DA86";
"PE3_TX_DP13":   PN = "CW86"  !CDS_PN = "CW86";
"PE3_TX_DP14":   PN = "CU86"  !CDS_PN = "CU86";
"PE3_TX_DP15":   PN = "CR86"  !CDS_PN = "CR86";
BODY = "SOCKET4677_AZIF0045P001C01CS","I54": LOCATION = "U1" #&CDS_LOCATION = "U1" &SEC = "19" #&CDS_SEC = "19";
"PE2_RX_DN0":   PN = "CU9"  !CDS_PN = "CU9";
"PE2_RX_DN1":   PN = "CY10"  !CDS_PN = "CY10";
"PE2_RX_DN2":   PN = "DA9"  !CDS_PN = "DA9";
"PE2_RX_DN3":   PN = "DD10"  !CDS_PN = "DD10";
"PE2_RX_DN4":   PN = "DE9"  !CDS_PN = "DE9";
"PE2_RX_DN5":   PN = "DH10"  !CDS_PN = "DH10";
"PE2_RX_DN6":   PN = "DJ9"  !CDS_PN = "DJ9";
"PE2_RX_DN7":   PN = "DM10"  !CDS_PN = "DM10";
"PE2_RX_DN8":   PN = "DN9"  !CDS_PN = "DN9";
"PE2_RX_DN9":   PN = "DT10"  !CDS_PN = "DT10";
"PE2_RX_DN10":   PN = "DU9"  !CDS_PN = "DU9";
"PE2_RX_DN11":   PN = "DY10"  !CDS_PN = "DY10";
"PE2_RX_DN12":   PN = "EA9"  !CDS_PN = "EA9";
"PE2_RX_DN13":   PN = "ED10"  !CDS_PN = "ED10";
"PE2_RX_DN14":   PN = "EE9"  !CDS_PN = "EE9";
"PE2_RX_DN15":   PN = "EH10"  !CDS_PN = "EH10";
"PE2_RX_DP0":   PN = "CV10"  !CDS_PN = "CV10";
"PE2_RX_DP1":   PN = "CW11"  !CDS_PN = "CW11";
"PE2_RX_DP2":   PN = "DB10"  !CDS_PN = "DB10";
"PE2_RX_DP3":   PN = "DC11"  !CDS_PN = "DC11";
"PE2_RX_DP4":   PN = "DF10"  !CDS_PN = "DF10";
"PE2_RX_DP5":   PN = "DG11"  !CDS_PN = "DG11";
"PE2_RX_DP6":   PN = "DK10"  !CDS_PN = "DK10";
"PE2_RX_DP7":   PN = "DL11"  !CDS_PN = "DL11";
"PE2_RX_DP8":   PN = "DP10"  !CDS_PN = "DP10";
"PE2_RX_DP9":   PN = "DR11"  !CDS_PN = "DR11";
"PE2_RX_DP10":   PN = "DV10"  !CDS_PN = "DV10";
"PE2_RX_DP11":   PN = "DW11"  !CDS_PN = "DW11";
"PE2_RX_DP12":   PN = "EB10"  !CDS_PN = "EB10";
"PE2_RX_DP13":   PN = "EC11"  !CDS_PN = "EC11";
"PE2_RX_DP14":   PN = "EF10"  !CDS_PN = "EF10";
"PE2_RX_DP15":   PN = "EG11"  !CDS_PN = "EG11";
"PE2_TX_DN0":   PN = "CU13"  !CDS_PN = "CU13";
"PE2_TX_DN1":   PN = "CV14"  !CDS_PN = "CV14";
"PE2_TX_DN2":   PN = "DA13"  !CDS_PN = "DA13";
"PE2_TX_DN3":   PN = "DB14"  !CDS_PN = "DB14";
"PE2_TX_DN4":   PN = "DE13"  !CDS_PN = "DE13";
"PE2_TX_DN5":   PN = "DF14"  !CDS_PN = "DF14";
"PE2_TX_DN6":   PN = "DJ13"  !CDS_PN = "DJ13";
"PE2_TX_DN7":   PN = "DK14"  !CDS_PN = "DK14";
"PE2_TX_DN8":   PN = "DN13"  !CDS_PN = "DN13";
"PE2_TX_DN9":   PN = "DP14"  !CDS_PN = "DP14";
"PE2_TX_DN10":   PN = "DU13"  !CDS_PN = "DU13";
"PE2_TX_DN11":   PN = "DV14"  !CDS_PN = "DV14";
"PE2_TX_DN12":   PN = "EA13"  !CDS_PN = "EA13";
"PE2_TX_DN13":   PN = "EB14"  !CDS_PN = "EB14";
"PE2_TX_DN14":   PN = "EE13"  !CDS_PN = "EE13";
"PE2_TX_DN15":   PN = "EF14"  !CDS_PN = "EF14";
"PE2_TX_DP0":   PN = "CT14"  !CDS_PN = "CT14";
"PE2_TX_DP1":   PN = "CW15"  !CDS_PN = "CW15";
"PE2_TX_DP2":   PN = "CY14"  !CDS_PN = "CY14";
"PE2_TX_DP3":   PN = "DC15"  !CDS_PN = "DC15";
"PE2_TX_DP4":   PN = "DD14"  !CDS_PN = "DD14";
"PE2_TX_DP5":   PN = "DG15"  !CDS_PN = "DG15";
"PE2_TX_DP6":   PN = "DH14"  !CDS_PN = "DH14";
"PE2_TX_DP7":   PN = "DL15"  !CDS_PN = "DL15";
"PE2_TX_DP8":   PN = "DM14"  !CDS_PN = "DM14";
"PE2_TX_DP9":   PN = "DR15"  !CDS_PN = "DR15";
"PE2_TX_DP10":   PN = "DT14"  !CDS_PN = "DT14";
"PE2_TX_DP11":   PN = "DW15"  !CDS_PN = "DW15";
"PE2_TX_DP12":   PN = "DY14"  !CDS_PN = "DY14";
"PE2_TX_DP13":   PN = "EC15"  !CDS_PN = "EC15";
"PE2_TX_DP14":   PN = "ED14"  !CDS_PN = "ED14";
"PE2_TX_DP15":   PN = "EG15"  !CDS_PN = "EG15";
DRAWING = "@s9s_mb_2u_lib.s9s_mb_2u(sch_1):page62";
BODY = "SOCKET4677_AZIF0045P001C01CS","I18": LOCATION = "U1" #&CDS_LOCATION = "U1" &SEC = "21" #&CDS_SEC = "21";
"PE4_RX_DN0":   PN = "J90"  !CDS_PN = "J90";
"PE4_RX_DN1":   PN = "P89"  !CDS_PN = "P89";
"PE4_RX_DN2":   PN = "T91"  !CDS_PN = "T91";
"PE4_RX_DN3":   PN = "V89"  !CDS_PN = "V89";
"PE4_RX_DN4":   PN = "Y91"  !CDS_PN = "Y91";
"PE4_RX_DN5":   PN = "AB89"  !CDS_PN = "AB89";
"PE4_RX_DN6":   PN = "AD91"  !CDS_PN = "AD91";
"PE4_RX_DN7":   PN = "AF89"  !CDS_PN = "AF89";
"PE4_RX_DN8":   PN = "AH91"  !CDS_PN = "AH91";
"PE4_RX_DN9":   PN = "AK89"  !CDS_PN = "AK89";
"PE4_RX_DN10":   PN = "AM91"  !CDS_PN = "AM91";
"PE4_RX_DN11":   PN = "AP89"  !CDS_PN = "AP89";
"PE4_RX_DN12":   PN = "AT91"  !CDS_PN = "AT91";
"PE4_RX_DN13":   PN = "AV89"  !CDS_PN = "AV89";
"PE4_RX_DN14":   PN = "AY91"  !CDS_PN = "AY91";
"PE4_RX_DN15":   PN = "BB89"  !CDS_PN = "BB89";
"PE4_RX_DP0":   PN = "K89"  !CDS_PN = "K89";
"PE4_RX_DP1":   PN = "N90"  !CDS_PN = "N90";
"PE4_RX_DP2":   PN = "R90"  !CDS_PN = "R90";
"PE4_RX_DP3":   PN = "U90"  !CDS_PN = "U90";
"PE4_RX_DP4":   PN = "W90"  !CDS_PN = "W90";
"PE4_RX_DP5":   PN = "AA90"  !CDS_PN = "AA90";
"PE4_RX_DP6":   PN = "AC90"  !CDS_PN = "AC90";
"PE4_RX_DP7":   PN = "AE90"  !CDS_PN = "AE90";
"PE4_RX_DP8":   PN = "AG90"  !CDS_PN = "AG90";
"PE4_RX_DP9":   PN = "AJ90"  !CDS_PN = "AJ90";
"PE4_RX_DP10":   PN = "AL90"  !CDS_PN = "AL90";
"PE4_RX_DP11":   PN = "AN90"  !CDS_PN = "AN90";
"PE4_RX_DP12":   PN = "AR90"  !CDS_PN = "AR90";
"PE4_RX_DP13":   PN = "AU90"  !CDS_PN = "AU90";
"PE4_RX_DP14":   PN = "AW90"  !CDS_PN = "AW90";
"PE4_RX_DP15":   PN = "BA90"  !CDS_PN = "BA90";
"PE4_TX_DN0":   PN = "L86"  !CDS_PN = "L86";
"PE4_TX_DN1":   PN = "P85"  !CDS_PN = "P85";
"PE4_TX_DN2":   PN = "R86"  !CDS_PN = "R86";
"PE4_TX_DN3":   PN = "U86"  !CDS_PN = "U86";
"PE4_TX_DN4":   PN = "W86"  !CDS_PN = "W86";
"PE4_TX_DN5":   PN = "AA86"  !CDS_PN = "AA86";
"PE4_TX_DN6":   PN = "AC86"  !CDS_PN = "AC86";
"PE4_TX_DN7":   PN = "AE86"  !CDS_PN = "AE86";
"PE4_TX_DN8":   PN = "AG86"  !CDS_PN = "AG86";
"PE4_TX_DN9":   PN = "AJ86"  !CDS_PN = "AJ86";
"PE4_TX_DN10":   PN = "AL86"  !CDS_PN = "AL86";
"PE4_TX_DN11":   PN = "AP85"  !CDS_PN = "AP85";
"PE4_TX_DN12":   PN = "AR86"  !CDS_PN = "AR86";
"PE4_TX_DN13":   PN = "AU86"  !CDS_PN = "AU86";
"PE4_TX_DN14":   PN = "AW86"  !CDS_PN = "AW86";
"PE4_TX_DN15":   PN = "BA86"  !CDS_PN = "BA86";
"PE4_TX_DP0":   PN = "M87"  !CDS_PN = "M87";
"PE4_TX_DP1":   PN = "N86"  !CDS_PN = "N86";
"PE4_TX_DP2":   PN = "T87"  !CDS_PN = "T87";
"PE4_TX_DP3":   PN = "V85"  !CDS_PN = "V85";
"PE4_TX_DP4":   PN = "Y87"  !CDS_PN = "Y87";
"PE4_TX_DP5":   PN = "AB85"  !CDS_PN = "AB85";
"PE4_TX_DP6":   PN = "AD87"  !CDS_PN = "AD87";
"PE4_TX_DP7":   PN = "AF85"  !CDS_PN = "AF85";
"PE4_TX_DP8":   PN = "AH87"  !CDS_PN = "AH87";
"PE4_TX_DP9":   PN = "AK85"  !CDS_PN = "AK85";
"PE4_TX_DP10":   PN = "AM87"  !CDS_PN = "AM87";
"PE4_TX_DP11":   PN = "AN86"  !CDS_PN = "AN86";
"PE4_TX_DP12":   PN = "AT87"  !CDS_PN = "AT87";
"PE4_TX_DP13":   PN = "AV85"  !CDS_PN = "AV85";
"PE4_TX_DP14":   PN = "AY87"  !CDS_PN = "AY87";
"PE4_TX_DP15":   PN = "BB85"  !CDS_PN = "BB85";
DRAWING = "@s9s_mb_2u_lib.s9s_mb_2u(sch_1):page63";
BODY = "SOCKET4677_AZIF0045P001C01CS","I51": LOCATION = "U1" #&CDS_LOCATION = "U1" &SEC = "22" #&CDS_SEC = "22";
"UPI0_RX_DN0":   PN = "K6"  !CDS_PN = "K6";
"UPI0_RX_DN1":   PN = "N5"  !CDS_PN = "N5";
"UPI0_RX_DN2":   PN = "P6"  !CDS_PN = "P6";
"UPI0_RX_DN3":   PN = "U5"  !CDS_PN = "U5";
"UPI0_RX_DN4":   PN = "V6"  !CDS_PN = "V6";
"UPI0_RX_DN5":   PN = "AA5"  !CDS_PN = "AA5";
"UPI0_RX_DN6":   PN = "AB6"  !CDS_PN = "AB6";
"UPI0_RX_DN7":   PN = "AE5"  !CDS_PN = "AE5";
"UPI0_RX_DN8":   PN = "AF6"  !CDS_PN = "AF6";
"UPI0_RX_DN9":   PN = "AH6"  !CDS_PN = "AH6";
"UPI0_RX_DN10":   PN = "AK6"  !CDS_PN = "AK6";
"UPI0_RX_DN11":   PN = "AN5"  !CDS_PN = "AN5";
"UPI0_RX_DN12":   PN = "AP6"  !CDS_PN = "AP6";
"UPI0_RX_DN13":   PN = "AU5"  !CDS_PN = "AU5";
"UPI0_RX_DN14":   PN = "AV6"  !CDS_PN = "AV6";
"UPI0_RX_DN15":   PN = "BA5"  !CDS_PN = "BA5";
"UPI0_RX_DN16":   PN = "BB6"  !CDS_PN = "BB6";
"UPI0_RX_DN17":   PN = "BE5"  !CDS_PN = "BE5";
"UPI0_RX_DN18":   PN = "BF6"  !CDS_PN = "BF6";
"UPI0_RX_DN19":   PN = "BJ5"  !CDS_PN = "BJ5";
"UPI0_RX_DN20":   PN = "BK6"  !CDS_PN = "BK6";
"UPI0_RX_DN21":   PN = "BN5"  !CDS_PN = "BN5";
"UPI0_RX_DN22":   PN = "BR7"  !CDS_PN = "BR7";
"UPI0_RX_DN23":   PN = "BU5"  !CDS_PN = "BU5";
"UPI0_RX_DP0":   PN = "L7"  !CDS_PN = "L7";
"UPI0_RX_DP1":   PN = "M6"  !CDS_PN = "M6";
"UPI0_RX_DP2":   PN = "R7"  !CDS_PN = "R7";
"UPI0_RX_DP3":   PN = "T6"  !CDS_PN = "T6";
"UPI0_RX_DP4":   PN = "W7"  !CDS_PN = "W7";
"UPI0_RX_DP5":   PN = "Y6"  !CDS_PN = "Y6";
"UPI0_RX_DP6":   PN = "AC7"  !CDS_PN = "AC7";
"UPI0_RX_DP7":   PN = "AD6"  !CDS_PN = "AD6";
"UPI0_RX_DP8":   PN = "AG7"  !CDS_PN = "AG7";
"UPI0_RX_DP9":   PN = "AJ5"  !CDS_PN = "AJ5";
"UPI0_RX_DP10":   PN = "AL7"  !CDS_PN = "AL7";
"UPI0_RX_DP11":   PN = "AM6"  !CDS_PN = "AM6";
"UPI0_RX_DP12":   PN = "AR7"  !CDS_PN = "AR7";
"UPI0_RX_DP13":   PN = "AT6"  !CDS_PN = "AT6";
"UPI0_RX_DP14":   PN = "AW7"  !CDS_PN = "AW7";
"UPI0_RX_DP15":   PN = "AY6"  !CDS_PN = "AY6";
"UPI0_RX_DP16":   PN = "BC7"  !CDS_PN = "BC7";
"UPI0_RX_DP17":   PN = "BD6"  !CDS_PN = "BD6";
"UPI0_RX_DP18":   PN = "BG7"  !CDS_PN = "BG7";
"UPI0_RX_DP19":   PN = "BH6"  !CDS_PN = "BH6";
"UPI0_RX_DP20":   PN = "BL7"  !CDS_PN = "BL7";
"UPI0_RX_DP21":   PN = "BM6"  !CDS_PN = "BM6";
"UPI0_RX_DP22":   PN = "BP6"  !CDS_PN = "BP6";
"UPI0_RX_DP23":   PN = "BT6"  !CDS_PN = "BT6";
"UPI0_TX_DN0":   PN = "K4"  !CDS_PN = "K4";
"UPI0_TX_DN1":   PN = "M2"  !CDS_PN = "M2";
"UPI0_TX_DN2":   PN = "N1"  !CDS_PN = "N1";
"UPI0_TX_DN3":   PN = "T2"  !CDS_PN = "T2";
"UPI0_TX_DN4":   PN = "U1"  !CDS_PN = "U1";
"UPI0_TX_DN5":   PN = "Y2"  !CDS_PN = "Y2";
"UPI0_TX_DN6":   PN = "AA1"  !CDS_PN = "AA1";
"UPI0_TX_DN7":   PN = "AD2"  !CDS_PN = "AD2";
"UPI0_TX_DN8":   PN = "AF2"  !CDS_PN = "AF2";
"UPI0_TX_DN9":   PN = "AH2"  !CDS_PN = "AH2";
"UPI0_TX_DN10":   PN = "AK2"  !CDS_PN = "AK2";
"UPI0_TX_DN11":   PN = "AM2"  !CDS_PN = "AM2";
"UPI0_TX_DN12":   PN = "AP2"  !CDS_PN = "AP2";
"UPI0_TX_DN13":   PN = "AT2"  !CDS_PN = "AT2";
"UPI0_TX_DN14":   PN = "AU1"  !CDS_PN = "AU1";
"UPI0_TX_DN15":   PN = "AY2"  !CDS_PN = "AY2";
"UPI0_TX_DN16":   PN = "BB2"  !CDS_PN = "BB2";
"UPI0_TX_DN17":   PN = "BD2"  !CDS_PN = "BD2";
"UPI0_TX_DN18":   PN = "BF2"  !CDS_PN = "BF2";
"UPI0_TX_DN19":   PN = "BH2"  !CDS_PN = "BH2";
"UPI0_TX_DN20":   PN = "BK2"  !CDS_PN = "BK2";
"UPI0_TX_DN21":   PN = "BM2"  !CDS_PN = "BM2";
"UPI0_TX_DN22":   PN = "BR3"  !CDS_PN = "BR3";
"UPI0_TX_DN23":   PN = "BT2"  !CDS_PN = "BT2";
"UPI0_TX_DP0":   PN = "J3"  !CDS_PN = "J3";
"UPI0_TX_DP1":   PN = "L3"  !CDS_PN = "L3";
"UPI0_TX_DP2":   PN = "P2"  !CDS_PN = "P2";
"UPI0_TX_DP3":   PN = "R3"  !CDS_PN = "R3";
"UPI0_TX_DP4":   PN = "V2"  !CDS_PN = "V2";
"UPI0_TX_DP5":   PN = "W3"  !CDS_PN = "W3";
"UPI0_TX_DP6":   PN = "AB2"  !CDS_PN = "AB2";
"UPI0_TX_DP7":   PN = "AC3"  !CDS_PN = "AC3";
"UPI0_TX_DP8":   PN = "AE1"  !CDS_PN = "AE1";
"UPI0_TX_DP9":   PN = "AG3"  !CDS_PN = "AG3";
"UPI0_TX_DP10":   PN = "AJ1"  !CDS_PN = "AJ1";
"UPI0_TX_DP11":   PN = "AL3"  !CDS_PN = "AL3";
"UPI0_TX_DP12":   PN = "AN1"  !CDS_PN = "AN1";
"UPI0_TX_DP13":   PN = "AR3"  !CDS_PN = "AR3";
"UPI0_TX_DP14":   PN = "AV2"  !CDS_PN = "AV2";
"UPI0_TX_DP15":   PN = "AW3"  !CDS_PN = "AW3";
"UPI0_TX_DP16":   PN = "BA1"  !CDS_PN = "BA1";
"UPI0_TX_DP17":   PN = "BC3"  !CDS_PN = "BC3";
"UPI0_TX_DP18":   PN = "BE1"  !CDS_PN = "BE1";
"UPI0_TX_DP19":   PN = "BG3"  !CDS_PN = "BG3";
"UPI0_TX_DP20":   PN = "BJ1"  !CDS_PN = "BJ1";
"UPI0_TX_DP21":   PN = "BL3"  !CDS_PN = "BL3";
"UPI0_TX_DP22":   PN = "BN3"  !CDS_PN = "BN3";
"UPI0_TX_DP23":   PN = "BU3"  !CDS_PN = "BU3";
DRAWING = "@s9s_mb_2u_lib.s9s_mb_2u(sch_1):page64";
BODY = "SOCKET4677_AZIF0045P001C01CS","I21": LOCATION = "U1" #&CDS_LOCATION = "U1" &SEC = "23" #&CDS_SEC = "23";
"UPI1_RX_DN0":   PN = "EH2"  !CDS_PN = "EH2";
"UPI1_RX_DN1":   PN = "EE3"  !CDS_PN = "EE3";
"UPI1_RX_DN2":   PN = "ED2"  !CDS_PN = "ED2";
"UPI1_RX_DN3":   PN = "EA1"  !CDS_PN = "EA1";
"UPI1_RX_DN4":   PN = "DY2"  !CDS_PN = "DY2";
"UPI1_RX_DN5":   PN = "DU1"  !CDS_PN = "DU1";
"UPI1_RX_DN6":   PN = "DT2"  !CDS_PN = "DT2";
"UPI1_RX_DN7":   PN = "DN1"  !CDS_PN = "DN1";
"UPI1_RX_DN8":   PN = "DL3"  !CDS_PN = "DL3";
"UPI1_RX_DN9":   PN = "DJ1"  !CDS_PN = "DJ1";
"UPI1_RX_DN10":   PN = "DG3"  !CDS_PN = "DG3";
"UPI1_RX_DN11":   PN = "DE1"  !CDS_PN = "DE1";
"UPI1_RX_DN12":   PN = "DD2"  !CDS_PN = "DD2";
"UPI1_RX_DN13":   PN = "DB2"  !CDS_PN = "DB2";
"UPI1_RX_DN14":   PN = "CY2"  !CDS_PN = "CY2";
"UPI1_RX_DN15":   PN = "CV2"  !CDS_PN = "CV2";
"UPI1_RX_DN16":   PN = "CR3"  !CDS_PN = "CR3";
"UPI1_RX_DN17":   PN = "CN1"  !CDS_PN = "CN1";
"UPI1_RX_DN18":   PN = "CL3"  !CDS_PN = "CL3";
"UPI1_RX_DN19":   PN = "CJ1"  !CDS_PN = "CJ1";
"UPI1_RX_DN20":   PN = "CH2"  !CDS_PN = "CH2";
"UPI1_RX_DN21":   PN = "CF2"  !CDS_PN = "CF2";
"UPI1_RX_DN22":   PN = "CD2"  !CDS_PN = "CD2";
"UPI1_RX_DN23":   PN = "CB2"  !CDS_PN = "CB2";
"UPI1_RX_DP0":   PN = "EJ3"  !CDS_PN = "EJ3";
"UPI1_RX_DP1":   PN = "EG3"  !CDS_PN = "EG3";
"UPI1_RX_DP2":   PN = "EC3"  !CDS_PN = "EC3";
"UPI1_RX_DP3":   PN = "EB2"  !CDS_PN = "EB2";
"UPI1_RX_DP4":   PN = "DW3"  !CDS_PN = "DW3";
"UPI1_RX_DP5":   PN = "DV2"  !CDS_PN = "DV2";
"UPI1_RX_DP6":   PN = "DR3"  !CDS_PN = "DR3";
"UPI1_RX_DP7":   PN = "DP2"  !CDS_PN = "DP2";
"UPI1_RX_DP8":   PN = "DM2"  !CDS_PN = "DM2";
"UPI1_RX_DP9":   PN = "DK2"  !CDS_PN = "DK2";
"UPI1_RX_DP10":   PN = "DH2"  !CDS_PN = "DH2";
"UPI1_RX_DP11":   PN = "DF2"  !CDS_PN = "DF2";
"UPI1_RX_DP12":   PN = "DC3"  !CDS_PN = "DC3";
"UPI1_RX_DP13":   PN = "DA1"  !CDS_PN = "DA1";
"UPI1_RX_DP14":   PN = "CW3"  !CDS_PN = "CW3";
"UPI1_RX_DP15":   PN = "CU1"  !CDS_PN = "CU1";
"UPI1_RX_DP16":   PN = "CT2"  !CDS_PN = "CT2";
"UPI1_RX_DP17":   PN = "CP2"  !CDS_PN = "CP2";
"UPI1_RX_DP18":   PN = "CM2"  !CDS_PN = "CM2";
"UPI1_RX_DP19":   PN = "CK2"  !CDS_PN = "CK2";
"UPI1_RX_DP20":   PN = "CG3"  !CDS_PN = "CG3";
"UPI1_RX_DP21":   PN = "CE1"  !CDS_PN = "CE1";
"UPI1_RX_DP22":   PN = "CC3"  !CDS_PN = "CC3";
"UPI1_RX_DP23":   PN = "BY2"  !CDS_PN = "BY2";
"UPI1_TX_DN0":   PN = "EF6"  !CDS_PN = "EF6";
"UPI1_TX_DN1":   PN = "EC7"  !CDS_PN = "EC7";
"UPI1_TX_DN2":   PN = "EB6"  !CDS_PN = "EB6";
"UPI1_TX_DN3":   PN = "DY6"  !CDS_PN = "DY6";
"UPI1_TX_DN4":   PN = "DV6"  !CDS_PN = "DV6";
"UPI1_TX_DN5":   PN = "DT6"  !CDS_PN = "DT6";
"UPI1_TX_DN6":   PN = "DP6"  !CDS_PN = "DP6";
"UPI1_TX_DN7":   PN = "DL7"  !CDS_PN = "DL7";
"UPI1_TX_DN8":   PN = "DK6"  !CDS_PN = "DK6";
"UPI1_TX_DN9":   PN = "DH6"  !CDS_PN = "DH6";
"UPI1_TX_DN10":   PN = "DE5"  !CDS_PN = "DE5";
"UPI1_TX_DN11":   PN = "DD6"  !CDS_PN = "DD6";
"UPI1_TX_DN12":   PN = "DA5"  !CDS_PN = "DA5";
"UPI1_TX_DN13":   PN = "CY6"  !CDS_PN = "CY6";
"UPI1_TX_DN14":   PN = "CU5"  !CDS_PN = "CU5";
"UPI1_TX_DN15":   PN = "CT6"  !CDS_PN = "CT6";
"UPI1_TX_DN16":   PN = "CN5"  !CDS_PN = "CN5";
"UPI1_TX_DN17":   PN = "CM6"  !CDS_PN = "CM6";
"UPI1_TX_DN18":   PN = "CJ5"  !CDS_PN = "CJ5";
"UPI1_TX_DN19":   PN = "CH6"  !CDS_PN = "CH6";
"UPI1_TX_DN20":   PN = "CE5"  !CDS_PN = "CE5";
"UPI1_TX_DN21":   PN = "CD6"  !CDS_PN = "CD6";
"UPI1_TX_DN22":   PN = "CA5"  !CDS_PN = "CA5";
"UPI1_TX_DN23":   PN = "BY6"  !CDS_PN = "BY6";
"UPI1_TX_DP0":   PN = "EE5"  !CDS_PN = "EE5";
"UPI1_TX_DP1":   PN = "ED6"  !CDS_PN = "ED6";
"UPI1_TX_DP2":   PN = "EA5"  !CDS_PN = "EA5";
"UPI1_TX_DP3":   PN = "DW7"  !CDS_PN = "DW7";
"UPI1_TX_DP4":   PN = "DU5"  !CDS_PN = "DU5";
"UPI1_TX_DP5":   PN = "DR7"  !CDS_PN = "DR7";
"UPI1_TX_DP6":   PN = "DN5"  !CDS_PN = "DN5";
"UPI1_TX_DP7":   PN = "DM6"  !CDS_PN = "DM6";
"UPI1_TX_DP8":   PN = "DJ5"  !CDS_PN = "DJ5";
"UPI1_TX_DP9":   PN = "DG7"  !CDS_PN = "DG7";
"UPI1_TX_DP10":   PN = "DF6"  !CDS_PN = "DF6";
"UPI1_TX_DP11":   PN = "DC7"  !CDS_PN = "DC7";
"UPI1_TX_DP12":   PN = "DB6"  !CDS_PN = "DB6";
"UPI1_TX_DP13":   PN = "CW7"  !CDS_PN = "CW7";
"UPI1_TX_DP14":   PN = "CV6"  !CDS_PN = "CV6";
"UPI1_TX_DP15":   PN = "CR7"  !CDS_PN = "CR7";
"UPI1_TX_DP16":   PN = "CP6"  !CDS_PN = "CP6";
"UPI1_TX_DP17":   PN = "CL7"  !CDS_PN = "CL7";
"UPI1_TX_DP18":   PN = "CK6"  !CDS_PN = "CK6";
"UPI1_TX_DP19":   PN = "CG7"  !CDS_PN = "CG7";
"UPI1_TX_DP20":   PN = "CF6"  !CDS_PN = "CF6";
"UPI1_TX_DP21":   PN = "CC7"  !CDS_PN = "CC7";
"UPI1_TX_DP22":   PN = "CB6"  !CDS_PN = "CB6";
"UPI1_TX_DP23":   PN = "BW7"  !CDS_PN = "BW7";
DRAWING = "@s9s_mb_2u_lib.s9s_mb_2u(sch_1):page65";
BODY = "SOCKET4677_AZIF0045P001C01CS","I16": LOCATION = "U1" #&CDS_LOCATION = "U1" &SEC = "24" #&CDS_SEC = "24";
"UPI2_RX_DN0":   PN = "E80"  !CDS_PN = "E80";
"UPI2_RX_DN1":   PN = "F81"  !CDS_PN = "F81";
"UPI2_RX_DN2":   PN = "G82"  !CDS_PN = "G82";
"UPI2_RX_DN3":   PN = "K79"  !CDS_PN = "K79";
"UPI2_RX_DN4":   PN = "J82"  !CDS_PN = "J82";
"UPI2_RX_DN5":   PN = "L80"  !CDS_PN = "L80";
"UPI2_RX_DN6":   PN = "AC80"  !CDS_PN = "AC80";
"UPI2_RX_DN7":   PN = "AD81"  !CDS_PN = "AD81";
"UPI2_RX_DN8":   PN = "AF79"  !CDS_PN = "AF79";
"UPI2_RX_DN9":   PN = "AE82"  !CDS_PN = "AE82";
"UPI2_RX_DN10":   PN = "AJ80"  !CDS_PN = "AJ80";
"UPI2_RX_DN11":   PN = "AG82"  !CDS_PN = "AG82";
"UPI2_RX_DN12":   PN = "BA72"  !CDS_PN = "BA72";
"UPI2_RX_DN13":   PN = "AV73"  !CDS_PN = "AV73";
"UPI2_RX_DN14":   PN = "AY75"  !CDS_PN = "AY75";
"UPI2_RX_DN15":   PN = "BB75"  !CDS_PN = "BB75";
"UPI2_RX_DN16":   PN = "AW74"  !CDS_PN = "AW74";
"UPI2_RX_DN17":   PN = "BH75"  !CDS_PN = "BH75";
"UPI2_RX_DN18":   PN = "BJ76"  !CDS_PN = "BJ76";
"UPI2_RX_DN19":   PN = "BL76"  !CDS_PN = "BL76";
"UPI2_RX_DN20":   PN = "BG74"  !CDS_PN = "BG74";
"UPI2_RX_DN21":   PN = "BN74"  !CDS_PN = "BN74";
"UPI2_RX_DN22":   PN = "BK73"  !CDS_PN = "BK73";
"UPI2_RX_DN23":   PN = "BD73"  !CDS_PN = "BD73";
"UPI2_RX_DP0":   PN = "G80"  !CDS_PN = "G80";
"UPI2_RX_DP1":   PN = "E82"  !CDS_PN = "E82";
"UPI2_RX_DP2":   PN = "H83"  !CDS_PN = "H83";
"UPI2_RX_DP3":   PN = "M79"  !CDS_PN = "M79";
"UPI2_RX_DP4":   PN = "L82"  !CDS_PN = "L82";
"UPI2_RX_DP5":   PN = "K81"  !CDS_PN = "K81";
"UPI2_RX_DP6":   PN = "AE80"  !CDS_PN = "AE80";
"UPI2_RX_DP7":   PN = "AC82"  !CDS_PN = "AC82";
"UPI2_RX_DP8":   PN = "AG80"  !CDS_PN = "AG80";
"UPI2_RX_DP9":   PN = "AF83"  !CDS_PN = "AF83";
"UPI2_RX_DP10":   PN = "AH81"  !CDS_PN = "AH81";
"UPI2_RX_DP11":   PN = "AJ82"  !CDS_PN = "AJ82";
"UPI2_RX_DP12":   PN = "BB73"  !CDS_PN = "BB73";
"UPI2_RX_DP13":   PN = "AY73"  !CDS_PN = "AY73";
"UPI2_RX_DP14":   PN = "BA76"  !CDS_PN = "BA76";
"UPI2_RX_DP15":   PN = "BD75"  !CDS_PN = "BD75";
"UPI2_RX_DP16":   PN = "AV75"  !CDS_PN = "AV75";
"UPI2_RX_DP17":   PN = "BG76"  !CDS_PN = "BG76";
"UPI2_RX_DP18":   PN = "BK77"  !CDS_PN = "BK77";
"UPI2_RX_DP19":   PN = "BN76"  !CDS_PN = "BN76";
"UPI2_RX_DP20":   PN = "BJ74"  !CDS_PN = "BJ74";
"UPI2_RX_DP21":   PN = "BM75"  !CDS_PN = "BM75";
"UPI2_RX_DP22":   PN = "BL74"  !CDS_PN = "BL74";
"UPI2_RX_DP23":   PN = "BC74"  !CDS_PN = "BC74";
"UPI2_TX_DN0":   PN = "B85"  !CDS_PN = "B85";
"UPI2_TX_DN1":   PN = "E84"  !CDS_PN = "E84";
"UPI2_TX_DN2":   PN = "D87"  !CDS_PN = "D87";
"UPI2_TX_DN3":   PN = "F87"  !CDS_PN = "F87";
"UPI2_TX_DN4":   PN = "H85"  !CDS_PN = "H85";
"UPI2_TX_DN5":   PN = "P81"  !CDS_PN = "P81";
"UPI2_TX_DN6":   PN = "R82"  !CDS_PN = "R82";
"UPI2_TX_DN7":   PN = "U80"  !CDS_PN = "U80";
"UPI2_TX_DN8":   PN = "V83"  !CDS_PN = "V83";
"UPI2_TX_DN9":   PN = "Y81"  !CDS_PN = "Y81";
"UPI2_TX_DN10":   PN = "AW78"  !CDS_PN = "AW78";
"UPI2_TX_DN11":   PN = "AU78"  !CDS_PN = "AU78";
"UPI2_TX_DN12":   PN = "AM81"  !CDS_PN = "AM81";
"UPI2_TX_DN13":   PN = "AN82"  !CDS_PN = "AN82";
"UPI2_TX_DN14":   PN = "AR80"  !CDS_PN = "AR80";
"UPI2_TX_DN15":   PN = "AT83"  !CDS_PN = "AT83";
"UPI2_TX_DN16":   PN = "AV81"  !CDS_PN = "AV81";
"UPI2_TX_DN17":   PN = "BA80"  !CDS_PN = "BA80";
"UPI2_TX_DN18":   PN = "BC82"  !CDS_PN = "BC82";
"UPI2_TX_DN19":   PN = "BE82"  !CDS_PN = "BE82";
"UPI2_TX_DN20":   PN = "BD79"  !CDS_PN = "BD79";
"UPI2_TX_DN21":   PN = "BF81"  !CDS_PN = "BF81";
"UPI2_TX_DN22":   PN = "BG80"  !CDS_PN = "BG80";
"UPI2_TX_DN23":   PN = "BM71"  !CDS_PN = "BM71";
"UPI2_TX_DP0":   PN = "D85"  !CDS_PN = "D85";
"UPI2_TX_DP1":   PN = "F85"  !CDS_PN = "F85";
"UPI2_TX_DP2":   PN = "E88"  !CDS_PN = "E88";
"UPI2_TX_DP3":   PN = "H87"  !CDS_PN = "H87";
"UPI2_TX_DP4":   PN = "G86"  !CDS_PN = "G86";
"UPI2_TX_DP5":   PN = "T81"  !CDS_PN = "T81";
"UPI2_TX_DP6":   PN = "P83"  !CDS_PN = "P83";
"UPI2_TX_DP7":   PN = "V81"  !CDS_PN = "V81";
"UPI2_TX_DP8":   PN = "Y83"  !CDS_PN = "Y83";
"UPI2_TX_DP9":   PN = "W82"  !CDS_PN = "W82";
"UPI2_TX_DP10":   PN = "BA78"  !CDS_PN = "BA78";
"UPI2_TX_DP11":   PN = "AV79"  !CDS_PN = "AV79";
"UPI2_TX_DP12":   PN = "AP81"  !CDS_PN = "AP81";
"UPI2_TX_DP13":   PN = "AM83"  !CDS_PN = "AM83";
"UPI2_TX_DP14":   PN = "AT81"  !CDS_PN = "AT81";
"UPI2_TX_DP15":   PN = "AV83"  !CDS_PN = "AV83";
"UPI2_TX_DP16":   PN = "AU82"  !CDS_PN = "AU82";
"UPI2_TX_DP17":   PN = "BB81"  !CDS_PN = "BB81";
"UPI2_TX_DP18":   PN = "BA82"  !CDS_PN = "BA82";
"UPI2_TX_DP19":   PN = "BD83"  !CDS_PN = "BD83";
"UPI2_TX_DP20":   PN = "BC80"  !CDS_PN = "BC80";
"UPI2_TX_DP21":   PN = "BG82"  !CDS_PN = "BG82";
"UPI2_TX_DP22":   PN = "BE80"  !CDS_PN = "BE80";
"UPI2_TX_DP23":   PN = "BN72"  !CDS_PN = "BN72";
DRAWING = "@s9s_mb_2u_lib.s9s_mb_2u(sch_1):page66";
BODY = "SOCKET4677_AZIF0045P001C01CS","I16": LOCATION = "U1" #&CDS_LOCATION = "U1" &SEC = "25" #&CDS_SEC = "25";
"UPI3_RX_DN0":   PN = "EJ80"  !CDS_PN = "EJ80";
"UPI3_RX_DN1":   PN = "EP81"  !CDS_PN = "EP81";
"UPI3_RX_DN2":   PN = "EL82"  !CDS_PN = "EL82";
"UPI3_RX_DN3":   PN = "EK81"  !CDS_PN = "EK81";
"UPI3_RX_DN4":   PN = "EF81"  !CDS_PN = "EF81";
"UPI3_RX_DN5":   PN = "ED83"  !CDS_PN = "ED83";
"UPI3_RX_DN6":   PN = "EC80"  !CDS_PN = "EC80";
"UPI3_RX_DN7":   PN = "EA82"  !CDS_PN = "EA82";
"UPI3_RX_DN8":   PN = "DY81"  !CDS_PN = "DY81";
"UPI3_RX_DN9":   PN = "DJ78"  !CDS_PN = "DJ78";
"UPI3_RX_DN10":   PN = "DG78"  !CDS_PN = "DG78";
"UPI3_RX_DN11":   PN = "DH81"  !CDS_PN = "DH81";
"UPI3_RX_DN12":   PN = "DF83"  !CDS_PN = "DF83";
"UPI3_RX_DN13":   PN = "DE80"  !CDS_PN = "DE80";
"UPI3_RX_DN14":   PN = "DC82"  !CDS_PN = "DC82";
"UPI3_RX_DN15":   PN = "DB81"  !CDS_PN = "DB81";
"UPI3_RX_DN16":   PN = "DF77"  !CDS_PN = "DF77";
"UPI3_RX_DN17":   PN = "CU82"  !CDS_PN = "CU82";
"UPI3_RX_DN18":   PN = "CR82"  !CDS_PN = "CR82";
"UPI3_RX_DN19":   PN = "CW80"  !CDS_PN = "CW80";
"UPI3_RX_DN20":   PN = "CP81"  !CDS_PN = "CP81";
"UPI3_RX_DN21":   PN = "CN80"  !CDS_PN = "CN80";
"UPI3_RX_DN22":   PN = "CT79"  !CDS_PN = "CT79";
"UPI3_RX_DN23":   PN = "DA78"  !CDS_PN = "DA78";
"UPI3_RX_DP0":   PN = "EL80"  !CDS_PN = "EL80";
"UPI3_RX_DP1":   PN = "ER82"  !CDS_PN = "ER82";
"UPI3_RX_DP2":   PN = "EN82"  !CDS_PN = "EN82";
"UPI3_RX_DP3":   PN = "EJ82"  !CDS_PN = "EJ82";
"UPI3_RX_DP4":   PN = "EE82"  !CDS_PN = "EE82";
"UPI3_RX_DP5":   PN = "EF83"  !CDS_PN = "EF83";
"UPI3_RX_DP6":   PN = "ED81"  !CDS_PN = "ED81";
"UPI3_RX_DP7":   PN = "DY83"  !CDS_PN = "DY83";
"UPI3_RX_DP8":   PN = "EB81"  !CDS_PN = "EB81";
"UPI3_RX_DP9":   PN = "DL78"  !CDS_PN = "DL78";
"UPI3_RX_DP10":   PN = "DH79"  !CDS_PN = "DH79";
"UPI3_RX_DP11":   PN = "DG82"  !CDS_PN = "DG82";
"UPI3_RX_DP12":   PN = "DH83"  !CDS_PN = "DH83";
"UPI3_RX_DP13":   PN = "DF81"  !CDS_PN = "DF81";
"UPI3_RX_DP14":   PN = "DB83"  !CDS_PN = "DB83";
"UPI3_RX_DP15":   PN = "DD81"  !CDS_PN = "DD81";
"UPI3_RX_DP16":   PN = "DE78"  !CDS_PN = "DE78";
"UPI3_RX_DP17":   PN = "CW82"  !CDS_PN = "CW82";
"UPI3_RX_DP18":   PN = "CT83"  !CDS_PN = "CT83";
"UPI3_RX_DP19":   PN = "CV81"  !CDS_PN = "CV81";
"UPI3_RX_DP20":   PN = "CN82"  !CDS_PN = "CN82";
"UPI3_RX_DP21":   PN = "CR80"  !CDS_PN = "CR80";
"UPI3_RX_DP22":   PN = "CU80"  !CDS_PN = "CU80";
"UPI3_RX_DP23":   PN = "DB79"  !CDS_PN = "DB79";
"UPI3_TX_DN0":   PN = "EH85"  !CDS_PN = "EH85";
"UPI3_TX_DN1":   PN = "EL84"  !CDS_PN = "EL84";
"UPI3_TX_DN2":   PN = "EP85"  !CDS_PN = "EP85";
"UPI3_TX_DN3":   PN = "EM87"  !CDS_PN = "EM87";
"UPI3_TX_DN4":   PN = "EJ86"  !CDS_PN = "EJ86";
"UPI3_TX_DN5":   PN = "EK87"  !CDS_PN = "EK87";
"UPI3_TX_DN6":   PN = "DU80"  !CDS_PN = "DU80";
"UPI3_TX_DN7":   PN = "DR82"  !CDS_PN = "DR82";
"UPI3_TX_DN8":   PN = "DP79"  !CDS_PN = "DP79";
"UPI3_TX_DN9":   PN = "DN82"  !CDS_PN = "DN82";
"UPI3_TX_DN10":   PN = "DM81"  !CDS_PN = "DM81";
"UPI3_TX_DN11":   PN = "DL80"  !CDS_PN = "DL80";
"UPI3_TX_DN12":   PN = "CW76"  !CDS_PN = "CW76";
"UPI3_TX_DN13":   PN = "CU76"  !CDS_PN = "CU76";
"UPI3_TX_DN14":   PN = "CT75"  !CDS_PN = "CT75";
"UPI3_TX_DN15":   PN = "CR74"  !CDS_PN = "CR74";
"UPI3_TX_DN16":   PN = "CK77"  !CDS_PN = "CK77";
"UPI3_TX_DN17":   PN = "CH77"  !CDS_PN = "CH77";
"UPI3_TX_DN18":   PN = "CM75"  !CDS_PN = "CM75";
"UPI3_TX_DN19":   PN = "CG76"  !CDS_PN = "CG76";
"UPI3_TX_DN20":   PN = "CF75"  !CDS_PN = "CF75";
"UPI3_TX_DN21":   PN = "CJ74"  !CDS_PN = "CJ74";
"UPI3_TX_DN22":   PN = "CV73"  !CDS_PN = "CV73";
"UPI3_TX_DN23":   PN = "CF73"  !CDS_PN = "CF73";
"UPI3_TX_DP0":   PN = "EK85"  !CDS_PN = "EK85";
"UPI3_TX_DP1":   PN = "EM85"  !CDS_PN = "EM85";
"UPI3_TX_DP2":   PN = "EN86"  !CDS_PN = "EN86";
"UPI3_TX_DP3":   PN = "EP87"  !CDS_PN = "EP87";
"UPI3_TX_DP4":   PN = "EH87"  !CDS_PN = "EH87";
"UPI3_TX_DP5":   PN = "EL88"  !CDS_PN = "EL88";
"UPI3_TX_DP6":   PN = "DT81"  !CDS_PN = "DT81";
"UPI3_TX_DP7":   PN = "DU82"  !CDS_PN = "DU82";
"UPI3_TX_DP8":   PN = "DR80"  !CDS_PN = "DR80";
"UPI3_TX_DP9":   PN = "DP83"  !CDS_PN = "DP83";
"UPI3_TX_DP10":   PN = "DL82"  !CDS_PN = "DL82";
"UPI3_TX_DP11":   PN = "DN80"  !CDS_PN = "DN80";
"UPI3_TX_DP12":   PN = "DA76"  !CDS_PN = "DA76";
"UPI3_TX_DP13":   PN = "CV77"  !CDS_PN = "CV77";
"UPI3_TX_DP14":   PN = "CR76"  !CDS_PN = "CR76";
"UPI3_TX_DP15":   PN = "CU74"  !CDS_PN = "CU74";
"UPI3_TX_DP16":   PN = "CM77"  !CDS_PN = "CM77";
"UPI3_TX_DP17":   PN = "CJ78"  !CDS_PN = "CJ78";
"UPI3_TX_DP18":   PN = "CL76"  !CDS_PN = "CL76";
"UPI3_TX_DP19":   PN = "CF77"  !CDS_PN = "CF77";
"UPI3_TX_DP20":   PN = "CH75"  !CDS_PN = "CH75";
"UPI3_TX_DP21":   PN = "CK75"  !CDS_PN = "CK75";
"UPI3_TX_DP22":   PN = "CW74"  !CDS_PN = "CW74";
"UPI3_TX_DP23":   PN = "CD73"  !CDS_PN = "CD73";
DRAWING = "@s9s_mb_2u_lib.s9s_mb_2u(sch_1):page67";
BODY = "SOCKET4677_AZIF0045P001C01CS","I1": LOCATION = "U1" #&CDS_LOCATION = "U1" &SEC = "26" #&CDS_SEC = "26";
"VCCIN190":   PN = "BW80"  !CDS_PN = "BW80";
"VCCIN191":   PN = "BW82"  !CDS_PN = "BW82";
"VCCIN192":   PN = "BW84"  !CDS_PN = "BW84";
"VCCIN193":   PN = "BW86"  !CDS_PN = "BW86";
"VCCIN194":   PN = "BW88"  !CDS_PN = "BW88";
"VCCIN195":   PN = "BW90"  !CDS_PN = "BW90";
"VCCIN196":   PN = "BY32"  !CDS_PN = "BY32";
"VCCIN197":   PN = "BY34"  !CDS_PN = "BY34";
"VCCIN198":   PN = "BY36"  !CDS_PN = "BY36";
"VCCIN199":   PN = "BY38"  !CDS_PN = "BY38";
"VCCIN200":   PN = "BY40"  !CDS_PN = "BY40";
"VCCIN201":   PN = "BY42"  !CDS_PN = "BY42";
"VCCIN202":   PN = "BY44"  !CDS_PN = "BY44";
"VCCIN203":   PN = "BY47"  !CDS_PN = "BY47";
"VCCIN204":   PN = "BY49"  !CDS_PN = "BY49";
"VCCIN205":   PN = "BY51"  !CDS_PN = "BY51";
"VCCIN206":   PN = "BY53"  !CDS_PN = "BY53";
"VCCIN207":   PN = "BY55"  !CDS_PN = "BY55";
"VCCIN208":   PN = "BY57"  !CDS_PN = "BY57";
"VCCIN209":   PN = "BY59"  !CDS_PN = "BY59";
"VCCIN210":   PN = "BY61"  !CDS_PN = "BY61";
"VCCIN211":   PN = "BY63"  !CDS_PN = "BY63";
"VCCIN212":   PN = "BY65"  !CDS_PN = "BY65";
"VCCIN213":   PN = "BY67"  !CDS_PN = "BY67";
"VCCIN214":   PN = "BY69"  !CDS_PN = "BY69";
"VCCIN215":   PN = "BY71"  !CDS_PN = "BY71";
"VCCIN216":   PN = "BY73"  !CDS_PN = "BY73";
"VCCIN217":   PN = "BY75"  !CDS_PN = "BY75";
"VCCIN218":   PN = "BY77"  !CDS_PN = "BY77";
"VCCIN219":   PN = "BY79"  !CDS_PN = "BY79";
"VCCIN220":   PN = "BY81"  !CDS_PN = "BY81";
"VCCIN221":   PN = "BY83"  !CDS_PN = "BY83";
"VCCIN222":   PN = "BY85"  !CDS_PN = "BY85";
"VCCIN223":   PN = "BY87"  !CDS_PN = "BY87";
"VCCIN224":   PN = "BY89"  !CDS_PN = "BY89";
"VCCIN225":   PN = "CA33"  !CDS_PN = "CA33";
"VCCIN226":   PN = "CA35"  !CDS_PN = "CA35";
"VCCIN227":   PN = "CA37"  !CDS_PN = "CA37";
"VCCIN228":   PN = "CA39"  !CDS_PN = "CA39";
"VCCIN229":   PN = "CA41"  !CDS_PN = "CA41";
"VCCIN230":   PN = "CA43"  !CDS_PN = "CA43";
"VCCIN231":   PN = "CA45"  !CDS_PN = "CA45";
"VCCIN232":   PN = "CA48"  !CDS_PN = "CA48";
"VCCIN233":   PN = "CA50"  !CDS_PN = "CA50";
"VCCIN234":   PN = "CA52"  !CDS_PN = "CA52";
"VCCIN235":   PN = "CA54"  !CDS_PN = "CA54";
"VCCIN236":   PN = "CA56"  !CDS_PN = "CA56";
"VCCIN237":   PN = "CA58"  !CDS_PN = "CA58";
"VCCIN238":   PN = "CA60"  !CDS_PN = "CA60";
"VCCIN239":   PN = "CA62"  !CDS_PN = "CA62";
"VCCIN240":   PN = "CA64"  !CDS_PN = "CA64";
"VCCIN241":   PN = "CA66"  !CDS_PN = "CA66";
"VCCIN242":   PN = "CA68"  !CDS_PN = "CA68";
"VCCIN243":   PN = "CA70"  !CDS_PN = "CA70";
"VCCIN244":   PN = "CA72"  !CDS_PN = "CA72";
"VCCIN245":   PN = "CA74"  !CDS_PN = "CA74";
"VCCIN246":   PN = "CA76"  !CDS_PN = "CA76";
"VCCIN247":   PN = "CA78"  !CDS_PN = "CA78";
"VCCIN248":   PN = "CA80"  !CDS_PN = "CA80";
"VCCIN249":   PN = "CA82"  !CDS_PN = "CA82";
"VCCIN250":   PN = "CA84"  !CDS_PN = "CA84";
"VCCIN251":   PN = "CA86"  !CDS_PN = "CA86";
"VCCIN252":   PN = "CA88"  !CDS_PN = "CA88";
"VCCIN253":   PN = "CA90"  !CDS_PN = "CA90";
"VCCIN254":   PN = "CB61"  !CDS_PN = "CB61";
"VCCIN255":   PN = "CB75"  !CDS_PN = "CB75";
"VCCIN256":   PN = "CB77"  !CDS_PN = "CB77";
"VCCIN257":   PN = "CC33"  !CDS_PN = "CC33";
"VCCIN258":   PN = "CC35"  !CDS_PN = "CC35";
"VCCIN259":   PN = "CC37"  !CDS_PN = "CC37";
"VCCIN260":   PN = "CC39"  !CDS_PN = "CC39";
"VCCIN261":   PN = "CC41"  !CDS_PN = "CC41";
"VCCIN262":   PN = "CC43"  !CDS_PN = "CC43";
"VCCIN263":   PN = "CC45"  !CDS_PN = "CC45";
"VCCIN264":   PN = "CC48"  !CDS_PN = "CC48";
"VCCIN265":   PN = "CC50"  !CDS_PN = "CC50";
"VCCIN266":   PN = "CC52"  !CDS_PN = "CC52";
"VCCIN267":   PN = "CC54"  !CDS_PN = "CC54";
"VCCIN268":   PN = "CC56"  !CDS_PN = "CC56";
"VCCIN269":   PN = "CC58"  !CDS_PN = "CC58";
"VCCIN270":   PN = "CC60"  !CDS_PN = "CC60";
"VCCIN271":   PN = "CC76"  !CDS_PN = "CC76";
"VCCIN272":   PN = "CC78"  !CDS_PN = "CC78";
"VCCIN273":   PN = "CC80"  !CDS_PN = "CC80";
"VCCIN274":   PN = "CC82"  !CDS_PN = "CC82";
"VCCIN275":   PN = "CC84"  !CDS_PN = "CC84";
"VCCIN276":   PN = "CC86"  !CDS_PN = "CC86";
"VCCIN277":   PN = "CC88"  !CDS_PN = "CC88";
"VCCIN278":   PN = "CC90"  !CDS_PN = "CC90";
"VCCIN279":   PN = "CD32"  !CDS_PN = "CD32";
"VCCIN280":   PN = "CD34"  !CDS_PN = "CD34";
"VCCIN281":   PN = "CD36"  !CDS_PN = "CD36";
"VCCIN282":   PN = "CD38"  !CDS_PN = "CD38";
"VCCIN283":   PN = "CD40"  !CDS_PN = "CD40";
"VCCIN284":   PN = "CD42"  !CDS_PN = "CD42";
"VCCIN285":   PN = "CD44"  !CDS_PN = "CD44";
"VCCIN286":   PN = "CD47"  !CDS_PN = "CD47";
"VCCIN287":   PN = "CD49"  !CDS_PN = "CD49";
"VCCIN288":   PN = "CD51"  !CDS_PN = "CD51";
"VCCIN289":   PN = "CD53"  !CDS_PN = "CD53";
"VCCIN290":   PN = "CD55"  !CDS_PN = "CD55";
"VCCIN291":   PN = "CD57"  !CDS_PN = "CD57";
"VCCIN292":   PN = "CD59"  !CDS_PN = "CD59";
"VCCIN293":   PN = "CD79"  !CDS_PN = "CD79";
"VCCIN294":   PN = "CD81"  !CDS_PN = "CD81";
"VCCIN295":   PN = "CD83"  !CDS_PN = "CD83";
"VCCIN296":   PN = "CD85"  !CDS_PN = "CD85";
"VCCIN297":   PN = "CD87"  !CDS_PN = "CD87";
"VCCIN298":   PN = "CD89"  !CDS_PN = "CD89";
"VCCIN299":   PN = "CE80"  !CDS_PN = "CE80";
"VCCIN300":   PN = "CE82"  !CDS_PN = "CE82";
"VCCIN301":   PN = "CE84"  !CDS_PN = "CE84";
"VCCIN302":   PN = "CE86"  !CDS_PN = "CE86";
"VCCIN303":   PN = "CE88"  !CDS_PN = "CE88";
"VCCIN304":   PN = "CE90"  !CDS_PN = "CE90";
"VCCIN305":   PN = "CF79"  !CDS_PN = "CF79";
"VCCIN306":   PN = "CF81"  !CDS_PN = "CF81";
"VCCIN307":   PN = "CF83"  !CDS_PN = "CF83";
"VCCIN308":   PN = "CF85"  !CDS_PN = "CF85";
"VCCIN309":   PN = "CF87"  !CDS_PN = "CF87";
"VCCIN310":   PN = "CF89"  !CDS_PN = "CF89";
"VCCIN311":   PN = "CF91"  !CDS_PN = "CF91";
"VCCIN312":   PN = "CG80"  !CDS_PN = "CG80";
"VCCIN313":   PN = "CG82"  !CDS_PN = "CG82";
"VCCIN314":   PN = "CG84"  !CDS_PN = "CG84";
"VCCIN315":   PN = "CG86"  !CDS_PN = "CG86";
"VCCIN316":   PN = "CG88"  !CDS_PN = "CG88";
"VCCIN317":   PN = "CG90"  !CDS_PN = "CG90";
"VCCIN318":   PN = "CH81"  !CDS_PN = "CH81";
"VCCIN319":   PN = "CH91"  !CDS_PN = "CH91";
"VCCIN320":   PN = "CJ82"  !CDS_PN = "CJ82";
"VCCIN321":   PN = "CJ84"  !CDS_PN = "CJ84";
"VCCIN322":   PN = "CJ86"  !CDS_PN = "CJ86";
"VCCIN323":   PN = "CJ88"  !CDS_PN = "CJ88";
"VCCIN324":   PN = "CJ90"  !CDS_PN = "CJ90";
"VCCIN325":   PN = "CK83"  !CDS_PN = "CK83";
"VCCIN326":   PN = "CK85"  !CDS_PN = "CK85";
"VCCIN327":   PN = "CK87"  !CDS_PN = "CK87";
"VCCIN328":   PN = "CK89"  !CDS_PN = "CK89";
"VCCIN329":   PN = "CK91"  !CDS_PN = "CK91";
"VCCIN330":   PN = "CL84"  !CDS_PN = "CL84";
"VCCIN331":   PN = "CL86"  !CDS_PN = "CL86";
"VCCIN332":   PN = "CL88"  !CDS_PN = "CL88";
"VCCIN333":   PN = "CL90"  !CDS_PN = "CL90";
"VCCIN334":   PN = "CM87"  !CDS_PN = "CM87";
"VCCIN335":   PN = "CM91"  !CDS_PN = "CM91";
"VCCIN336":   PN = "CN88"  !CDS_PN = "CN88";
"VCCIN337":   PN = "CN90"  !CDS_PN = "CN90";
"VCCIN338":   PN = "CP89"  !CDS_PN = "CP89";
"VCCIN339":   PN = "CM89"  !CDS_PN = "CM89";
BODY = "SOCKET4677_AZIF0045P001C01CS","I3": LOCATION = "U1" #&CDS_LOCATION = "U1" &SEC = "27" #&CDS_SEC = "27";
"VCCIN40":   PN = "BN43"  !CDS_PN = "BN43";
"VCCIN41":   PN = "BN45"  !CDS_PN = "BN45";
"VCCIN42":   PN = "BN48"  !CDS_PN = "BN48";
"VCCIN43":   PN = "BN50"  !CDS_PN = "BN50";
"VCCIN44":   PN = "BN52"  !CDS_PN = "BN52";
"VCCIN45":   PN = "BN54"  !CDS_PN = "BN54";
"VCCIN46":   PN = "BN56"  !CDS_PN = "BN56";
"VCCIN47":   PN = "BN58"  !CDS_PN = "BN58";
"VCCIN48":   PN = "BN60"  !CDS_PN = "BN60";
"VCCIN49":   PN = "BN78"  !CDS_PN = "BN78";
"VCCIN50":   PN = "BN80"  !CDS_PN = "BN80";
"VCCIN51":   PN = "BN82"  !CDS_PN = "BN82";
"VCCIN52":   PN = "BN84"  !CDS_PN = "BN84";
"VCCIN53":   PN = "BN86"  !CDS_PN = "BN86";
"VCCIN54":   PN = "BN88"  !CDS_PN = "BN88";
"VCCIN55":   PN = "BN90"  !CDS_PN = "BN90";
"VCCIN56":   PN = "BP32"  !CDS_PN = "BP32";
"VCCIN57":   PN = "BP34"  !CDS_PN = "BP34";
"VCCIN58":   PN = "BP36"  !CDS_PN = "BP36";
"VCCIN59":   PN = "BP38"  !CDS_PN = "BP38";
"VCCIN60":   PN = "BP40"  !CDS_PN = "BP40";
"VCCIN61":   PN = "BP42"  !CDS_PN = "BP42";
"VCCIN62":   PN = "BP44"  !CDS_PN = "BP44";
"VCCIN63":   PN = "BP47"  !CDS_PN = "BP47";
"VCCIN64":   PN = "BP49"  !CDS_PN = "BP49";
"VCCIN65":   PN = "BP51"  !CDS_PN = "BP51";
"VCCIN66":   PN = "BP53"  !CDS_PN = "BP53";
"VCCIN67":   PN = "BP55"  !CDS_PN = "BP55";
"VCCIN68":   PN = "BP57"  !CDS_PN = "BP57";
"VCCIN69":   PN = "BP59"  !CDS_PN = "BP59";
"VCCIN70":   PN = "BP61"  !CDS_PN = "BP61";
"VCCIN71":   PN = "BP79"  !CDS_PN = "BP79";
"VCCIN72":   PN = "BP81"  !CDS_PN = "BP81";
"VCCIN73":   PN = "BP83"  !CDS_PN = "BP83";
"VCCIN74":   PN = "BP85"  !CDS_PN = "BP85";
"VCCIN75":   PN = "BP87"  !CDS_PN = "BP87";
"VCCIN76":   PN = "BP89"  !CDS_PN = "BP89";
"VCCIN77":   PN = "BR60"  !CDS_PN = "BR60";
"VCCIN78":   PN = "BR62"  !CDS_PN = "BR62";
"VCCIN79":   PN = "BR78"  !CDS_PN = "BR78";
"VCCIN80":   PN = "BT32"  !CDS_PN = "BT32";
"VCCIN81":   PN = "BT34"  !CDS_PN = "BT34";
"VCCIN82":   PN = "BT36"  !CDS_PN = "BT36";
"VCCIN83":   PN = "BT38"  !CDS_PN = "BT38";
"VCCIN84":   PN = "BT40"  !CDS_PN = "BT40";
"VCCIN85":   PN = "BT42"  !CDS_PN = "BT42";
"VCCIN86":   PN = "BT44"  !CDS_PN = "BT44";
"VCCIN87":   PN = "BT47"  !CDS_PN = "BT47";
"VCCIN88":   PN = "BT49"  !CDS_PN = "BT49";
"VCCIN89":   PN = "BT51"  !CDS_PN = "BT51";
"VCCIN90":   PN = "BT53"  !CDS_PN = "BT53";
"VCCIN91":   PN = "BT55"  !CDS_PN = "BT55";
"VCCIN92":   PN = "BT57"  !CDS_PN = "BT57";
"VCCIN93":   PN = "BT59"  !CDS_PN = "BT59";
"VCCIN94":   PN = "BT61"  !CDS_PN = "BT61";
"VCCIN95":   PN = "BT63"  !CDS_PN = "BT63";
"VCCIN96":   PN = "BT65"  !CDS_PN = "BT65";
"VCCIN97":   PN = "BT67"  !CDS_PN = "BT67";
"VCCIN98":   PN = "BT69"  !CDS_PN = "BT69";
"VCCIN99":   PN = "BT71"  !CDS_PN = "BT71";
"VCCIN100":   PN = "BT73"  !CDS_PN = "BT73";
"VCCIN101":   PN = "BT75"  !CDS_PN = "BT75";
"VCCIN102":   PN = "BT77"  !CDS_PN = "BT77";
"VCCIN103":   PN = "BT79"  !CDS_PN = "BT79";
"VCCIN104":   PN = "BT81"  !CDS_PN = "BT81";
"VCCIN105":   PN = "BT83"  !CDS_PN = "BT83";
"VCCIN106":   PN = "BT85"  !CDS_PN = "BT85";
"VCCIN107":   PN = "BT87"  !CDS_PN = "BT87";
"VCCIN108":   PN = "BT89"  !CDS_PN = "BT89";
"VCCIN109":   PN = "BU33"  !CDS_PN = "BU33";
"VCCIN110":   PN = "BU35"  !CDS_PN = "BU35";
"VCCIN111":   PN = "BU37"  !CDS_PN = "BU37";
"VCCIN112":   PN = "BU39"  !CDS_PN = "BU39";
"VCCIN113":   PN = "BU41"  !CDS_PN = "BU41";
"VCCIN114":   PN = "BU43"  !CDS_PN = "BU43";
"VCCIN115":   PN = "BU45"  !CDS_PN = "BU45";
"VCCIN116":   PN = "BU48"  !CDS_PN = "BU48";
"VCCIN117":   PN = "BU50"  !CDS_PN = "BU50";
"VCCIN118":   PN = "BU52"  !CDS_PN = "BU52";
"VCCIN119":   PN = "BU54"  !CDS_PN = "BU54";
"VCCIN120":   PN = "BU56"  !CDS_PN = "BU56";
"VCCIN121":   PN = "BU58"  !CDS_PN = "BU58";
"VCCIN122":   PN = "BU60"  !CDS_PN = "BU60";
"VCCIN123":   PN = "BU62"  !CDS_PN = "BU62";
"VCCIN124":   PN = "BU64"  !CDS_PN = "BU64";
"VCCIN125":   PN = "BU66"  !CDS_PN = "BU66";
"VCCIN126":   PN = "BU68"  !CDS_PN = "BU68";
"VCCIN127":   PN = "BU70"  !CDS_PN = "BU70";
"VCCIN128":   PN = "BU72"  !CDS_PN = "BU72";
"VCCIN129":   PN = "BU74"  !CDS_PN = "BU74";
"VCCIN130":   PN = "BU76"  !CDS_PN = "BU76";
"VCCIN131":   PN = "BU78"  !CDS_PN = "BU78";
"VCCIN132":   PN = "BU80"  !CDS_PN = "BU80";
"VCCIN133":   PN = "BU82"  !CDS_PN = "BU82";
"VCCIN134":   PN = "BU84"  !CDS_PN = "BU84";
"VCCIN135":   PN = "BU86"  !CDS_PN = "BU86";
"VCCIN136":   PN = "BU88"  !CDS_PN = "BU88";
"VCCIN137":   PN = "BU90"  !CDS_PN = "BU90";
"VCCIN138":   PN = "BV32"  !CDS_PN = "BV32";
"VCCIN139":   PN = "BV34"  !CDS_PN = "BV34";
"VCCIN140":   PN = "BV36"  !CDS_PN = "BV36";
"VCCIN141":   PN = "BV38"  !CDS_PN = "BV38";
"VCCIN142":   PN = "BV40"  !CDS_PN = "BV40";
"VCCIN143":   PN = "BV42"  !CDS_PN = "BV42";
"VCCIN144":   PN = "BV44"  !CDS_PN = "BV44";
"VCCIN145":   PN = "BV47"  !CDS_PN = "BV47";
"VCCIN146":   PN = "BV49"  !CDS_PN = "BV49";
"VCCIN147":   PN = "BV51"  !CDS_PN = "BV51";
"VCCIN148":   PN = "BV53"  !CDS_PN = "BV53";
"VCCIN149":   PN = "BV55"  !CDS_PN = "BV55";
"VCCIN150":   PN = "BV57"  !CDS_PN = "BV57";
"VCCIN151":   PN = "BV59"  !CDS_PN = "BV59";
"VCCIN152":   PN = "BV61"  !CDS_PN = "BV61";
"VCCIN153":   PN = "BV63"  !CDS_PN = "BV63";
"VCCIN154":   PN = "BV65"  !CDS_PN = "BV65";
"VCCIN155":   PN = "BV67"  !CDS_PN = "BV67";
"VCCIN156":   PN = "BV69"  !CDS_PN = "BV69";
"VCCIN157":   PN = "BV71"  !CDS_PN = "BV71";
"VCCIN158":   PN = "BV73"  !CDS_PN = "BV73";
"VCCIN159":   PN = "BV75"  !CDS_PN = "BV75";
"VCCIN160":   PN = "BV77"  !CDS_PN = "BV77";
"VCCIN161":   PN = "BV79"  !CDS_PN = "BV79";
"VCCIN162":   PN = "BV81"  !CDS_PN = "BV81";
"VCCIN163":   PN = "BV83"  !CDS_PN = "BV83";
"VCCIN164":   PN = "BV85"  !CDS_PN = "BV85";
"VCCIN165":   PN = "BV87"  !CDS_PN = "BV87";
"VCCIN166":   PN = "BV89"  !CDS_PN = "BV89";
"VCCIN167":   PN = "BW33"  !CDS_PN = "BW33";
"VCCIN168":   PN = "BW35"  !CDS_PN = "BW35";
"VCCIN169":   PN = "BW37"  !CDS_PN = "BW37";
"VCCIN170":   PN = "BW39"  !CDS_PN = "BW39";
"VCCIN171":   PN = "BW41"  !CDS_PN = "BW41";
"VCCIN172":   PN = "BW43"  !CDS_PN = "BW43";
"VCCIN173":   PN = "BW45"  !CDS_PN = "BW45";
"VCCIN174":   PN = "BW48"  !CDS_PN = "BW48";
"VCCIN175":   PN = "BW50"  !CDS_PN = "BW50";
"VCCIN176":   PN = "BW52"  !CDS_PN = "BW52";
"VCCIN177":   PN = "BW54"  !CDS_PN = "BW54";
"VCCIN178":   PN = "BW56"  !CDS_PN = "BW56";
"VCCIN179":   PN = "BW58"  !CDS_PN = "BW58";
"VCCIN180":   PN = "BW60"  !CDS_PN = "BW60";
"VCCIN181":   PN = "BW62"  !CDS_PN = "BW62";
"VCCIN182":   PN = "BW64"  !CDS_PN = "BW64";
"VCCIN183":   PN = "BW66"  !CDS_PN = "BW66";
"VCCIN184":   PN = "BW68"  !CDS_PN = "BW68";
"VCCIN185":   PN = "BW70"  !CDS_PN = "BW70";
"VCCIN186":   PN = "BW72"  !CDS_PN = "BW72";
"VCCIN187":   PN = "BW74"  !CDS_PN = "BW74";
"VCCIN188":   PN = "BW76"  !CDS_PN = "BW76";
"VCCIN189":   PN = "BW78"  !CDS_PN = "BW78";
DRAWING = "@s9s_mb_2u_lib.s9s_mb_2u(sch_1):page68";
BODY = "SOCKET4677_AZIF0045P001C01CS","I1": LOCATION = "U1" #&CDS_LOCATION = "U1" &SEC = "28" #&CDS_SEC = "28";
"VCCIN0":   PN = "BD91"  !CDS_PN = "BD91";
"VCCIN1":   PN = "BE86"  !CDS_PN = "BE86";
"VCCIN2":   PN = "BE88"  !CDS_PN = "BE88";
"VCCIN3":   PN = "BE90"  !CDS_PN = "BE90";
"VCCIN4":   PN = "BF85"  !CDS_PN = "BF85";
"VCCIN5":   PN = "BF87"  !CDS_PN = "BF87";
"VCCIN6":   PN = "BF89"  !CDS_PN = "BF89";
"VCCIN7":   PN = "BF91"  !CDS_PN = "BF91";
"VCCIN8":   PN = "BG84"  !CDS_PN = "BG84";
"VCCIN9":   PN = "BG86"  !CDS_PN = "BG86";
"VCCIN10":   PN = "BG88"  !CDS_PN = "BG88";
"VCCIN11":   PN = "BG90"  !CDS_PN = "BG90";
"VCCIN12":   PN = "BH85"  !CDS_PN = "BH85";
"VCCIN13":   PN = "BH87"  !CDS_PN = "BH87";
"VCCIN14":   PN = "BH89"  !CDS_PN = "BH89";
"VCCIN15":   PN = "BH91"  !CDS_PN = "BH91";
"VCCIN16":   PN = "BK81"  !CDS_PN = "BK81";
"VCCIN17":   PN = "BK83"  !CDS_PN = "BK83";
"VCCIN18":   PN = "BK85"  !CDS_PN = "BK85";
"VCCIN19":   PN = "BK87"  !CDS_PN = "BK87";
"VCCIN20":   PN = "BK89"  !CDS_PN = "BK89";
"VCCIN21":   PN = "BK91"  !CDS_PN = "BK91";
"VCCIN22":   PN = "BL80"  !CDS_PN = "BL80";
"VCCIN23":   PN = "BL82"  !CDS_PN = "BL82";
"VCCIN24":   PN = "BL84"  !CDS_PN = "BL84";
"VCCIN25":   PN = "BL86"  !CDS_PN = "BL86";
"VCCIN26":   PN = "BL88"  !CDS_PN = "BL88";
"VCCIN27":   PN = "BL90"  !CDS_PN = "BL90";
"VCCIN28":   PN = "BM79"  !CDS_PN = "BM79";
"VCCIN29":   PN = "BM81"  !CDS_PN = "BM81";
"VCCIN30":   PN = "BM83"  !CDS_PN = "BM83";
"VCCIN31":   PN = "BM85"  !CDS_PN = "BM85";
"VCCIN32":   PN = "BM87"  !CDS_PN = "BM87";
"VCCIN33":   PN = "BM89"  !CDS_PN = "BM89";
"VCCIN34":   PN = "BM91"  !CDS_PN = "BM91";
"VCCIN35":   PN = "BN33"  !CDS_PN = "BN33";
"VCCIN36":   PN = "BN35"  !CDS_PN = "BN35";
"VCCIN37":   PN = "BN37"  !CDS_PN = "BN37";
"VCCIN38":   PN = "BN39"  !CDS_PN = "BN39";
"VCCIN39":   PN = "BN41"  !CDS_PN = "BN41";
"VCCINFAON33":   PN = "AY18"  !CDS_PN = "AY18";
"VCCINFAON34":   PN = "BA15"  !CDS_PN = "BA15";
"VCCINFAON35":   PN = "BC60"  !CDS_PN = "BC60";
"VCCINFAON36":   PN = "BE15"  !CDS_PN = "BE15";
"VCCINFAON37":   PN = "BE60"  !CDS_PN = "BE60";
"VCCINFAON38":   PN = "BG60"  !CDS_PN = "BG60";
"VCCINFAON39":   PN = "BJ15"  !CDS_PN = "BJ15";
"VCCINFAON40":   PN = "BJ60"  !CDS_PN = "BJ60";
"VCCINFAON41":   PN = "BK61"  !CDS_PN = "BK61";
"VCCINFAON42":   PN = "BN15"  !CDS_PN = "BN15";
"VCCINFAON43":   PN = "CA15"  !CDS_PN = "CA15";
"VCCINFAON44":   PN = "CE19"  !CDS_PN = "CE19";
"VCCINFAON45":   PN = "CJ11"  !CDS_PN = "CJ11";
"VCCINFAON46":   PN = "CJ19"  !CDS_PN = "CJ19";
"VCCINFAON47":   PN = "CN19"  !CDS_PN = "CN19";
"VCCINFAON48":   PN = "CP63"  !CDS_PN = "CP63";
"VCCINFAON49":   PN = "CT63"  !CDS_PN = "CT63";
"VCCINFAON50":   PN = "CV61"  !CDS_PN = "CV61";
"VCCINFAON51":   PN = "CV63"  !CDS_PN = "CV63";
"VCCINFAON52":   PN = "CW62"  !CDS_PN = "CW62";
"VCCINFAON53":   PN = "DA21"  !CDS_PN = "DA21";
BODY = "Q_CAP","I4": LOCATION = "C71" #&CDS_LOCATION = "C71" &SEC = "1" #&CDS_SEC = "1";
"A":   PN = "1"  !CDS_PN = "1";
"B":   PN = "2"  !CDS_PN = "2";
BODY = "SOCKET4677_AZIF0045P001C01CS","I8": LOCATION = "U1" #&CDS_LOCATION = "U1" &SEC = "29" #&CDS_SEC = "29";
"VCCD_HV0":   PN = "AT36"  !CDS_PN = "AT36";
"VCCD_HV1":   PN = "AT55"  !CDS_PN = "AT55";
"VCCD_HV2":   PN = "AU3"  !CDS_PN = "AU3";
"VCCD_HV3":   PN = "AU35"  !CDS_PN = "AU35";
"VCCD_HV4":   PN = "AU54"  !CDS_PN = "AU54";
"VCCD_HV5":   PN = "AU7"  !CDS_PN = "AU7";
"VCCD_HV6":   PN = "AV34"  !CDS_PN = "AV34";
"VCCD_HV7":   PN = "AV36"  !CDS_PN = "AV36";
"VCCD_HV8":   PN = "AV53"  !CDS_PN = "AV53";
"VCCD_HV9":   PN = "AV55"  !CDS_PN = "AV55";
"VCCD_HV10":   PN = "BA3"  !CDS_PN = "BA3";
"VCCD_HV11":   PN = "BA7"  !CDS_PN = "BA7";
"VCCD_HV12":   PN = "BE11"  !CDS_PN = "BE11";
"VCCD_HV13":   PN = "BE3"  !CDS_PN = "BE3";
"VCCD_HV14":   PN = "BE7"  !CDS_PN = "BE7";
"VCCD_HV15":   PN = "BJ11"  !CDS_PN = "BJ11";
"VCCD_HV16":   PN = "BJ3"  !CDS_PN = "BJ3";
"VCCD_HV17":   PN = "BJ7"  !CDS_PN = "BJ7";
"VCCD_HV18":   PN = "BN7"  !CDS_PN = "BN7";
"VCCD_HV19":   PN = "CA7"  !CDS_PN = "CA7";
"VCCD_HV20":   PN = "CE7"  !CDS_PN = "CE7";
"VCCD_HV21":   PN = "CW35"  !CDS_PN = "CW35";
"VCCD_HV22":   PN = "CW37"  !CDS_PN = "CW37";
"VCCD_HV23":   PN = "CW52"  !CDS_PN = "CW52";
"VCCD_HV24":   PN = "CW54"  !CDS_PN = "CW54";
"VCCD_HV25":   PN = "CW56"  !CDS_PN = "CW56";
"VCCD_HV26":   PN = "CY34"  !CDS_PN = "CY34";
"VCCD_HV27":   PN = "CY36"  !CDS_PN = "CY36";
"VCCD_HV28":   PN = "CY53"  !CDS_PN = "CY53";
"VCCFA_EHV0":   PN = "AA3"  !CDS_PN = "AA3";
"VCCFA_EHV1":   PN = "AE3"  !CDS_PN = "AE3";
"VCCFA_EHV2":   PN = "AJ3"  !CDS_PN = "AJ3";
"VCCFA_EHV3":   PN = "AN3"  !CDS_PN = "AN3";
"VCCFA_EHV4":   PN = "AT61"  !CDS_PN = "AT61";
"VCCFA_EHV5":   PN = "AU60"  !CDS_PN = "AU60";
"VCCFA_EHV6":   PN = "AV61"  !CDS_PN = "AV61";
"VCCFA_EHV7":   PN = "AW60"  !CDS_PN = "AW60";
"VCCFA_EHV8":   PN = "N3"  !CDS_PN = "N3";
"VCCFA_EHV9":   PN = "U3"  !CDS_PN = "U3";
"VCCINFAON0":   PN = "CE15"  !CDS_PN = "CE15";
"VCCINFAON1":   PN = "CJ15"  !CDS_PN = "CJ15";
"VCCINFAON2":   PN = "CJ3"  !CDS_PN = "CJ3";
"VCCINFAON3":   PN = "CJ7"  !CDS_PN = "CJ7";
"VCCINFAON4":   PN = "CN11"  !CDS_PN = "CN11";
"VCCINFAON5":   PN = "CN15"  !CDS_PN = "CN15";
"VCCINFAON6":   PN = "CN3"  !CDS_PN = "CN3";
"VCCINFAON7":   PN = "CN64"  !CDS_PN = "CN64";
"VCCINFAON8":   PN = "CN66"  !CDS_PN = "CN66";
"VCCINFAON9":   PN = "CN7"  !CDS_PN = "CN7";
"VCCINFAON10":   PN = "CP65"  !CDS_PN = "CP65";
"VCCINFAON11":   PN = "CP67"  !CDS_PN = "CP67";
"VCCINFAON12":   PN = "CT65"  !CDS_PN = "CT65";
"VCCINFAON13":   PN = "CT67"  !CDS_PN = "CT67";
"VCCINFAON14":   PN = "CU11"  !CDS_PN = "CU11";
"VCCINFAON15":   PN = "CU15"  !CDS_PN = "CU15";
"VCCINFAON16":   PN = "CU3"  !CDS_PN = "CU3";
"VCCINFAON17":   PN = "CU64"  !CDS_PN = "CU64";
"VCCINFAON18":   PN = "CU7"  !CDS_PN = "CU7";
"VCCINFAON19":   PN = "CV65"  !CDS_PN = "CV65";
"VCCINFAON20":   PN = "CV67"  !CDS_PN = "CV67";
"VCCINFAON21":   PN = "CW66"  !CDS_PN = "CW66";
"VCCINFAON22":   PN = "CY65"  !CDS_PN = "CY65";
"VCCINFAON23":   PN = "CY67"  !CDS_PN = "CY67";
"VCCINFAON24":   PN = "DA11"  !CDS_PN = "DA11";
"VCCINFAON25":   PN = "DA15"  !CDS_PN = "DA15";
"VCCINFAON26":   PN = "DA64"  !CDS_PN = "DA64";
"VCCINFAON27":   PN = "DE11"  !CDS_PN = "DE11";
"VCCINFAON28":   PN = "DE15"  !CDS_PN = "DE15";
"VCCINFAON29":   PN = "DE3"  !CDS_PN = "DE3";
"VCCINFAON30":   PN = "DJ15"  !CDS_PN = "DJ15";
"VCCINFAON31":   PN = "DJ3"  !CDS_PN = "DJ3";
"VCCINFAON32":   PN = "DJ7"  !CDS_PN = "DJ7";
"VCCINFAON54":   PN = "CR66"  !CDS_PN = "CR66";
"VCCINFAON55":   PN = "CW64"  !CDS_PN = "CW64";
"VCCINFAON56":   PN = "DA3"  !CDS_PN = "DA3";
"VCCINFAON57":   PN = "DA7"  !CDS_PN = "DA7";
"VCCINFAON58":   PN = "DE7"  !CDS_PN = "DE7";
"VCCINFAON59":   PN = "DJ11"  !CDS_PN = "DJ11";
"VCCVNN0":   PN = "BA19"  !CDS_PN = "BA19";
"VCCVNN1":   PN = "BE19"  !CDS_PN = "BE19";
"VCCVNN2":   PN = "BJ19"  !CDS_PN = "BJ19";
"VCCVNN3":   PN = "BN19"  !CDS_PN = "BN19";
"VPP_HBM1":   PN = "CF67"  !CDS_PN = "CF67";
"VPP_HBM2":   PN = "CE68"  !CDS_PN = "CE68";
"VPP_HBM3":   PN = "CD67"  !CDS_PN = "CD67";
"VPP_HBM4":   PN = "CC68"  !CDS_PN = "CC68";
"VCC_3P3_AUX0":   PN = "BC21"  !CDS_PN = "BC21";
"VCC_3P3_AUX1":   PN = "BA21"  !CDS_PN = "BA21";
"VPP_HBM":   PN = "CG68"  !CDS_PN = "CG68";
DRAWING = "@s9s_mb_2u_lib.s9s_mb_2u(sch_1):page69";
BODY = "SOCKET4677_AZIF0045P001C01CS","I1": LOCATION = "U1" #&CDS_LOCATION = "U1" &SEC = "30" #&CDS_SEC = "30";
"VCCFA_EHV_FIVRA0":   PN = "AA11"  !CDS_PN = "AA11";
"VCCFA_EHV_FIVRA1":   PN = "AA15"  !CDS_PN = "AA15";
"VCCFA_EHV_FIVRA2":   PN = "AA7"  !CDS_PN = "AA7";
"VCCFA_EHV_FIVRA3":   PN = "AD85"  !CDS_PN = "AD85";
"VCCFA_EHV_FIVRA4":   PN = "AD89"  !CDS_PN = "AD89";
"VCCFA_EHV_FIVRA5":   PN = "AE11"  !CDS_PN = "AE11";
"VCCFA_EHV_FIVRA6":   PN = "AE15"  !CDS_PN = "AE15";
"VCCFA_EHV_FIVRA7":   PN = "AE7"  !CDS_PN = "AE7";
"VCCFA_EHV_FIVRA8":   PN = "AF77"  !CDS_PN = "AF77";
"VCCFA_EHV_FIVRA9":   PN = "AG78"  !CDS_PN = "AG78";
"VCCFA_EHV_FIVRA10":   PN = "AH85"  !CDS_PN = "AH85";
"VCCFA_EHV_FIVRA11":   PN = "AH89"  !CDS_PN = "AH89";
"VCCFA_EHV_FIVRA12":   PN = "AJ11"  !CDS_PN = "AJ11";
"VCCFA_EHV_FIVRA13":   PN = "AJ15"  !CDS_PN = "AJ15";
"VCCFA_EHV_FIVRA14":   PN = "AJ7"  !CDS_PN = "AJ7";
"VCCFA_EHV_FIVRA15":   PN = "AM79"  !CDS_PN = "AM79";
"VCCFA_EHV_FIVRA16":   PN = "AM85"  !CDS_PN = "AM85";
"VCCFA_EHV_FIVRA17":   PN = "AM89"  !CDS_PN = "AM89";
"VCCFA_EHV_FIVRA18":   PN = "AN11"  !CDS_PN = "AN11";
"VCCFA_EHV_FIVRA19":   PN = "AN15"  !CDS_PN = "AN15";
"VCCFA_EHV_FIVRA20":   PN = "AN7"  !CDS_PN = "AN7";
"VCCFA_EHV_FIVRA21":   PN = "AN80"  !CDS_PN = "AN80";
"VCCFA_EHV_FIVRA22":   PN = "AT73"  !CDS_PN = "AT73";
"VCCFA_EHV_FIVRA23":   PN = "AT89"  !CDS_PN = "AT89";
"VCCFA_EHV_FIVRA24":   PN = "AU15"  !CDS_PN = "AU15";
"VCCFA_EHV_FIVRA25":   PN = "AW76"  !CDS_PN = "AW76";
"VCCFA_EHV_FIVRA26":   PN = "AY89"  !CDS_PN = "AY89";
"VCCFA_EHV_FIVRA27":   PN = "BE72"  !CDS_PN = "BE72";
"VCCFA_EHV_FIVRA28":   PN = "BF77"  !CDS_PN = "BF77";
"VCCFA_EHV_FIVRA29":   PN = "BH79"  !CDS_PN = "BH79";
"VCCFA_EHV_FIVRA30":   PN = "BJ72"  !CDS_PN = "BJ72";
"VCCFA_EHV_FIVRA31":   PN = "BJ78"  !CDS_PN = "BJ78";
"VCCFA_EHV_FIVRA32":   PN = "C84"  !CDS_PN = "C84";
"VCCFA_EHV_FIVRA33":   PN = "C88"  !CDS_PN = "C88";
"VCCFA_EHV_FIVRA34":   PN = "CE74"  !CDS_PN = "CE74";
"VCCFA_EHV_FIVRA35":   PN = "CK73"  !CDS_PN = "CK73";
"VCCFA_EHV_FIVRA36":   PN = "CK79"  !CDS_PN = "CK79";
"VCCFA_EHV_FIVRA37":   PN = "CM73"  !CDS_PN = "CM73";
"VCCFA_EHV_FIVRA38":   PN = "CN78"  !CDS_PN = "CN78";
"VCCFA_EHV_FIVRA39":   PN = "CP73"  !CDS_PN = "CP73";
"VCCFA_EHV_FIVRA40":   PN = "CT77"  !CDS_PN = "CT77";
"VCCFA_EHV_FIVRA41":   PN = "CT85"  !CDS_PN = "CT85";
"VCCFA_EHV_FIVRA42":   PN = "CY75"  !CDS_PN = "CY75";
"VCCFA_EHV_FIVRA43":   PN = "CY79"  !CDS_PN = "CY79";
"VCCFA_EHV_FIVRA44":   PN = "CY85"  !CDS_PN = "CY85";
"VCCFA_EHV_FIVRA45":   PN = "CY89"  !CDS_PN = "CY89";
"VCCFA_EHV_FIVRA46":   PN = "DD77"  !CDS_PN = "DD77";
"VCCFA_EHV_FIVRA47":   PN = "DD83"  !CDS_PN = "DD83";
"VCCFA_EHV_FIVRA48":   PN = "DD85"  !CDS_PN = "DD85";
"VCCFA_EHV_FIVRA49":   PN = "DD89"  !CDS_PN = "DD89";
"VCCFA_EHV_FIVRA50":   PN = "DH89"  !CDS_PN = "DH89";
"VCCFA_EHV_FIVRA51":   PN = "DM83"  !CDS_PN = "DM83";
"VCCFA_EHV_FIVRA52":   PN = "DM85"  !CDS_PN = "DM85";
"VCCFA_EHV_FIVRA53":   PN = "DM89"  !CDS_PN = "DM89";
"VCCFA_EHV_FIVRA54":   PN = "DN11"  !CDS_PN = "DN11";
"VCCFA_EHV_FIVRA55":   PN = "DN15"  !CDS_PN = "DN15";
"VCCFA_EHV_FIVRA56":   PN = "DN3"  !CDS_PN = "DN3";
"VCCFA_EHV_FIVRA57":   PN = "DN7"  !CDS_PN = "DN7";
"VCCFA_EHV_FIVRA58":   PN = "DT79"  !CDS_PN = "DT79";
"VCCFA_EHV_FIVRA59":   PN = "DT85"  !CDS_PN = "DT85";
"VCCFA_EHV_FIVRA60":   PN = "DT89"  !CDS_PN = "DT89";
"VCCFA_EHV_FIVRA61":   PN = "DU11"  !CDS_PN = "DU11";
"VCCFA_EHV_FIVRA62":   PN = "DU15"  !CDS_PN = "DU15";
"VCCFA_EHV_FIVRA63":   PN = "DU3"  !CDS_PN = "DU3";
"VCCFA_EHV_FIVRA64":   PN = "DU7"  !CDS_PN = "DU7";
"VCCFA_EHV_FIVRA65":   PN = "DY85"  !CDS_PN = "DY85";
"VCCFA_EHV_FIVRA66":   PN = "DY89"  !CDS_PN = "DY89";
"VCCFA_EHV_FIVRA67":   PN = "EA11"  !CDS_PN = "EA11";
"VCCFA_EHV_FIVRA68":   PN = "EA15"  !CDS_PN = "EA15";
"VCCFA_EHV_FIVRA69":   PN = "EA3"  !CDS_PN = "EA3";
"VCCFA_EHV_FIVRA70":   PN = "EA7"  !CDS_PN = "EA7";
"VCCFA_EHV_FIVRA71":   PN = "EC78"  !CDS_PN = "EC78";
"VCCFA_EHV_FIVRA72":   PN = "ED79"  !CDS_PN = "ED79";
"VCCFA_EHV_FIVRA73":   PN = "ED85"  !CDS_PN = "ED85";
"VCCFA_EHV_FIVRA74":   PN = "ED89"  !CDS_PN = "ED89";
"VCCFA_EHV_FIVRA75":   PN = "EE11"  !CDS_PN = "EE11";
"VCCFA_EHV_FIVRA76":   PN = "EE15"  !CDS_PN = "EE15";
"VCCFA_EHV_FIVRA77":   PN = "EE7"  !CDS_PN = "EE7";
"VCCFA_EHV_FIVRA78":   PN = "EE84"  !CDS_PN = "EE84";
"VCCFA_EHV_FIVRA79":   PN = "EF79"  !CDS_PN = "EF79";
"VCCFA_EHV_FIVRA80":   PN = "EG80"  !CDS_PN = "EG80";
"VCCFA_EHV_FIVRA81":   PN = "EJ15"  !CDS_PN = "EJ15";
"VCCFA_EHV_FIVRA82":   PN = "EJ84"  !CDS_PN = "EJ84";
"VCCFA_EHV_FIVRA83":   PN = "EN84"  !CDS_PN = "EN84";
"VCCFA_EHV_FIVRA84":   PN = "H89"  !CDS_PN = "H89";
"VCCFA_EHV_FIVRA85":   PN = "J11"  !CDS_PN = "J11";
"VCCFA_EHV_FIVRA86":   PN = "J7"  !CDS_PN = "J7";
"VCCFA_EHV_FIVRA87":   PN = "J80"  !CDS_PN = "J80";
"VCCFA_EHV_FIVRA88":   PN = "K87"  !CDS_PN = "K87";
"VCCFA_EHV_FIVRA89":   PN = "L84"  !CDS_PN = "L84";
"VCCFA_EHV_FIVRA90":   PN = "M85"  !CDS_PN = "M85";
"VCCFA_EHV_FIVRA91":   PN = "M89"  !CDS_PN = "M89";
"VCCFA_EHV_FIVRA92":   PN = "N11"  !CDS_PN = "N11";
"VCCFA_EHV_FIVRA93":   PN = "N7"  !CDS_PN = "N7";
"VCCFA_EHV_FIVRA94":   PN = "P79"  !CDS_PN = "P79";
"VCCFA_EHV_FIVRA95":   PN = "R80"  !CDS_PN = "R80";
"VCCFA_EHV_FIVRA96":   PN = "T85"  !CDS_PN = "T85";
"VCCFA_EHV_FIVRA97":   PN = "T89"  !CDS_PN = "T89";
"VCCFA_EHV_FIVRA98":   PN = "U11"  !CDS_PN = "U11";
"VCCFA_EHV_FIVRA99":   PN = "U15"  !CDS_PN = "U15";
"VCCFA_EHV_FIVRA100":   PN = "U7"  !CDS_PN = "U7";
"VCCFA_EHV_FIVRA101":   PN = "W80"  !CDS_PN = "W80";
"VCCFA_EHV_FIVRA102":   PN = "Y79"  !CDS_PN = "Y79";
"VCCFA_EHV_FIVRA103":   PN = "Y85"  !CDS_PN = "Y85";
"VCCFA_EHV_FIVRA104":   PN = "Y89"  !CDS_PN = "Y89";
DRAWING = "@s9s_mb_2u_lib.s9s_mb_2u(sch_1):page70";
BODY = "SOCKET4677_AZIF0045P001C01CS","I2": LOCATION = "U1" #&CDS_LOCATION = "U1" &SEC = "31" #&CDS_SEC = "31";
"VSS1312":   PN = "EH42"  !CDS_PN = "EH42";
"VSS1315":   PN = "EH55"  !CDS_PN = "EH55";
"VSS1319":   PN = "EH61"  !CDS_PN = "EH61";
"VSS1320":   PN = "EH67"  !CDS_PN = "EH67";
"VSS1322":   PN = "EH79"  !CDS_PN = "EH79";
"VSS1325":   PN = "EJ11"  !CDS_PN = "EJ11";
"VSS1328":   PN = "EJ17"  !CDS_PN = "EJ17";
"VSS1331":   PN = "EJ25"  !CDS_PN = "EJ25";
"VSS1334":   PN = "EJ35"  !CDS_PN = "EJ35";
"VSS1340":   PN = "EJ54"  !CDS_PN = "EJ54";
"VSS1343":   PN = "EJ62"  !CDS_PN = "EJ62";
"VSS1345":   PN = "EJ68"  !CDS_PN = "EJ68";
"VSS1347":   PN = "EJ72"  !CDS_PN = "EJ72";
"VSS1355":   PN = "EK16"  !CDS_PN = "EK16";
"VSS1357":   PN = "EK20"  !CDS_PN = "EK20";
"VSS1359":   PN = "EK26"  !CDS_PN = "EK26";
"VSS1366":   PN = "EK44"  !CDS_PN = "EK44";
"VSS1368":   PN = "EK51"  !CDS_PN = "EK51";
"VSS1369":   PN = "EK53"  !CDS_PN = "EK53";
"VSS1371":   PN = "EK59"  !CDS_PN = "EK59";
"VSS1372":   PN = "EK63"  !CDS_PN = "EK63";
"VSS1375":   PN = "EK71"  !CDS_PN = "EK71";
"VSS1377":   PN = "EK77"  !CDS_PN = "EK77";
"VSS1378":   PN = "EK79"  !CDS_PN = "EK79";
"VSS1379":   PN = "EK83"  !CDS_PN = "EK83";
"VSS1380":   PN = "EK89"  !CDS_PN = "EK89";
"VSS1381":   PN = "EL15"  !CDS_PN = "EL15";
"VSS1391":   PN = "EL52"  !CDS_PN = "EL52";
"VSS1394":   PN = "EL58"  !CDS_PN = "EL58";
"VSS1396":   PN = "EL7"  !CDS_PN = "EL7";
"VSS1397":   PN = "EL70"  !CDS_PN = "EL70";
"VSS1398":   PN = "EL72"  !CDS_PN = "EL72";
"VSS1400":   PN = "EL86"  !CDS_PN = "EL86";
"VSS1401":   PN = "EL9"  !CDS_PN = "EL9";
"VSS1405":   PN = "EM49"  !CDS_PN = "EM49";
"VSS1409":   PN = "EM79"  !CDS_PN = "EM79";
"VSS1419":   PN = "EH36"  !CDS_PN = "EH36";
"VSS1421":   PN = "EH49"  !CDS_PN = "EH49";
"VSS1422":   PN = "EH73"  !CDS_PN = "EH73";
"VSS1423":   PN = "EH81"  !CDS_PN = "EH81";
"VSS1424":   PN = "EH83"  !CDS_PN = "EH83";
"VSS1425":   PN = "EJ13"  !CDS_PN = "EJ13";
"VSS1426":   PN = "EJ19"  !CDS_PN = "EJ19";
"VSS1427":   PN = "EN39"  !CDS_PN = "EN39";
"VSS1428":   PN = "EJ23"  !CDS_PN = "EJ23";
"VSS1429":   PN = "EJ29"  !CDS_PN = "EJ29";
"VSS1430":   PN = "EJ31"  !CDS_PN = "EJ31";
"VSS1431":   PN = "EJ37"  !CDS_PN = "EJ37";
"VSS1432":   PN = "EJ41"  !CDS_PN = "EJ41";
"VSS1433":   PN = "EJ43"  !CDS_PN = "EJ43";
"VSS1434":   PN = "EJ48"  !CDS_PN = "EJ48";
"VSS1435":   PN = "EJ50"  !CDS_PN = "EJ50";
"VSS1436":   PN = "EN58"  !CDS_PN = "EN58";
"VSS1437":   PN = "EN60"  !CDS_PN = "EN60";
"VSS1438":   PN = "EN62"  !CDS_PN = "EN62";
"VSS1439":   PN = "EJ56"  !CDS_PN = "EJ56";
"VSS1440":   PN = "EN66"  !CDS_PN = "EN66";
"VSS1441":   PN = "EN72"  !CDS_PN = "EN72";
"VSS1442":   PN = "EJ60"  !CDS_PN = "EJ60";
"VSS1443":   PN = "EJ66"  !CDS_PN = "EJ66";
"VSS1444":   PN = "EJ7"  !CDS_PN = "EJ7";
"VSS1445":   PN = "EN88"  !CDS_PN = "EN88";
"VSS1446":   PN = "EN9"  !CDS_PN = "EN9";
"VSS1447":   PN = "EJ74"  !CDS_PN = "EJ74";
"VSS1448":   PN = "EJ78"  !CDS_PN = "EJ78";
"VSS1449":   PN = "EJ88"  !CDS_PN = "EJ88";
"VSS1450":   PN = "EJ9"  !CDS_PN = "EJ9";
"VSS1451":   PN = "EK10"  !CDS_PN = "EK10";
"VSS1452":   PN = "EP69"  !CDS_PN = "EP69";
"VSS1453":   PN = "EP71"  !CDS_PN = "EP71";
"VSS1454":   PN = "EP77"  !CDS_PN = "EP77";
"VSS1455":   PN = "EK14"  !CDS_PN = "EK14";
"VSS1456":   PN = "ER15"  !CDS_PN = "ER15";
"VSS1457":   PN = "ER21"  !CDS_PN = "ER21";
"VSS1458":   PN = "EK2"  !CDS_PN = "EK2";
"VSS1459":   PN = "EK22"  !CDS_PN = "EK22";
"VSS1460":   PN = "EK28"  !CDS_PN = "EK28";
"VSS1461":   PN = "EK32"  !CDS_PN = "EK32";
"VSS1462":   PN = "ER39"  !CDS_PN = "ER39";
"VSS1463":   PN = "EK34"  !CDS_PN = "EK34";
"VSS1464":   PN = "ER52"  !CDS_PN = "ER52";
"VSS1465":   PN = "EK38"  !CDS_PN = "EK38";
"VSS1466":   PN = "EK4"  !CDS_PN = "EK4";
"VSS1467":   PN = "ER58"  !CDS_PN = "ER58";
"VSS1468":   PN = "ER64"  !CDS_PN = "ER64";
"VSS1469":   PN = "EK40"  !CDS_PN = "EK40";
"VSS1470":   PN = "EK47"  !CDS_PN = "EK47";
"VSS1471":   PN = "EK57"  !CDS_PN = "EK57";
"VSS1472":   PN = "EK65"  !CDS_PN = "EK65";
"VSS1473":   PN = "EK69"  !CDS_PN = "EK69";
"VSS1474":   PN = "EK75"  !CDS_PN = "EK75";
"VSS1475":   PN = "EL21"  !CDS_PN = "EL21";
"VSS1476":   PN = "ER9"  !CDS_PN = "ER9";
"VSS1477":   PN = "EL27"  !CDS_PN = "EL27";
"VSS1478":   PN = "ET14"  !CDS_PN = "ET14";
"VSS1479":   PN = "EL3"  !CDS_PN = "EL3";
"VSS1480":   PN = "ET20"  !CDS_PN = "ET20";
"VSS1481":   PN = "EL33"  !CDS_PN = "EL33";
"VSS1482":   PN = "ET26"  !CDS_PN = "ET26";
"VSS1483":   PN = "EL39"  !CDS_PN = "EL39";
"VSS1484":   PN = "ET32"  !CDS_PN = "ET32";
"VSS1485":   PN = "EL45"  !CDS_PN = "EL45";
"VSS1486":   PN = "EL5"  !CDS_PN = "EL5";
"VSS1488":   PN = "EL64"  !CDS_PN = "EL64";
"VSS1489":   PN = "EL76"  !CDS_PN = "EL76";
"VSS1491":   PN = "ET53"  !CDS_PN = "ET53";
"VSS1492":   PN = "EM42"  !CDS_PN = "EM42";
"VSS1493":   PN = "ET59"  !CDS_PN = "ET59";
"VSS1496":   PN = "EM73"  !CDS_PN = "EM73";
"VSS1497":   PN = "EM8"  !CDS_PN = "EM8";
"VSS1498":   PN = "EM81"  !CDS_PN = "EM81";
"VSS1499":   PN = "EM83"  !CDS_PN = "EM83";
"VSS1500":   PN = "EN11"  !CDS_PN = "EN11";
"VSS1501":   PN = "EN13"  !CDS_PN = "EN13";
"VSS1503":   PN = "EN15"  !CDS_PN = "EN15";
"VSS1505":   PN = "EN17"  !CDS_PN = "EN17";
"VSS1506":   PN = "EN19"  !CDS_PN = "EN19";
"VSS1512":   PN = "EN21"  !CDS_PN = "EN21";
"VSS1513":   PN = "EN23"  !CDS_PN = "EN23";
"VSS1515":   PN = "EN25"  !CDS_PN = "EN25";
"VSS1517":   PN = "EN27"  !CDS_PN = "EN27";
"VSS1518":   PN = "EN29"  !CDS_PN = "EN29";
"VSS1520":   PN = "EN31"  !CDS_PN = "EN31";
"VSS1522":   PN = "EN33"  !CDS_PN = "EN33";
"VSS1524":   PN = "EN35"  !CDS_PN = "EN35";
"VSS1525":   PN = "EN37"  !CDS_PN = "EN37";
"VSS1526":   PN = "EN41"  !CDS_PN = "EN41";
"VSS1528":   PN = "EN43"  !CDS_PN = "EN43";
"VSS1529":   PN = "EN45"  !CDS_PN = "EN45";
"VSS1530":   PN = "EN48"  !CDS_PN = "EN48";
"VSS1531":   PN = "EN50"  !CDS_PN = "EN50";
"VSS1533":   PN = "EN52"  !CDS_PN = "EN52";
"VSS1537":   PN = "EN54"  !CDS_PN = "EN54";
"VSS1539":   PN = "EN56"  !CDS_PN = "EN56";
"VSS1540":   PN = "EN64"  !CDS_PN = "EN64";
"VSS1541":   PN = "EN78"  !CDS_PN = "EN78";
"VSS1542":   PN = "EN80"  !CDS_PN = "EN80";
"VSS1543":   PN = "EP67"  !CDS_PN = "EP67";
"VSS1545":   PN = "EP83"  !CDS_PN = "EP83";
"VSS1547":   PN = "ER27"  !CDS_PN = "ER27";
"VSS1548":   PN = "ER33"  !CDS_PN = "ER33";
"VSS1549":   PN = "ER5"  !CDS_PN = "ER5";
"VSS1550":   PN = "ER7"  !CDS_PN = "ER7";
"VSS1551":   PN = "ER70"  !CDS_PN = "ER70";
"VSS1552":   PN = "ER74"  !CDS_PN = "ER74";
"VSS1553":   PN = "ER78"  !CDS_PN = "ER78";
"VSS1554":   PN = "ER80"  !CDS_PN = "ER80";
"VSS1555":   PN = "ER84"  !CDS_PN = "ER84";
"VSS1556":   PN = "ER86"  !CDS_PN = "ER86";
"VSS1557":   PN = "ET10"  !CDS_PN = "ET10";
"VSS1559":   PN = "ET16"  !CDS_PN = "ET16";
"VSS1561":   PN = "ET22"  !CDS_PN = "ET22";
"VSS1562":   PN = "ET28"  !CDS_PN = "ET28";
"VSS1563":   PN = "ET34"  !CDS_PN = "ET34";
"VSS1565":   PN = "ET38"  !CDS_PN = "ET38";
"VSS1569":   PN = "ET57"  !CDS_PN = "ET57";
"VSS1834":   PN = "ER41"  !CDS_PN = "ER41";
"VSS1835":   PN = "ER43"  !CDS_PN = "ER43";
"VSS1836":   PN = "ER48"  !CDS_PN = "ER48";
"VSS1837":   PN = "ER50"  !CDS_PN = "ER50";
BODY = "SOCKET4677_AZIF0045P001C01CS","I5": LOCATION = "U1" #&CDS_LOCATION = "U1" &SEC = "32" #&CDS_SEC = "32";
"VSS1111":   PN = "DY12"  !CDS_PN = "DY12";
"VSS1112":   PN = "DY16"  !CDS_PN = "DY16";
"VSS1115":   PN = "DY4"  !CDS_PN = "DY4";
"VSS1116":   PN = "DY42"  !CDS_PN = "DY42";
"VSS1141":   PN = "EA39"  !CDS_PN = "EA39";
"VSS1142":   PN = "EA45"  !CDS_PN = "EA45";
"VSS1144":   PN = "EA52"  !CDS_PN = "EA52";
"VSS1145":   PN = "EA58"  !CDS_PN = "EA58";
"VSS1146":   PN = "EA64"  !CDS_PN = "EA64";
"VSS1155":   PN = "EB16"  !CDS_PN = "EB16";
"VSS1156":   PN = "EB20"  !CDS_PN = "EB20";
"VSS1158":   PN = "EB26"  !CDS_PN = "EB26";
"VSS1161":   PN = "EB34"  !CDS_PN = "EB34";
"VSS1163":   PN = "EB4"  !CDS_PN = "EB4";
"VSS1165":   PN = "EB44"  !CDS_PN = "EB44";
"VSS1167":   PN = "EB51"  !CDS_PN = "EB51";
"VSS1168":   PN = "EB53"  !CDS_PN = "EB53";
"VSS1170":   PN = "EB59"  !CDS_PN = "EB59";
"VSS1171":   PN = "EB63"  !CDS_PN = "EB63";
"VSS1180":   PN = "EB91"  !CDS_PN = "EB91";
"VSS1185":   PN = "EC25"  !CDS_PN = "EC25";
"VSS1188":   PN = "EC35"  !CDS_PN = "EC35";
"VSS1193":   PN = "EC5"  !CDS_PN = "EC5";
"VSS1195":   PN = "EC54"  !CDS_PN = "EC54";
"VSS1197":   PN = "EC60"  !CDS_PN = "EC60";
"VSS1198":   PN = "EC62"  !CDS_PN = "EC62";
"VSS1200":   PN = "EC68"  !CDS_PN = "EC68";
"VSS1208":   PN = "ED12"  !CDS_PN = "ED12";
"VSS1210":   PN = "ED18"  !CDS_PN = "ED18";
"VSS1217":   PN = "ED42"  !CDS_PN = "ED42";
"VSS1220":   PN = "ED55"  !CDS_PN = "ED55";
"VSS1223":   PN = "ED61"  !CDS_PN = "ED61";
"VSS1224":   PN = "ED67"  !CDS_PN = "ED67";
"VSS1225":   PN = "ED73"  !CDS_PN = "ED73";
"VSS1232":   PN = "EE17"  !CDS_PN = "EE17";
"VSS1235":   PN = "EE39"  !CDS_PN = "EE39";
"VSS1237":   PN = "EE52"  !CDS_PN = "EE52";
"VSS1257":   PN = "DW66"  !CDS_PN = "DW66";
"VSS1258":   PN = "DW68"  !CDS_PN = "DW68";
"VSS1259":   PN = "DW70"  !CDS_PN = "DW70";
"VSS1260":   PN = "DW72"  !CDS_PN = "DW72";
"VSS1261":   PN = "DW74"  !CDS_PN = "DW74";
"VSS1262":   PN = "DW76"  !CDS_PN = "DW76";
"VSS1263":   PN = "DW80"  !CDS_PN = "DW80";
"VSS1264":   PN = "DW82"  !CDS_PN = "DW82";
"VSS1265":   PN = "EF51"  !CDS_PN = "EF51";
"VSS1266":   PN = "DW84"  !CDS_PN = "DW84";
"VSS1267":   PN = "DW88"  !CDS_PN = "DW88";
"VSS1269":   PN = "DY77"  !CDS_PN = "DY77";
"VSS1270":   PN = "DY8"  !CDS_PN = "DY8";
"VSS1274":   PN = "EA21"  !CDS_PN = "EA21";
"VSS1275":   PN = "EA27"  !CDS_PN = "EA27";
"VSS1276":   PN = "EF73"  !CDS_PN = "EF73";
"VSS1277":   PN = "EF75"  !CDS_PN = "EF75";
"VSS1278":   PN = "EA33"  !CDS_PN = "EA33";
"VSS1279":   PN = "EA70"  !CDS_PN = "EA70";
"VSS1280":   PN = "EA76"  !CDS_PN = "EA76";
"VSS1281":   PN = "EA78"  !CDS_PN = "EA78";
"VSS1282":   PN = "EA80"  !CDS_PN = "EA80";
"VSS1283":   PN = "EF89"  !CDS_PN = "EF89";
"VSS1284":   PN = "EG13"  !CDS_PN = "EG13";
"VSS1285":   PN = "EA84"  !CDS_PN = "EA84";
"VSS1286":   PN = "EA88"  !CDS_PN = "EA88";
"VSS1287":   PN = "EB12"  !CDS_PN = "EB12";
"VSS1288":   PN = "EB22"  !CDS_PN = "EB22";
"VSS1289":   PN = "EB28"  !CDS_PN = "EB28";
"VSS1290":   PN = "EG5"  !CDS_PN = "EG5";
"VSS1291":   PN = "EG52"  !CDS_PN = "EG52";
"VSS1292":   PN = "EB32"  !CDS_PN = "EB32";
"VSS1293":   PN = "EB38"  !CDS_PN = "EB38";
"VSS1294":   PN = "EG7"  !CDS_PN = "EG7";
"VSS1295":   PN = "EB40"  !CDS_PN = "EB40";
"VSS1296":   PN = "EB47"  !CDS_PN = "EB47";
"VSS1297":   PN = "EB57"  !CDS_PN = "EB57";
"VSS1298":   PN = "EB65"  !CDS_PN = "EB65";
"VSS1299":   PN = "EB69"  !CDS_PN = "EB69";
"VSS1300":   PN = "EB71"  !CDS_PN = "EB71";
"VSS1301":   PN = "EB75"  !CDS_PN = "EB75";
"VSS1302":   PN = "EH12"  !CDS_PN = "EH12";
"VSS1303":   PN = "EH14"  !CDS_PN = "EH14";
"VSS1304":   PN = "EB79"  !CDS_PN = "EB79";
"VSS1305":   PN = "EH18"  !CDS_PN = "EH18";
"VSS1306":   PN = "EB8"  !CDS_PN = "EB8";
"VSS1307":   PN = "EB83"  !CDS_PN = "EB83";
"VSS1308":   PN = "EB87"  !CDS_PN = "EB87";
"VSS1309":   PN = "EC1"  !CDS_PN = "EC1";
"VSS1310":   PN = "EC13"  !CDS_PN = "EC13";
"VSS1311":   PN = "EC19"  !CDS_PN = "EC19";
"VSS1313":   PN = "EC23"  !CDS_PN = "EC23";
"VSS1314":   PN = "EC29"  !CDS_PN = "EC29";
"VSS1316":   PN = "EC31"  !CDS_PN = "EC31";
"VSS1317":   PN = "EC37"  !CDS_PN = "EC37";
"VSS1318":   PN = "EH6"  !CDS_PN = "EH6";
"VSS1321":   PN = "EC41"  !CDS_PN = "EC41";
"VSS1323":   PN = "EC43"  !CDS_PN = "EC43";
"VSS1324":   PN = "EC48"  !CDS_PN = "EC48";
"VSS1326":   PN = "EC50"  !CDS_PN = "EC50";
"VSS1327":   PN = "EC56"  !CDS_PN = "EC56";
"VSS1329":   PN = "EC66"  !CDS_PN = "EC66";
"VSS1330":   PN = "EC72"  !CDS_PN = "EC72";
"VSS1332":   PN = "EC74"  !CDS_PN = "EC74";
"VSS1333":   PN = "EC82"  !CDS_PN = "EC82";
"VSS1335":   PN = "EC84"  !CDS_PN = "EC84";
"VSS1336":   PN = "EC88"  !CDS_PN = "EC88";
"VSS1337":   PN = "EC9"  !CDS_PN = "EC9";
"VSS1338":   PN = "ED16"  !CDS_PN = "ED16";
"VSS1339":   PN = "ED24"  !CDS_PN = "ED24";
"VSS1341":   PN = "ED30"  !CDS_PN = "ED30";
"VSS1342":   PN = "ED36"  !CDS_PN = "ED36";
"VSS1344":   PN = "ED4"  !CDS_PN = "ED4";
"VSS1346":   PN = "ED49"  !CDS_PN = "ED49";
"VSS1348":   PN = "ED8"  !CDS_PN = "ED8";
"VSS1349":   PN = "EE78"  !CDS_PN = "EE78";
"VSS1350":   PN = "EE80"  !CDS_PN = "EE80";
"VSS1351":   PN = "EE88"  !CDS_PN = "EE88";
"VSS1352":   PN = "EF12"  !CDS_PN = "EF12";
"VSS1353":   PN = "EF16"  !CDS_PN = "EF16";
"VSS1354":   PN = "EF18"  !CDS_PN = "EF18";
"VSS1356":   PN = "EF2"  !CDS_PN = "EF2";
"VSS1358":   PN = "EF20"  !CDS_PN = "EF20";
"VSS1360":   PN = "EF22"  !CDS_PN = "EF22";
"VSS1361":   PN = "EF24"  !CDS_PN = "EF24";
"VSS1362":   PN = "EF26"  !CDS_PN = "EF26";
"VSS1363":   PN = "EF28"  !CDS_PN = "EF28";
"VSS1364":   PN = "EF30"  !CDS_PN = "EF30";
"VSS1365":   PN = "EF32"  !CDS_PN = "EF32";
"VSS1367":   PN = "EF34"  !CDS_PN = "EF34";
"VSS1370":   PN = "EF36"  !CDS_PN = "EF36";
"VSS1373":   PN = "EF38"  !CDS_PN = "EF38";
"VSS1374":   PN = "EF4"  !CDS_PN = "EF4";
"VSS1376":   PN = "EF40"  !CDS_PN = "EF40";
"VSS1382":   PN = "EF42"  !CDS_PN = "EF42";
"VSS1383":   PN = "EF44"  !CDS_PN = "EF44";
"VSS1384":   PN = "EF47"  !CDS_PN = "EF47";
"VSS1385":   PN = "EF49"  !CDS_PN = "EF49";
"VSS1386":   PN = "EF53"  !CDS_PN = "EF53";
"VSS1387":   PN = "EF55"  !CDS_PN = "EF55";
"VSS1388":   PN = "EF57"  !CDS_PN = "EF57";
"VSS1389":   PN = "EF59"  !CDS_PN = "EF59";
"VSS1390":   PN = "EF61"  !CDS_PN = "EF61";
"VSS1392":   PN = "EF63"  !CDS_PN = "EF63";
"VSS1393":   PN = "EF65"  !CDS_PN = "EF65";
"VSS1395":   PN = "EF67"  !CDS_PN = "EF67";
"VSS1399":   PN = "EF69"  !CDS_PN = "EF69";
"VSS1402":   PN = "EF71"  !CDS_PN = "EF71";
"VSS1403":   PN = "EF77"  !CDS_PN = "EF77";
"VSS1404":   PN = "EF8"  !CDS_PN = "EF8";
"VSS1406":   PN = "EF85"  !CDS_PN = "EF85";
"VSS1407":   PN = "EF87"  !CDS_PN = "EF87";
"VSS1408":   PN = "EG39"  !CDS_PN = "EG39";
"VSS1410":   PN = "EG82"  !CDS_PN = "EG82";
"VSS1411":   PN = "EG84"  !CDS_PN = "EG84";
"VSS1412":   PN = "EG86"  !CDS_PN = "EG86";
"VSS1413":   PN = "EG88"  !CDS_PN = "EG88";
"VSS1414":   PN = "EG9"  !CDS_PN = "EG9";
"VSS1415":   PN = "EG90"  !CDS_PN = "EG90";
"VSS1416":   PN = "EH16"  !CDS_PN = "EH16";
"VSS1417":   PN = "EH24"  !CDS_PN = "EH24";
"VSS1418":   PN = "EH30"  !CDS_PN = "EH30";
"VSS1420":   PN = "EH4"  !CDS_PN = "EH4";
BODY = "SOCKET4677_AZIF0045P001C01CS","I8": LOCATION = "U1" #&CDS_LOCATION = "U1" &SEC = "33" #&CDS_SEC = "33";
"VSS934":   PN = "DM51"  !CDS_PN = "DM51";
"VSS945":   PN = "DM73"  !CDS_PN = "DM73";
"VSS955":   PN = "DN17"  !CDS_PN = "DN17";
"VSS957":   PN = "DN39"  !CDS_PN = "DN39";
"VSS959":   PN = "DN52"  !CDS_PN = "DN52";
"VSS966":   PN = "DP12"  !CDS_PN = "DP12";
"VSS968":   PN = "DP18"  !CDS_PN = "DP18";
"VSS969":   PN = "DP24"  !CDS_PN = "DP24";
"VSS973":   PN = "DP42"  !CDS_PN = "DP42";
"VSS976":   PN = "DP55"  !CDS_PN = "DP55";
"VSS979":   PN = "DP61"  !CDS_PN = "DP61";
"VSS980":   PN = "DP67"  !CDS_PN = "DP67";
"VSS985":   PN = "DP91"  !CDS_PN = "DP91";
"VSS990":   PN = "DR25"  !CDS_PN = "DR25";
"VSS993":   PN = "DR35"  !CDS_PN = "DR35";
"VSS998":   PN = "DR5"  !CDS_PN = "DR5";
"VSS1000":   PN = "DR54"  !CDS_PN = "DR54";
"VSS1002":   PN = "DR60"  !CDS_PN = "DR60";
"VSS1003":   PN = "DR62"  !CDS_PN = "DR62";
"VSS1005":   PN = "DR68"  !CDS_PN = "DR68";
"VSS1006":   PN = "DR72"  !CDS_PN = "DR72";
"VSS1013":   PN = "DT16"  !CDS_PN = "DT16";
"VSS1014":   PN = "DT20"  !CDS_PN = "DT20";
"VSS1016":   PN = "DT26"  !CDS_PN = "DT26";
"VSS1021":   PN = "DT4"  !CDS_PN = "DT4";
"VSS1023":   PN = "DT44"  !CDS_PN = "DT44";
"VSS1025":   PN = "DT51"  !CDS_PN = "DT51";
"VSS1026":   PN = "DT53"  !CDS_PN = "DT53";
"VSS1028":   PN = "DT59"  !CDS_PN = "DT59";
"VSS1029":   PN = "DT63"  !CDS_PN = "DT63";
"VSS1036":   PN = "DT83"  !CDS_PN = "DT83";
"VSS1047":   PN = "DU39"  !CDS_PN = "DU39";
"VSS1048":   PN = "DU45"  !CDS_PN = "DU45";
"VSS1050":   PN = "DU52"  !CDS_PN = "DU52";
"VSS1051":   PN = "DU58"  !CDS_PN = "DU58";
"VSS1052":   PN = "DU64"  !CDS_PN = "DU64";
"VSS1054":   PN = "DU70"  !CDS_PN = "DU70";
"VSS1059":   PN = "DV12"  !CDS_PN = "DV12";
"VSS1060":   PN = "DV16"  !CDS_PN = "DV16";
"VSS1063":   PN = "DV4"  !CDS_PN = "DV4";
"VSS1064":   PN = "DV42"  !CDS_PN = "DV42";
"VSS1077":   PN = "DW21"  !CDS_PN = "DW21";
"VSS1097":   PN = "DW60"  !CDS_PN = "DW60";
"VSS1100":   PN = "DM12"  !CDS_PN = "DM12";
"VSS1101":   PN = "DM16"  !CDS_PN = "DM16";
"VSS1102":   PN = "DM18"  !CDS_PN = "DM18";
"VSS1103":   PN = "DM20"  !CDS_PN = "DM20";
"VSS1104":   PN = "DM22"  !CDS_PN = "DM22";
"VSS1105":   PN = "DM24"  !CDS_PN = "DM24";
"VSS1106":   PN = "DM26"  !CDS_PN = "DM26";
"VSS1107":   PN = "DM28"  !CDS_PN = "DM28";
"VSS1108":   PN = "DM30"  !CDS_PN = "DM30";
"VSS1109":   PN = "DM32"  !CDS_PN = "DM32";
"VSS1110":   PN = "DM34"  !CDS_PN = "DM34";
"VSS1113":   PN = "DM36"  !CDS_PN = "DM36";
"VSS1114":   PN = "DM38"  !CDS_PN = "DM38";
"VSS1117":   PN = "DM4"  !CDS_PN = "DM4";
"VSS1118":   PN = "DM40"  !CDS_PN = "DM40";
"VSS1119":   PN = "DM42"  !CDS_PN = "DM42";
"VSS1120":   PN = "DM44"  !CDS_PN = "DM44";
"VSS1121":   PN = "DM47"  !CDS_PN = "DM47";
"VSS1122":   PN = "DM49"  !CDS_PN = "DM49";
"VSS1123":   PN = "DM53"  !CDS_PN = "DM53";
"VSS1124":   PN = "DM55"  !CDS_PN = "DM55";
"VSS1127":   PN = "DM57"  !CDS_PN = "DM57";
"VSS1128":   PN = "DM59"  !CDS_PN = "DM59";
"VSS1130":   PN = "DM61"  !CDS_PN = "DM61";
"VSS1132":   PN = "DM63"  !CDS_PN = "DM63";
"VSS1133":   PN = "DM65"  !CDS_PN = "DM65";
"VSS1134":   PN = "DM67"  !CDS_PN = "DM67";
"VSS1135":   PN = "DM69"  !CDS_PN = "DM69";
"VSS1136":   PN = "DM71"  !CDS_PN = "DM71";
"VSS1137":   PN = "DM75"  !CDS_PN = "DM75";
"VSS1138":   PN = "DM77"  !CDS_PN = "DM77";
"VSS1139":   PN = "DM79"  !CDS_PN = "DM79";
"VSS1140":   PN = "DM8"  !CDS_PN = "DM8";
"VSS1143":   PN = "DN78"  !CDS_PN = "DN78";
"VSS1147":   PN = "DN84"  !CDS_PN = "DN84";
"VSS1148":   PN = "DN88"  !CDS_PN = "DN88";
"VSS1149":   PN = "DP16"  !CDS_PN = "DP16";
"VSS1150":   PN = "DP30"  !CDS_PN = "DP30";
"VSS1151":   PN = "DP36"  !CDS_PN = "DP36";
"VSS1152":   PN = "DP4"  !CDS_PN = "DP4";
"VSS1153":   PN = "DP49"  !CDS_PN = "DP49";
"VSS1154":   PN = "DP73"  !CDS_PN = "DP73";
"VSS1157":   PN = "DP8"  !CDS_PN = "DP8";
"VSS1159":   PN = "DP81"  !CDS_PN = "DP81";
"VSS1160":   PN = "DP87"  !CDS_PN = "DP87";
"VSS1162":   PN = "DR1"  !CDS_PN = "DR1";
"VSS1164":   PN = "DR13"  !CDS_PN = "DR13";
"VSS1166":   PN = "DR19"  !CDS_PN = "DR19";
"VSS1169":   PN = "DR23"  !CDS_PN = "DR23";
"VSS1172":   PN = "DR29"  !CDS_PN = "DR29";
"VSS1173":   PN = "DR31"  !CDS_PN = "DR31";
"VSS1174":   PN = "DR37"  !CDS_PN = "DR37";
"VSS1175":   PN = "DR41"  !CDS_PN = "DR41";
"VSS1176":   PN = "DR43"  !CDS_PN = "DR43";
"VSS1177":   PN = "DR48"  !CDS_PN = "DR48";
"VSS1178":   PN = "DR50"  !CDS_PN = "DR50";
"VSS1179":   PN = "DR56"  !CDS_PN = "DR56";
"VSS1181":   PN = "DR66"  !CDS_PN = "DR66";
"VSS1182":   PN = "DR74"  !CDS_PN = "DR74";
"VSS1183":   PN = "DR78"  !CDS_PN = "DR78";
"VSS1184":   PN = "DR84"  !CDS_PN = "DR84";
"VSS1186":   PN = "DR88"  !CDS_PN = "DR88";
"VSS1187":   PN = "DR9"  !CDS_PN = "DR9";
"VSS1189":   PN = "DT12"  !CDS_PN = "DT12";
"VSS1190":   PN = "DT22"  !CDS_PN = "DT22";
"VSS1191":   PN = "DT28"  !CDS_PN = "DT28";
"VSS1192":   PN = "DT32"  !CDS_PN = "DT32";
"VSS1194":   PN = "DT34"  !CDS_PN = "DT34";
"VSS1196":   PN = "DT38"  !CDS_PN = "DT38";
"VSS1199":   PN = "DT40"  !CDS_PN = "DT40";
"VSS1201":   PN = "DT47"  !CDS_PN = "DT47";
"VSS1202":   PN = "DT57"  !CDS_PN = "DT57";
"VSS1203":   PN = "DT65"  !CDS_PN = "DT65";
"VSS1204":   PN = "DT69"  !CDS_PN = "DT69";
"VSS1205":   PN = "DT71"  !CDS_PN = "DT71";
"VSS1206":   PN = "DT75"  !CDS_PN = "DT75";
"VSS1207":   PN = "DT8"  !CDS_PN = "DT8";
"VSS1209":   PN = "DU21"  !CDS_PN = "DU21";
"VSS1211":   PN = "DU27"  !CDS_PN = "DU27";
"VSS1212":   PN = "DU33"  !CDS_PN = "DU33";
"VSS1213":   PN = "DU76"  !CDS_PN = "DU76";
"VSS1214":   PN = "DU78"  !CDS_PN = "DU78";
"VSS1215":   PN = "DU84"  !CDS_PN = "DU84";
"VSS1216":   PN = "DU88"  !CDS_PN = "DU88";
"VSS1218":   PN = "DV77"  !CDS_PN = "DV77";
"VSS1219":   PN = "DV79"  !CDS_PN = "DV79";
"VSS1221":   PN = "DV8"  !CDS_PN = "DV8";
"VSS1222":   PN = "DV81"  !CDS_PN = "DV81";
"VSS1226":   PN = "DV83"  !CDS_PN = "DV83";
"VSS1227":   PN = "DV87"  !CDS_PN = "DV87";
"VSS1228":   PN = "DV91"  !CDS_PN = "DV91";
"VSS1229":   PN = "DW1"  !CDS_PN = "DW1";
"VSS1230":   PN = "DW13"  !CDS_PN = "DW13";
"VSS1231":   PN = "DW17"  !CDS_PN = "DW17";
"VSS1233":   PN = "DW19"  !CDS_PN = "DW19";
"VSS1234":   PN = "DW23"  !CDS_PN = "DW23";
"VSS1236":   PN = "DW25"  !CDS_PN = "DW25";
"VSS1238":   PN = "DW27"  !CDS_PN = "DW27";
"VSS1239":   PN = "DW29"  !CDS_PN = "DW29";
"VSS1240":   PN = "DW31"  !CDS_PN = "DW31";
"VSS1241":   PN = "DW33"  !CDS_PN = "DW33";
"VSS1242":   PN = "DW35"  !CDS_PN = "DW35";
"VSS1243":   PN = "DW37"  !CDS_PN = "DW37";
"VSS1244":   PN = "DW39"  !CDS_PN = "DW39";
"VSS1245":   PN = "DW41"  !CDS_PN = "DW41";
"VSS1246":   PN = "DW43"  !CDS_PN = "DW43";
"VSS1247":   PN = "DW45"  !CDS_PN = "DW45";
"VSS1248":   PN = "DW48"  !CDS_PN = "DW48";
"VSS1249":   PN = "DW5"  !CDS_PN = "DW5";
"VSS1250":   PN = "DW50"  !CDS_PN = "DW50";
"VSS1251":   PN = "DW52"  !CDS_PN = "DW52";
"VSS1252":   PN = "DW54"  !CDS_PN = "DW54";
"VSS1253":   PN = "DW56"  !CDS_PN = "DW56";
"VSS1254":   PN = "DW58"  !CDS_PN = "DW58";
"VSS1255":   PN = "DW62"  !CDS_PN = "DW62";
"VSS1256":   PN = "DW64"  !CDS_PN = "DW64";
"VSS1268":   PN = "DW9"  !CDS_PN = "DW9";
DRAWING = "@s9s_mb_2u_lib.s9s_mb_2u(sch_1):page71";
BODY = "SOCKET4677_AZIF0045P001C01CS","I2": LOCATION = "U1" #&CDS_LOCATION = "U1" &SEC = "34" #&CDS_SEC = "34";
"VSS723":   PN = "DB91"  !CDS_PN = "DB91";
"VSS724":   PN = "DC1"  !CDS_PN = "DC1";
"VSS725":   PN = "DC13"  !CDS_PN = "DC13";
"VSS726":   PN = "DC21"  !CDS_PN = "DC21";
"VSS735":   PN = "DC52"  !CDS_PN = "DC52";
"VSS738":   PN = "DC58"  !CDS_PN = "DC58";
"VSS739":   PN = "DC64"  !CDS_PN = "DC64";
"VSS747":   PN = "DD12"  !CDS_PN = "DD12";
"VSS748":   PN = "DD16"  !CDS_PN = "DD16";
"VSS753":   PN = "DD49"  !CDS_PN = "DD49";
"VSS776":   PN = "DE39"  !CDS_PN = "DE39";
"VSS791":   PN = "DE70"  !CDS_PN = "DE70";
"VSS798":   PN = "DF12"  !CDS_PN = "DF12";
"VSS799":   PN = "DF16"  !CDS_PN = "DF16";
"VSS802":   PN = "DF49"  !CDS_PN = "DF49";
"VSS806":   PN = "DF91"  !CDS_PN = "DF91";
"VSS807":   PN = "DG1"  !CDS_PN = "DG1";
"VSS808":   PN = "DG13"  !CDS_PN = "DG13";
"VSS809":   PN = "DG21"  !CDS_PN = "DG21";
"VSS817":   PN = "DG52"  !CDS_PN = "DG52";
"VSS820":   PN = "DG58"  !CDS_PN = "DG58";
"VSS821":   PN = "DG64"  !CDS_PN = "DG64";
"VSS829":   PN = "DH16"  !CDS_PN = "DH16";
"VSS830":   PN = "DH20"  !CDS_PN = "DH20";
"VSS832":   PN = "DH26"  !CDS_PN = "DH26";
"VSS835":   PN = "DH34"  !CDS_PN = "DH34";
"VSS839":   PN = "DH44"  !CDS_PN = "DH44";
"VSS841":   PN = "DH51"  !CDS_PN = "DH51";
"VSS842":   PN = "DH53"  !CDS_PN = "DH53";
"VSS844":   PN = "DH59"  !CDS_PN = "DH59";
"VSS845":   PN = "DH63"  !CDS_PN = "DH63";
"VSS847":   PN = "DH69"  !CDS_PN = "DH69";
"VSS849":   PN = "DH75"  !CDS_PN = "DH75";
"VSS857":   PN = "DJ25"  !CDS_PN = "DJ25";
"VSS861":   PN = "DJ35"  !CDS_PN = "DJ35";
"VSS867":   PN = "DJ54"  !CDS_PN = "DJ54";
"VSS870":   PN = "DJ62"  !CDS_PN = "DJ62";
"VSS872":   PN = "DJ68"  !CDS_PN = "DJ68";
"VSS880":   PN = "DK12"  !CDS_PN = "DK12";
"VSS882":   PN = "DK18"  !CDS_PN = "DK18";
"VSS883":   PN = "DK24"  !CDS_PN = "DK24";
"VSS887":   PN = "DK42"  !CDS_PN = "DK42";
"VSS890":   PN = "DK55"  !CDS_PN = "DK55";
"VSS893":   PN = "DK61"  !CDS_PN = "DK61";
"VSS894":   PN = "DK67"  !CDS_PN = "DK67";
"VSS903":   PN = "DL1"  !CDS_PN = "DL1";
"VSS904":   PN = "DL13"  !CDS_PN = "DL13";
"VSS905":   PN = "DL17"  !CDS_PN = "DL17";
"VSS908":   PN = "DL5"  !CDS_PN = "DL5";
"VSS909":   PN = "DL52"  !CDS_PN = "DL52";
"VSS949":   PN = "DC27"  !CDS_PN = "DC27";
"VSS950":   PN = "DC33"  !CDS_PN = "DC33";
"VSS951":   PN = "DC39"  !CDS_PN = "DC39";
"VSS952":   PN = "DC45"  !CDS_PN = "DC45";
"VSS953":   PN = "DC5"  !CDS_PN = "DC5";
"VSS954":   PN = "DC70"  !CDS_PN = "DC70";
"VSS956":   PN = "DC76"  !CDS_PN = "DC76";
"VSS958":   PN = "DC78"  !CDS_PN = "DC78";
"VSS960":   PN = "DC80"  !CDS_PN = "DC80";
"VSS961":   PN = "DC84"  !CDS_PN = "DC84";
"VSS962":   PN = "DC88"  !CDS_PN = "DC88";
"VSS963":   PN = "DC9"  !CDS_PN = "DC9";
"VSS964":   PN = "DD4"  !CDS_PN = "DD4";
"VSS965":   PN = "DD79"  !CDS_PN = "DD79";
"VSS967":   PN = "DD8"  !CDS_PN = "DD8";
"VSS970":   PN = "DE17"  !CDS_PN = "DE17";
"VSS971":   PN = "DE19"  !CDS_PN = "DE19";
"VSS972":   PN = "DE21"  !CDS_PN = "DE21";
"VSS974":   PN = "DE23"  !CDS_PN = "DE23";
"VSS975":   PN = "DE25"  !CDS_PN = "DE25";
"VSS977":   PN = "DE27"  !CDS_PN = "DE27";
"VSS978":   PN = "DE29"  !CDS_PN = "DE29";
"VSS981":   PN = "DE31"  !CDS_PN = "DE31";
"VSS982":   PN = "DE33"  !CDS_PN = "DE33";
"VSS983":   PN = "DE35"  !CDS_PN = "DE35";
"VSS984":   PN = "DE37"  !CDS_PN = "DE37";
"VSS986":   PN = "DE41"  !CDS_PN = "DE41";
"VSS987":   PN = "DE43"  !CDS_PN = "DE43";
"VSS988":   PN = "DE45"  !CDS_PN = "DE45";
"VSS989":   PN = "DE48"  !CDS_PN = "DE48";
"VSS991":   PN = "DE50"  !CDS_PN = "DE50";
"VSS992":   PN = "DE52"  !CDS_PN = "DE52";
"VSS994":   PN = "DE54"  !CDS_PN = "DE54";
"VSS995":   PN = "DE56"  !CDS_PN = "DE56";
"VSS996":   PN = "DE58"  !CDS_PN = "DE58";
"VSS997":   PN = "DE60"  !CDS_PN = "DE60";
"VSS999":   PN = "DE62"  !CDS_PN = "DE62";
"VSS1001":   PN = "DE64"  !CDS_PN = "DE64";
"VSS1004":   PN = "DE66"  !CDS_PN = "DE66";
"VSS1007":   PN = "DE68"  !CDS_PN = "DE68";
"VSS1008":   PN = "DE72"  !CDS_PN = "DE72";
"VSS1009":   PN = "DE74"  !CDS_PN = "DE74";
"VSS1010":   PN = "DE76"  !CDS_PN = "DE76";
"VSS1011":   PN = "DE82"  !CDS_PN = "DE82";
"VSS1012":   PN = "DE84"  !CDS_PN = "DE84";
"VSS1015":   PN = "DE88"  !CDS_PN = "DE88";
"VSS1017":   PN = "DF4"  !CDS_PN = "DF4";
"VSS1018":   PN = "DF79"  !CDS_PN = "DF79";
"VSS1019":   PN = "DF8"  !CDS_PN = "DF8";
"VSS1020":   PN = "DF87"  !CDS_PN = "DF87";
"VSS1022":   PN = "DG27"  !CDS_PN = "DG27";
"VSS1024":   PN = "DG33"  !CDS_PN = "DG33";
"VSS1027":   PN = "DG39"  !CDS_PN = "DG39";
"VSS1030":   PN = "DG45"  !CDS_PN = "DG45";
"VSS1031":   PN = "DG5"  !CDS_PN = "DG5";
"VSS1032":   PN = "DG70"  !CDS_PN = "DG70";
"VSS1033":   PN = "DG76"  !CDS_PN = "DG76";
"VSS1034":   PN = "DG80"  !CDS_PN = "DG80";
"VSS1035":   PN = "DG84"  !CDS_PN = "DG84";
"VSS1037":   PN = "DG88"  !CDS_PN = "DG88";
"VSS1038":   PN = "DG9"  !CDS_PN = "DG9";
"VSS1039":   PN = "DH12"  !CDS_PN = "DH12";
"VSS1040":   PN = "DH22"  !CDS_PN = "DH22";
"VSS1041":   PN = "DH28"  !CDS_PN = "DH28";
"VSS1042":   PN = "DH32"  !CDS_PN = "DH32";
"VSS1043":   PN = "DH38"  !CDS_PN = "DH38";
"VSS1044":   PN = "DH4"  !CDS_PN = "DH4";
"VSS1045":   PN = "DH40"  !CDS_PN = "DH40";
"VSS1046":   PN = "DH47"  !CDS_PN = "DH47";
"VSS1049":   PN = "DH57"  !CDS_PN = "DH57";
"VSS1053":   PN = "DH65"  !CDS_PN = "DH65";
"VSS1055":   PN = "DH71"  !CDS_PN = "DH71";
"VSS1056":   PN = "DH77"  !CDS_PN = "DH77";
"VSS1057":   PN = "DH8"  !CDS_PN = "DH8";
"VSS1058":   PN = "DH85"  !CDS_PN = "DH85";
"VSS1061":   PN = "DJ19"  !CDS_PN = "DJ19";
"VSS1062":   PN = "DJ23"  !CDS_PN = "DJ23";
"VSS1065":   PN = "DJ29"  !CDS_PN = "DJ29";
"VSS1066":   PN = "DJ31"  !CDS_PN = "DJ31";
"VSS1067":   PN = "DJ37"  !CDS_PN = "DJ37";
"VSS1068":   PN = "DJ41"  !CDS_PN = "DJ41";
"VSS1069":   PN = "DJ43"  !CDS_PN = "DJ43";
"VSS1070":   PN = "DJ48"  !CDS_PN = "DJ48";
"VSS1071":   PN = "DJ50"  !CDS_PN = "DJ50";
"VSS1072":   PN = "DJ56"  !CDS_PN = "DJ56";
"VSS1073":   PN = "DJ60"  !CDS_PN = "DJ60";
"VSS1074":   PN = "DJ66"  !CDS_PN = "DJ66";
"VSS1075":   PN = "DJ72"  !CDS_PN = "DJ72";
"VSS1076":   PN = "DJ74"  !CDS_PN = "DJ74";
"VSS1078":   PN = "DJ80"  !CDS_PN = "DJ80";
"VSS1079":   PN = "DJ82"  !CDS_PN = "DJ82";
"VSS1080":   PN = "DJ84"  !CDS_PN = "DJ84";
"VSS1081":   PN = "DJ88"  !CDS_PN = "DJ88";
"VSS1082":   PN = "DK16"  !CDS_PN = "DK16";
"VSS1083":   PN = "DK30"  !CDS_PN = "DK30";
"VSS1084":   PN = "DK36"  !CDS_PN = "DK36";
"VSS1085":   PN = "DK4"  !CDS_PN = "DK4";
"VSS1086":   PN = "DK49"  !CDS_PN = "DK49";
"VSS1087":   PN = "DK73"  !CDS_PN = "DK73";
"VSS1088":   PN = "DK77"  !CDS_PN = "DK77";
"VSS1089":   PN = "DK79"  !CDS_PN = "DK79";
"VSS1090":   PN = "DK8"  !CDS_PN = "DK8";
"VSS1091":   PN = "DK81"  !CDS_PN = "DK81";
"VSS1092":   PN = "DK83"  !CDS_PN = "DK83";
"VSS1093":   PN = "DK87"  !CDS_PN = "DK87";
"VSS1094":   PN = "DK91"  !CDS_PN = "DK91";
"VSS1095":   PN = "DL39"  !CDS_PN = "DL39";
"VSS1096":   PN = "DL84"  !CDS_PN = "DL84";
"VSS1098":   PN = "DL88"  !CDS_PN = "DL88";
"VSS1099":   PN = "DL9"  !CDS_PN = "DL9";
BODY = "SOCKET4677_AZIF0045P001C01CS","I5": LOCATION = "U1" #&CDS_LOCATION = "U1" &SEC = "35" #&CDS_SEC = "35";
"VSS436":   PN = "CM16"  !CDS_PN = "CM16";
"VSS438":   PN = "CM22"  !CDS_PN = "CM22";
"VSS471":   PN = "CN76"  !CDS_PN = "CN76";
"VSS478":   PN = "CP16"  !CDS_PN = "CP16";
"VSS493":   PN = "CP79"  !CDS_PN = "CP79";
"VSS514":   PN = "CR78"  !CDS_PN = "CR78";
"VSS521":   PN = "CT16"  !CDS_PN = "CT16";
"VSS526":   PN = "CT4"  !CDS_PN = "CT4";
"VSS534":   PN = "CT8"  !CDS_PN = "CT8";
"VSS537":   PN = "CT89"  !CDS_PN = "CT89";
"VSS544":   PN = "CU25"  !CDS_PN = "CU25";
"VSS553":   PN = "CU72"  !CDS_PN = "CU72";
"VSS554":   PN = "CU78"  !CDS_PN = "CU78";
"VSS558":   PN = "CV16"  !CDS_PN = "CV16";
"VSS562":   PN = "CV26"  !CDS_PN = "CV26";
"VSS571":   PN = "CV79"  !CDS_PN = "CV79";
"VSS583":   PN = "CW33"  !CDS_PN = "CW33";
"VSS595":   PN = "CW70"  !CDS_PN = "CW70";
"VSS611":   PN = "CY4"  !CDS_PN = "CY4";
"VSS679":   PN = "DA43"  !CDS_PN = "DA43";
"VSS690":   PN = "DA68"  !CDS_PN = "DA68";
"VSS699":   PN = "DB16"  !CDS_PN = "DB16";
"VSS700":   PN = "DB20"  !CDS_PN = "DB20";
"VSS702":   PN = "DB26"  !CDS_PN = "DB26";
"VSS705":   PN = "DB34"  !CDS_PN = "DB34";
"VSS709":   PN = "DB44"  !CDS_PN = "DB44";
"VSS711":   PN = "DB51"  !CDS_PN = "DB51";
"VSS712":   PN = "DB53"  !CDS_PN = "DB53";
"VSS714":   PN = "DB59"  !CDS_PN = "DB59";
"VSS715":   PN = "DB63"  !CDS_PN = "DB63";
"VSS717":   PN = "DB69"  !CDS_PN = "DB69";
"VSS719":   PN = "DB75"  !CDS_PN = "DB75";
"VSS744":   PN = "CK63"  !CDS_PN = "CK63";
"VSS745":   PN = "CK69"  !CDS_PN = "CK69";
"VSS749":   PN = "CK81"  !CDS_PN = "CK81";
"VSS750":   PN = "CL1"  !CDS_PN = "CL1";
"VSS751":   PN = "CL13"  !CDS_PN = "CL13";
"VSS752":   PN = "CL17"  !CDS_PN = "CL17";
"VSS754":   PN = "CL5"  !CDS_PN = "CL5";
"VSS755":   PN = "CL62"  !CDS_PN = "CL62";
"VSS756":   PN = "CL74"  !CDS_PN = "CL74";
"VSS757":   PN = "CL78"  !CDS_PN = "CL78";
"VSS758":   PN = "CL80"  !CDS_PN = "CL80";
"VSS759":   PN = "CL82"  !CDS_PN = "CL82";
"VSS760":   PN = "CL9"  !CDS_PN = "CL9";
"VSS761":   PN = "CM12"  !CDS_PN = "CM12";
"VSS762":   PN = "CM20"  !CDS_PN = "CM20";
"VSS763":   PN = "CM24"  !CDS_PN = "CM24";
"VSS764":   PN = "CM4"  !CDS_PN = "CM4";
"VSS765":   PN = "CM61"  !CDS_PN = "CM61";
"VSS766":   PN = "CM65"  !CDS_PN = "CM65";
"VSS767":   PN = "CM67"  !CDS_PN = "CM67";
"VSS768":   PN = "CM79"  !CDS_PN = "CM79";
"VSS769":   PN = "CM8"  !CDS_PN = "CM8";
"VSS770":   PN = "CM81"  !CDS_PN = "CM81";
"VSS771":   PN = "CM83"  !CDS_PN = "CM83";
"VSS772":   PN = "CM85"  !CDS_PN = "CM85";
"VSS773":   PN = "CN68"  !CDS_PN = "CN68";
"VSS774":   PN = "CN70"  !CDS_PN = "CN70";
"VSS775":   PN = "CN72"  !CDS_PN = "CN72";
"VSS777":   PN = "CN74"  !CDS_PN = "CN74";
"VSS778":   PN = "CN84"  !CDS_PN = "CN84";
"VSS779":   PN = "CN86"  !CDS_PN = "CN86";
"VSS780":   PN = "CP12"  !CDS_PN = "CP12";
"VSS781":   PN = "CP18"  !CDS_PN = "CP18";
"VSS782":   PN = "CP4"  !CDS_PN = "CP4";
"VSS783":   PN = "CP75"  !CDS_PN = "CP75";
"VSS784":   PN = "CP77"  !CDS_PN = "CP77";
"VSS785":   PN = "CP8"  !CDS_PN = "CP8";
"VSS786":   PN = "CP83"  !CDS_PN = "CP83";
"VSS787":   PN = "CP87"  !CDS_PN = "CP87";
"VSS788":   PN = "CP91"  !CDS_PN = "CP91";
"VSS789":   PN = "CR1"  !CDS_PN = "CR1";
"VSS790":   PN = "CR11"  !CDS_PN = "CR11";
"VSS792":   PN = "CR13"  !CDS_PN = "CR13";
"VSS793":   PN = "CR17"  !CDS_PN = "CR17";
"VSS794":   PN = "CR5"  !CDS_PN = "CR5";
"VSS795":   PN = "CR62"  !CDS_PN = "CR62";
"VSS796":   PN = "CR64"  !CDS_PN = "CR64";
"VSS797":   PN = "CR84"  !CDS_PN = "CR84";
"VSS800":   PN = "CR88"  !CDS_PN = "CR88";
"VSS801":   PN = "CR9"  !CDS_PN = "CR9";
"VSS803":   PN = "CR90"  !CDS_PN = "CR90";
"VSS804":   PN = "CT10"  !CDS_PN = "CT10";
"VSS805":   PN = "CT12"  !CDS_PN = "CT12";
"VSS810":   PN = "CT69"  !CDS_PN = "CT69";
"VSS811":   PN = "CT73"  !CDS_PN = "CT73";
"VSS812":   PN = "CT81"  !CDS_PN = "CT81";
"VSS813":   PN = "CU19"  !CDS_PN = "CU19";
"VSS814":   PN = "CU21"  !CDS_PN = "CU21";
"VSS815":   PN = "CU23"  !CDS_PN = "CU23";
"VSS816":   PN = "CU60"  !CDS_PN = "CU60";
"VSS818":   PN = "CU66"  !CDS_PN = "CU66";
"VSS819":   PN = "CU68"  !CDS_PN = "CU68";
"VSS822":   PN = "CU84"  !CDS_PN = "CU84";
"VSS823":   PN = "CU88"  !CDS_PN = "CU88";
"VSS824":   PN = "CV12"  !CDS_PN = "CV12";
"VSS825":   PN = "CV4"  !CDS_PN = "CV4";
"VSS826":   PN = "CV75"  !CDS_PN = "CV75";
"VSS827":   PN = "CV8"  !CDS_PN = "CV8";
"VSS828":   PN = "CV83"  !CDS_PN = "CV83";
"VSS831":   PN = "CV87"  !CDS_PN = "CV87";
"VSS833":   PN = "CV91"  !CDS_PN = "CV91";
"VSS834":   PN = "CW1"  !CDS_PN = "CW1";
"VSS836":   PN = "CW13"  !CDS_PN = "CW13";
"VSS837":   PN = "CW17"  !CDS_PN = "CW17";
"VSS838":   PN = "CW5"  !CDS_PN = "CW5";
"VSS840":   PN = "CW72"  !CDS_PN = "CW72";
"VSS843":   PN = "CW78"  !CDS_PN = "CW78";
"VSS846":   PN = "CW84"  !CDS_PN = "CW84";
"VSS848":   PN = "CW88"  !CDS_PN = "CW88";
"VSS850":   PN = "CW9"  !CDS_PN = "CW9";
"VSS851":   PN = "CY12"  !CDS_PN = "CY12";
"VSS852":   PN = "CY16"  !CDS_PN = "CY16";
"VSS853":   PN = "CY18"  !CDS_PN = "CY18";
"VSS854":   PN = "CY26"  !CDS_PN = "CY26";
"VSS855":   PN = "CY30"  !CDS_PN = "CY30";
"VSS856":   PN = "CY63"  !CDS_PN = "CY63";
"VSS858":   PN = "CY73"  !CDS_PN = "CY73";
"VSS859":   PN = "CY77"  !CDS_PN = "CY77";
"VSS860":   PN = "CY8"  !CDS_PN = "CY8";
"VSS862":   PN = "CY81"  !CDS_PN = "CY81";
"VSS863":   PN = "CY83"  !CDS_PN = "CY83";
"VSS910":   PN = "DA19"  !CDS_PN = "DA19";
"VSS911":   PN = "DA23"  !CDS_PN = "DA23";
"VSS912":   PN = "DA25"  !CDS_PN = "DA25";
"VSS913":   PN = "DA29"  !CDS_PN = "DA29";
"VSS914":   PN = "DA31"  !CDS_PN = "DA31";
"VSS915":   PN = "DA33"  !CDS_PN = "DA33";
"VSS916":   PN = "DA35"  !CDS_PN = "DA35";
"VSS917":   PN = "DA37"  !CDS_PN = "DA37";
"VSS918":   PN = "DA41"  !CDS_PN = "DA41";
"VSS919":   PN = "DA48"  !CDS_PN = "DA48";
"VSS920":   PN = "DA50"  !CDS_PN = "DA50";
"VSS921":   PN = "DA54"  !CDS_PN = "DA54";
"VSS922":   PN = "DA56"  !CDS_PN = "DA56";
"VSS923":   PN = "DA58"  !CDS_PN = "DA58";
"VSS924":   PN = "DA60"  !CDS_PN = "DA60";
"VSS925":   PN = "DA62"  !CDS_PN = "DA62";
"VSS926":   PN = "DA66"  !CDS_PN = "DA66";
"VSS927":   PN = "DA72"  !CDS_PN = "DA72";
"VSS928":   PN = "DA74"  !CDS_PN = "DA74";
"VSS929":   PN = "DA80"  !CDS_PN = "DA80";
"VSS930":   PN = "DA82"  !CDS_PN = "DA82";
"VSS931":   PN = "DA84"  !CDS_PN = "DA84";
"VSS932":   PN = "DA88"  !CDS_PN = "DA88";
"VSS933":   PN = "DB12"  !CDS_PN = "DB12";
"VSS935":   PN = "DB22"  !CDS_PN = "DB22";
"VSS936":   PN = "DB28"  !CDS_PN = "DB28";
"VSS937":   PN = "DB32"  !CDS_PN = "DB32";
"VSS938":   PN = "DB38"  !CDS_PN = "DB38";
"VSS939":   PN = "DB4"  !CDS_PN = "DB4";
"VSS940":   PN = "DB40"  !CDS_PN = "DB40";
"VSS941":   PN = "DB47"  !CDS_PN = "DB47";
"VSS942":   PN = "DB57"  !CDS_PN = "DB57";
"VSS943":   PN = "DB65"  !CDS_PN = "DB65";
"VSS944":   PN = "DB71"  !CDS_PN = "DB71";
"VSS946":   PN = "DB77"  !CDS_PN = "DB77";
"VSS947":   PN = "DB8"  !CDS_PN = "DB8";
"VSS948":   PN = "DB87"  !CDS_PN = "DB87";
BODY = "SOCKET4677_AZIF0045P001C01CS","I8": LOCATION = "U1" #&CDS_LOCATION = "U1" &SEC = "36" #&CDS_SEC = "36";
"VSS383":   PN = "CJ76"  !CDS_PN = "CJ76";
"VSS396":   PN = "CK4"  !CDS_PN = "CK4";
"VSS542":   PN = "BR35"  !CDS_PN = "BR35";
"VSS543":   PN = "BR37"  !CDS_PN = "BR37";
"VSS545":   PN = "BR39"  !CDS_PN = "BR39";
"VSS546":   PN = "BR41"  !CDS_PN = "BR41";
"VSS547":   PN = "BR43"  !CDS_PN = "BR43";
"VSS548":   PN = "BR45"  !CDS_PN = "BR45";
"VSS549":   PN = "BR48"  !CDS_PN = "BR48";
"VSS550":   PN = "BR50"  !CDS_PN = "BR50";
"VSS551":   PN = "BR52"  !CDS_PN = "BR52";
"VSS552":   PN = "BR54"  !CDS_PN = "BR54";
"VSS555":   PN = "BR56"  !CDS_PN = "BR56";
"VSS556":   PN = "BR58"  !CDS_PN = "BR58";
"VSS557":   PN = "BR64"  !CDS_PN = "BR64";
"VSS559":   PN = "BR66"  !CDS_PN = "BR66";
"VSS560":   PN = "BR68"  !CDS_PN = "BR68";
"VSS561":   PN = "BR70"  !CDS_PN = "BR70";
"VSS563":   PN = "BR72"  !CDS_PN = "BR72";
"VSS564":   PN = "BR74"  !CDS_PN = "BR74";
"VSS565":   PN = "BR76"  !CDS_PN = "BR76";
"VSS566":   PN = "BR80"  !CDS_PN = "BR80";
"VSS567":   PN = "BR82"  !CDS_PN = "BR82";
"VSS568":   PN = "BR84"  !CDS_PN = "BR84";
"VSS569":   PN = "BR86"  !CDS_PN = "BR86";
"VSS570":   PN = "BR88"  !CDS_PN = "BR88";
"VSS573":   PN = "BR90"  !CDS_PN = "BR90";
"VSS574":   PN = "BT12"  !CDS_PN = "BT12";
"VSS575":   PN = "BT16"  !CDS_PN = "BT16";
"VSS576":   PN = "BT20"  !CDS_PN = "BT20";
"VSS577":   PN = "BT4"  !CDS_PN = "BT4";
"VSS578":   PN = "BT8"  !CDS_PN = "BT8";
"VSS579":   PN = "BU15"  !CDS_PN = "BU15";
"VSS580":   PN = "BU19"  !CDS_PN = "BU19";
"VSS581":   PN = "BU21"  !CDS_PN = "BU21";
"VSS582":   PN = "BU23"  !CDS_PN = "BU23";
"VSS584":   PN = "BU25"  !CDS_PN = "BU25";
"VSS585":   PN = "BU31"  !CDS_PN = "BU31";
"VSS586":   PN = "BU7"  !CDS_PN = "BU7";
"VSS587":   PN = "BV12"  !CDS_PN = "BV12";
"VSS588":   PN = "BV16"  !CDS_PN = "BV16";
"VSS589":   PN = "BV18"  !CDS_PN = "BV18";
"VSS590":   PN = "BV2"  !CDS_PN = "BV2";
"VSS591":   PN = "BV20"  !CDS_PN = "BV20";
"VSS592":   PN = "BV4"  !CDS_PN = "BV4";
"VSS593":   PN = "BV6"  !CDS_PN = "BV6";
"VSS594":   PN = "BV8"  !CDS_PN = "BV8";
"VSS596":   PN = "BW13"  !CDS_PN = "BW13";
"VSS597":   PN = "BW17"  !CDS_PN = "BW17";
"VSS598":   PN = "BW27"  !CDS_PN = "BW27";
"VSS599":   PN = "BW29"  !CDS_PN = "BW29";
"VSS600":   PN = "BW3"  !CDS_PN = "BW3";
"VSS601":   PN = "BW31"  !CDS_PN = "BW31";
"VSS602":   PN = "BW5"  !CDS_PN = "BW5";
"VSS603":   PN = "BW9"  !CDS_PN = "BW9";
"VSS604":   PN = "BY12"  !CDS_PN = "BY12";
"VSS605":   PN = "BY16"  !CDS_PN = "BY16";
"VSS606":   PN = "BY20"  !CDS_PN = "BY20";
"VSS607":   PN = "BY4"  !CDS_PN = "BY4";
"VSS608":   PN = "BY8"  !CDS_PN = "BY8";
"VSS620":   PN = "CA3"  !CDS_PN = "CA3";
"VSS621":   PN = "CA31"  !CDS_PN = "CA31";
"VSS622":   PN = "CB12"  !CDS_PN = "CB12";
"VSS623":   PN = "CB16"  !CDS_PN = "CB16";
"VSS624":   PN = "CB20"  !CDS_PN = "CB20";
"VSS625":   PN = "CB22"  !CDS_PN = "CB22";
"VSS626":   PN = "CB24"  !CDS_PN = "CB24";
"VSS627":   PN = "CB26"  !CDS_PN = "CB26";
"VSS628":   PN = "CB28"  !CDS_PN = "CB28";
"VSS629":   PN = "CB32"  !CDS_PN = "CB32";
"VSS630":   PN = "CB34"  !CDS_PN = "CB34";
"VSS631":   PN = "CB36"  !CDS_PN = "CB36";
"VSS632":   PN = "CB38"  !CDS_PN = "CB38";
"VSS633":   PN = "CB4"  !CDS_PN = "CB4";
"VSS634":   PN = "CB40"  !CDS_PN = "CB40";
"VSS635":   PN = "CB42"  !CDS_PN = "CB42";
"VSS636":   PN = "CB44"  !CDS_PN = "CB44";
"VSS637":   PN = "CB47"  !CDS_PN = "CB47";
"VSS638":   PN = "CB49"  !CDS_PN = "CB49";
"VSS639":   PN = "CB51"  !CDS_PN = "CB51";
"VSS640":   PN = "CB53"  !CDS_PN = "CB53";
"VSS641":   PN = "CB55"  !CDS_PN = "CB55";
"VSS642":   PN = "CB57"  !CDS_PN = "CB57";
"VSS643":   PN = "CB59"  !CDS_PN = "CB59";
"VSS644":   PN = "CB63"  !CDS_PN = "CB63";
"VSS645":   PN = "CB65"  !CDS_PN = "CB65";
"VSS646":   PN = "CB67"  !CDS_PN = "CB67";
"VSS647":   PN = "CB69"  !CDS_PN = "CB69";
"VSS648":   PN = "CB71"  !CDS_PN = "CB71";
"VSS649":   PN = "CB73"  !CDS_PN = "CB73";
"VSS650":   PN = "CB79"  !CDS_PN = "CB79";
"VSS651":   PN = "CB8"  !CDS_PN = "CB8";
"VSS652":   PN = "CB81"  !CDS_PN = "CB81";
"VSS653":   PN = "CB83"  !CDS_PN = "CB83";
"VSS654":   PN = "CB85"  !CDS_PN = "CB85";
"VSS655":   PN = "CB87"  !CDS_PN = "CB87";
"VSS656":   PN = "CB89"  !CDS_PN = "CB89";
"VSS660":   PN = "CC13"  !CDS_PN = "CC13";
"VSS661":   PN = "CC17"  !CDS_PN = "CC17";
"VSS664":   PN = "CC31"  !CDS_PN = "CC31";
"VSS665":   PN = "CC5"  !CDS_PN = "CC5";
"VSS666":   PN = "CC62"  !CDS_PN = "CC62";
"VSS667":   PN = "CC70"  !CDS_PN = "CC70";
"VSS668":   PN = "CC72"  !CDS_PN = "CC72";
"VSS669":   PN = "CC74"  !CDS_PN = "CC74";
"VSS670":   PN = "CC9"  !CDS_PN = "CC9";
"VSS671":   PN = "CD12"  !CDS_PN = "CD12";
"VSS672":   PN = "CD16"  !CDS_PN = "CD16";
"VSS673":   PN = "CD20"  !CDS_PN = "CD20";
"VSS674":   PN = "CD4"  !CDS_PN = "CD4";
"VSS675":   PN = "CD61"  !CDS_PN = "CD61";
"VSS676":   PN = "CD75"  !CDS_PN = "CD75";
"VSS677":   PN = "CD77"  !CDS_PN = "CD77";
"VSS678":   PN = "CD8"  !CDS_PN = "CD8";
"VSS680":   PN = "CE3"  !CDS_PN = "CE3";
"VSS681":   PN = "CE60"  !CDS_PN = "CE60";
"VSS682":   PN = "CE66"  !CDS_PN = "CE66";
"VSS683":   PN = "CE72"  !CDS_PN = "CE72";
"VSS684":   PN = "CE76"  !CDS_PN = "CE76";
"VSS685":   PN = "CE78"  !CDS_PN = "CE78";
"VSS686":   PN = "CF12"  !CDS_PN = "CF12";
"VSS687":   PN = "CF16"  !CDS_PN = "CF16";
"VSS688":   PN = "CF20"  !CDS_PN = "CF20";
"VSS689":   PN = "CF4"  !CDS_PN = "CF4";
"VSS691":   PN = "CF69"  !CDS_PN = "CF69";
"VSS692":   PN = "CF71"  !CDS_PN = "CF71";
"VSS693":   PN = "CF8"  !CDS_PN = "CF8";
"VSS694":   PN = "CG1"  !CDS_PN = "CG1";
"VSS695":   PN = "CG13"  !CDS_PN = "CG13";
"VSS696":   PN = "CG17"  !CDS_PN = "CG17";
"VSS697":   PN = "CG21"  !CDS_PN = "CG21";
"VSS698":   PN = "CG23"  !CDS_PN = "CG23";
"VSS701":   PN = "CG25"  !CDS_PN = "CG25";
"VSS703":   PN = "CG5"  !CDS_PN = "CG5";
"VSS704":   PN = "CG62"  !CDS_PN = "CG62";
"VSS706":   PN = "CG64"  !CDS_PN = "CG64";
"VSS707":   PN = "CG70"  !CDS_PN = "CG70";
"VSS708":   PN = "CG72"  !CDS_PN = "CG72";
"VSS710":   PN = "CG74"  !CDS_PN = "CG74";
"VSS713":   PN = "CG78"  !CDS_PN = "CG78";
"VSS716":   PN = "CG9"  !CDS_PN = "CG9";
"VSS718":   PN = "CH12"  !CDS_PN = "CH12";
"VSS720":   PN = "CH16"  !CDS_PN = "CH16";
"VSS721":   PN = "CH20"  !CDS_PN = "CH20";
"VSS722":   PN = "CH4"  !CDS_PN = "CH4";
"VSS727":   PN = "CH67"  !CDS_PN = "CH67";
"VSS728":   PN = "CH73"  !CDS_PN = "CH73";
"VSS729":   PN = "CH79"  !CDS_PN = "CH79";
"VSS730":   PN = "CH8"  !CDS_PN = "CH8";
"VSS731":   PN = "CH83"  !CDS_PN = "CH83";
"VSS732":   PN = "CH85"  !CDS_PN = "CH85";
"VSS733":   PN = "CH87"  !CDS_PN = "CH87";
"VSS734":   PN = "CH89"  !CDS_PN = "CH89";
"VSS736":   PN = "CJ60"  !CDS_PN = "CJ60";
"VSS737":   PN = "CJ80"  !CDS_PN = "CJ80";
"VSS740":   PN = "CK12"  !CDS_PN = "CK12";
"VSS741":   PN = "CK16"  !CDS_PN = "CK16";
"VSS742":   PN = "CK20"  !CDS_PN = "CK20";
"VSS743":   PN = "CK26"  !CDS_PN = "CK26";
"VSS746":   PN = "CK8"  !CDS_PN = "CK8";
DRAWING = "@s9s_mb_2u_lib.s9s_mb_2u(sch_1):page72";
BODY = "SOCKET4677_AZIF0045P001C01CS","I2": LOCATION = "U1" #&CDS_LOCATION = "U1" &SEC = "37" #&CDS_SEC = "37";
"VSS0":   PN = "BR5"  !CDS_PN = "BR5";
"VSS356":   PN = "AW21"  !CDS_PN = "AW21";
"VSS357":   PN = "AW23"  !CDS_PN = "AW23";
"VSS358":   PN = "AW25"  !CDS_PN = "AW25";
"VSS360":   PN = "AW62"  !CDS_PN = "AW62";
"VSS361":   PN = "AW66"  !CDS_PN = "AW66";
"VSS362":   PN = "AW68"  !CDS_PN = "AW68";
"VSS363":   PN = "AW72"  !CDS_PN = "AW72";
"VSS364":   PN = "AW80"  !CDS_PN = "AW80";
"VSS365":   PN = "AW82"  !CDS_PN = "AW82";
"VSS366":   PN = "AW84"  !CDS_PN = "AW84";
"VSS367":   PN = "AW88"  !CDS_PN = "AW88";
"VSS369":   PN = "AY12"  !CDS_PN = "AY12";
"VSS370":   PN = "AY16"  !CDS_PN = "AY16";
"VSS371":   PN = "AY4"  !CDS_PN = "AY4";
"VSS372":   PN = "AY71"  !CDS_PN = "AY71";
"VSS373":   PN = "AY77"  !CDS_PN = "AY77";
"VSS374":   PN = "AY79"  !CDS_PN = "AY79";
"VSS375":   PN = "AY8"  !CDS_PN = "AY8";
"VSS376":   PN = "AY81"  !CDS_PN = "AY81";
"VSS377":   PN = "AY83"  !CDS_PN = "AY83";
"VSS393":   PN = "BA17"  !CDS_PN = "BA17";
"VSS394":   PN = "BA60"  !CDS_PN = "BA60";
"VSS395":   PN = "BA64"  !CDS_PN = "BA64";
"VSS397":   PN = "BA74"  !CDS_PN = "BA74";
"VSS398":   PN = "BA84"  !CDS_PN = "BA84";
"VSS399":   PN = "BA88"  !CDS_PN = "BA88";
"VSS400":   PN = "BB10"  !CDS_PN = "BB10";
"VSS401":   PN = "BB12"  !CDS_PN = "BB12";
"VSS402":   PN = "BB16"  !CDS_PN = "BB16";
"VSS403":   PN = "BB20"  !CDS_PN = "BB20";
"VSS404":   PN = "BB22"  !CDS_PN = "BB22";
"VSS405":   PN = "BB24"  !CDS_PN = "BB24";
"VSS406":   PN = "BB26"  !CDS_PN = "BB26";
"VSS407":   PN = "BB4"  !CDS_PN = "BB4";
"VSS408":   PN = "BB63"  !CDS_PN = "BB63";
"VSS409":   PN = "BB69"  !CDS_PN = "BB69";
"VSS410":   PN = "BB71"  !CDS_PN = "BB71";
"VSS411":   PN = "BB77"  !CDS_PN = "BB77";
"VSS412":   PN = "BB79"  !CDS_PN = "BB79";
"VSS413":   PN = "BB8"  !CDS_PN = "BB8";
"VSS414":   PN = "BB83"  !CDS_PN = "BB83";
"VSS415":   PN = "BB87"  !CDS_PN = "BB87";
"VSS416":   PN = "BB91"  !CDS_PN = "BB91";
"VSS417":   PN = "BC1"  !CDS_PN = "BC1";
"VSS418":   PN = "BC13"  !CDS_PN = "BC13";
"VSS419":   PN = "BC17"  !CDS_PN = "BC17";
"VSS420":   PN = "BC5"  !CDS_PN = "BC5";
"VSS421":   PN = "BC62"  !CDS_PN = "BC62";
"VSS422":   PN = "BC66"  !CDS_PN = "BC66";
"VSS423":   PN = "BC72"  !CDS_PN = "BC72";
"VSS424":   PN = "BC76"  !CDS_PN = "BC76";
"VSS425":   PN = "BC78"  !CDS_PN = "BC78";
"VSS426":   PN = "BC84"  !CDS_PN = "BC84";
"VSS427":   PN = "BC86"  !CDS_PN = "BC86";
"VSS428":   PN = "BC88"  !CDS_PN = "BC88";
"VSS429":   PN = "BC9"  !CDS_PN = "BC9";
"VSS430":   PN = "BD12"  !CDS_PN = "BD12";
"VSS431":   PN = "BD16"  !CDS_PN = "BD16";
"VSS432":   PN = "BD20"  !CDS_PN = "BD20";
"VSS433":   PN = "BD4"  !CDS_PN = "BD4";
"VSS434":   PN = "BD8"  !CDS_PN = "BD8";
"VSS435":   PN = "BD81"  !CDS_PN = "BD81";
"VSS437":   PN = "BD85"  !CDS_PN = "BD85";
"VSS439":   PN = "BD89"  !CDS_PN = "BD89";
"VSS440":   PN = "BE64"  !CDS_PN = "BE64";
"VSS441":   PN = "BE66"  !CDS_PN = "BE66";
"VSS442":   PN = "BE68"  !CDS_PN = "BE68";
"VSS443":   PN = "BE74"  !CDS_PN = "BE74";
"VSS444":   PN = "BE76"  !CDS_PN = "BE76";
"VSS445":   PN = "BE78"  !CDS_PN = "BE78";
"VSS446":   PN = "BE84"  !CDS_PN = "BE84";
"VSS447":   PN = "BF12"  !CDS_PN = "BF12";
"VSS448":   PN = "BF16"  !CDS_PN = "BF16";
"VSS449":   PN = "BF20"  !CDS_PN = "BF20";
"VSS450":   PN = "BF4"  !CDS_PN = "BF4";
"VSS451":   PN = "BF61"  !CDS_PN = "BF61";
"VSS452":   PN = "BF63"  !CDS_PN = "BF63";
"VSS453":   PN = "BF73"  !CDS_PN = "BF73";
"VSS454":   PN = "BF75"  !CDS_PN = "BF75";
"VSS455":   PN = "BF79"  !CDS_PN = "BF79";
"VSS456":   PN = "BF8"  !CDS_PN = "BF8";
"VSS457":   PN = "BF83"  !CDS_PN = "BF83";
"VSS458":   PN = "BG1"  !CDS_PN = "BG1";
"VSS459":   PN = "BG13"  !CDS_PN = "BG13";
"VSS460":   PN = "BG17"  !CDS_PN = "BG17";
"VSS461":   PN = "BG21"  !CDS_PN = "BG21";
"VSS462":   PN = "BG23"  !CDS_PN = "BG23";
"VSS463":   PN = "BG25"  !CDS_PN = "BG25";
"VSS464":   PN = "BG5"  !CDS_PN = "BG5";
"VSS465":   PN = "BG70"  !CDS_PN = "BG70";
"VSS466":   PN = "BG9"  !CDS_PN = "BG9";
"VSS467":   PN = "BH12"  !CDS_PN = "BH12";
"VSS468":   PN = "BH16"  !CDS_PN = "BH16";
"VSS469":   PN = "BH20"  !CDS_PN = "BH20";
"VSS470":   PN = "BH4"  !CDS_PN = "BH4";
"VSS472":   PN = "BH67"  !CDS_PN = "BH67";
"VSS473":   PN = "BH73"  !CDS_PN = "BH73";
"VSS474":   PN = "BH77"  !CDS_PN = "BH77";
"VSS475":   PN = "BH8"  !CDS_PN = "BH8";
"VSS476":   PN = "BH81"  !CDS_PN = "BH81";
"VSS477":   PN = "BH83"  !CDS_PN = "BH83";
"VSS479":   PN = "BJ62"  !CDS_PN = "BJ62";
"VSS480":   PN = "BJ68"  !CDS_PN = "BJ68";
"VSS481":   PN = "BJ80"  !CDS_PN = "BJ80";
"VSS482":   PN = "BJ82"  !CDS_PN = "BJ82";
"VSS483":   PN = "BJ84"  !CDS_PN = "BJ84";
"VSS484":   PN = "BJ86"  !CDS_PN = "BJ86";
"VSS485":   PN = "BJ88"  !CDS_PN = "BJ88";
"VSS486":   PN = "BJ90"  !CDS_PN = "BJ90";
"VSS487":   PN = "BK12"  !CDS_PN = "BK12";
"VSS488":   PN = "BK16"  !CDS_PN = "BK16";
"VSS489":   PN = "BK20"  !CDS_PN = "BK20";
"VSS490":   PN = "BK4"  !CDS_PN = "BK4";
"VSS491":   PN = "BK65"  !CDS_PN = "BK65";
"VSS492":   PN = "BK71"  !CDS_PN = "BK71";
"VSS494":   PN = "BK75"  !CDS_PN = "BK75";
"VSS495":   PN = "BK79"  !CDS_PN = "BK79";
"VSS496":   PN = "BK8"  !CDS_PN = "BK8";
"VSS497":   PN = "BL1"  !CDS_PN = "BL1";
"VSS498":   PN = "BL13"  !CDS_PN = "BL13";
"VSS499":   PN = "BL17"  !CDS_PN = "BL17";
"VSS500":   PN = "BL5"  !CDS_PN = "BL5";
"VSS501":   PN = "BL68"  !CDS_PN = "BL68";
"VSS502":   PN = "BL70"  !CDS_PN = "BL70";
"VSS503":   PN = "BL72"  !CDS_PN = "BL72";
"VSS504":   PN = "BL78"  !CDS_PN = "BL78";
"VSS505":   PN = "BL9"  !CDS_PN = "BL9";
"VSS506":   PN = "BM12"  !CDS_PN = "BM12";
"VSS507":   PN = "BM16"  !CDS_PN = "BM16";
"VSS508":   PN = "BM20"  !CDS_PN = "BM20";
"VSS509":   PN = "BM22"  !CDS_PN = "BM22";
"VSS510":   PN = "BM24"  !CDS_PN = "BM24";
"VSS511":   PN = "BM26"  !CDS_PN = "BM26";
"VSS512":   PN = "BM4"  !CDS_PN = "BM4";
"VSS513":   PN = "BM61"  !CDS_PN = "BM61";
"VSS515":   PN = "BM73"  !CDS_PN = "BM73";
"VSS516":   PN = "BM77"  !CDS_PN = "BM77";
"VSS517":   PN = "BM8"  !CDS_PN = "BM8";
"VSS518":   PN = "BN31"  !CDS_PN = "BN31";
"VSS519":   PN = "BN62"  !CDS_PN = "BN62";
"VSS520":   PN = "BN70"  !CDS_PN = "BN70";
"VSS522":   PN = "BP12"  !CDS_PN = "BP12";
"VSS523":   PN = "BP16"  !CDS_PN = "BP16";
"VSS524":   PN = "BP2"  !CDS_PN = "BP2";
"VSS525":   PN = "BP20"  !CDS_PN = "BP20";
"VSS527":   PN = "BP4"  !CDS_PN = "BP4";
"VSS528":   PN = "BP63"  !CDS_PN = "BP63";
"VSS529":   PN = "BP71"  !CDS_PN = "BP71";
"VSS530":   PN = "BP73"  !CDS_PN = "BP73";
"VSS531":   PN = "BP75"  !CDS_PN = "BP75";
"VSS532":   PN = "BP77"  !CDS_PN = "BP77";
"VSS533":   PN = "BP8"  !CDS_PN = "BP8";
"VSS535":   PN = "BR13"  !CDS_PN = "BR13";
"VSS536":   PN = "BR17"  !CDS_PN = "BR17";
"VSS538":   PN = "BR27"  !CDS_PN = "BR27";
"VSS539":   PN = "BR29"  !CDS_PN = "BR29";
"VSS540":   PN = "BR31"  !CDS_PN = "BR31";
"VSS541":   PN = "BR33"  !CDS_PN = "BR33";
"VSS572":   PN = "BR9"  !CDS_PN = "BR9";
BODY = "SOCKET4677_AZIF0045P001C01CS","I5": LOCATION = "U1" #&CDS_LOCATION = "U1" &SEC = "38" #&CDS_SEC = "38";
"VSS198":   PN = "AK12"  !CDS_PN = "AK12";
"VSS199":   PN = "AK16"  !CDS_PN = "AK16";
"VSS200":   PN = "AK18"  !CDS_PN = "AK18";
"VSS201":   PN = "AK24"  !CDS_PN = "AK24";
"VSS202":   PN = "AK30"  !CDS_PN = "AK30";
"VSS203":   PN = "AK36"  !CDS_PN = "AK36";
"VSS204":   PN = "AK4"  !CDS_PN = "AK4";
"VSS205":   PN = "AK42"  !CDS_PN = "AK42";
"VSS206":   PN = "AK49"  !CDS_PN = "AK49";
"VSS207":   PN = "AK55"  !CDS_PN = "AK55";
"VSS208":   PN = "AK61"  !CDS_PN = "AK61";
"VSS209":   PN = "AK67"  !CDS_PN = "AK67";
"VSS210":   PN = "AK73"  !CDS_PN = "AK73";
"VSS211":   PN = "AK79"  !CDS_PN = "AK79";
"VSS212":   PN = "AK8"  !CDS_PN = "AK8";
"VSS213":   PN = "AK81"  !CDS_PN = "AK81";
"VSS214":   PN = "AK83"  !CDS_PN = "AK83";
"VSS215":   PN = "AK87"  !CDS_PN = "AK87";
"VSS216":   PN = "AK91"  !CDS_PN = "AK91";
"VSS217":   PN = "AL1"  !CDS_PN = "AL1";
"VSS218":   PN = "AL13"  !CDS_PN = "AL13";
"VSS219":   PN = "AL17"  !CDS_PN = "AL17";
"VSS220":   PN = "AL5"  !CDS_PN = "AL5";
"VSS221":   PN = "AL52"  !CDS_PN = "AL52";
"VSS222":   PN = "AL80"  !CDS_PN = "AL80";
"VSS223":   PN = "AL82"  !CDS_PN = "AL82";
"VSS224":   PN = "AL84"  !CDS_PN = "AL84";
"VSS225":   PN = "AL88"  !CDS_PN = "AL88";
"VSS226":   PN = "AL9"  !CDS_PN = "AL9";
"VSS227":   PN = "AM12"  !CDS_PN = "AM12";
"VSS228":   PN = "AM16"  !CDS_PN = "AM16";
"VSS229":   PN = "AM18"  !CDS_PN = "AM18";
"VSS230":   PN = "AM20"  !CDS_PN = "AM20";
"VSS231":   PN = "AM22"  !CDS_PN = "AM22";
"VSS232":   PN = "AM24"  !CDS_PN = "AM24";
"VSS233":   PN = "AM26"  !CDS_PN = "AM26";
"VSS234":   PN = "AM28"  !CDS_PN = "AM28";
"VSS235":   PN = "AM30"  !CDS_PN = "AM30";
"VSS236":   PN = "AM32"  !CDS_PN = "AM32";
"VSS237":   PN = "AM34"  !CDS_PN = "AM34";
"VSS238":   PN = "AM36"  !CDS_PN = "AM36";
"VSS239":   PN = "AM38"  !CDS_PN = "AM38";
"VSS240":   PN = "AM4"  !CDS_PN = "AM4";
"VSS241":   PN = "AM40"  !CDS_PN = "AM40";
"VSS242":   PN = "AM42"  !CDS_PN = "AM42";
"VSS243":   PN = "AM44"  !CDS_PN = "AM44";
"VSS244":   PN = "AM47"  !CDS_PN = "AM47";
"VSS245":   PN = "AM49"  !CDS_PN = "AM49";
"VSS246":   PN = "AM51"  !CDS_PN = "AM51";
"VSS247":   PN = "AM53"  !CDS_PN = "AM53";
"VSS248":   PN = "AM55"  !CDS_PN = "AM55";
"VSS249":   PN = "AM57"  !CDS_PN = "AM57";
"VSS250":   PN = "AM59"  !CDS_PN = "AM59";
"VSS251":   PN = "AM61"  !CDS_PN = "AM61";
"VSS252":   PN = "AM63"  !CDS_PN = "AM63";
"VSS253":   PN = "AM65"  !CDS_PN = "AM65";
"VSS254":   PN = "AM67"  !CDS_PN = "AM67";
"VSS255":   PN = "AM69"  !CDS_PN = "AM69";
"VSS256":   PN = "AM71"  !CDS_PN = "AM71";
"VSS257":   PN = "AM73"  !CDS_PN = "AM73";
"VSS258":   PN = "AM75"  !CDS_PN = "AM75";
"VSS259":   PN = "AM77"  !CDS_PN = "AM77";
"VSS260":   PN = "AM8"  !CDS_PN = "AM8";
"VSS261":   PN = "AN52"  !CDS_PN = "AN52";
"VSS262":   PN = "AN84"  !CDS_PN = "AN84";
"VSS263":   PN = "AN88"  !CDS_PN = "AN88";
"VSS264":   PN = "AP12"  !CDS_PN = "AP12";
"VSS265":   PN = "AP16"  !CDS_PN = "AP16";
"VSS266":   PN = "AP18"  !CDS_PN = "AP18";
"VSS267":   PN = "AP24"  !CDS_PN = "AP24";
"VSS268":   PN = "AP30"  !CDS_PN = "AP30";
"VSS269":   PN = "AP36"  !CDS_PN = "AP36";
"VSS270":   PN = "AP4"  !CDS_PN = "AP4";
"VSS271":   PN = "AP42"  !CDS_PN = "AP42";
"VSS272":   PN = "AP49"  !CDS_PN = "AP49";
"VSS273":   PN = "AP55"  !CDS_PN = "AP55";
"VSS274":   PN = "AP61"  !CDS_PN = "AP61";
"VSS275":   PN = "AP67"  !CDS_PN = "AP67";
"VSS276":   PN = "AP73"  !CDS_PN = "AP73";
"VSS277":   PN = "AP79"  !CDS_PN = "AP79";
"VSS278":   PN = "AP8"  !CDS_PN = "AP8";
"VSS279":   PN = "AP83"  !CDS_PN = "AP83";
"VSS280":   PN = "AP87"  !CDS_PN = "AP87";
"VSS281":   PN = "AP91"  !CDS_PN = "AP91";
"VSS282":   PN = "AR1"  !CDS_PN = "AR1";
"VSS283":   PN = "AR13"  !CDS_PN = "AR13";
"VSS284":   PN = "AR19"  !CDS_PN = "AR19";
"VSS285":   PN = "AR23"  !CDS_PN = "AR23";
"VSS286":   PN = "AR25"  !CDS_PN = "AR25";
"VSS287":   PN = "AR29"  !CDS_PN = "AR29";
"VSS288":   PN = "AR31"  !CDS_PN = "AR31";
"VSS289":   PN = "AR35"  !CDS_PN = "AR35";
"VSS290":   PN = "AR37"  !CDS_PN = "AR37";
"VSS291":   PN = "AR41"  !CDS_PN = "AR41";
"VSS292":   PN = "AR43"  !CDS_PN = "AR43";
"VSS293":   PN = "AR48"  !CDS_PN = "AR48";
"VSS294":   PN = "AR5"  !CDS_PN = "AR5";
"VSS295":   PN = "AR50"  !CDS_PN = "AR50";
"VSS296":   PN = "AR54"  !CDS_PN = "AR54";
"VSS297":   PN = "AR56"  !CDS_PN = "AR56";
"VSS298":   PN = "AR60"  !CDS_PN = "AR60";
"VSS299":   PN = "AR62"  !CDS_PN = "AR62";
"VSS300":   PN = "AR66"  !CDS_PN = "AR66";
"VSS301":   PN = "AR68"  !CDS_PN = "AR68";
"VSS302":   PN = "AR72"  !CDS_PN = "AR72";
"VSS303":   PN = "AR74"  !CDS_PN = "AR74";
"VSS304":   PN = "AR78"  !CDS_PN = "AR78";
"VSS305":   PN = "AR82"  !CDS_PN = "AR82";
"VSS306":   PN = "AR84"  !CDS_PN = "AR84";
"VSS307":   PN = "AR88"  !CDS_PN = "AR88";
"VSS308":   PN = "AR9"  !CDS_PN = "AR9";
"VSS309":   PN = "AT12"  !CDS_PN = "AT12";
"VSS310":   PN = "AT16"  !CDS_PN = "AT16";
"VSS311":   PN = "AT20"  !CDS_PN = "AT20";
"VSS312":   PN = "AT22"  !CDS_PN = "AT22";
"VSS313":   PN = "AT26"  !CDS_PN = "AT26";
"VSS314":   PN = "AT28"  !CDS_PN = "AT28";
"VSS315":   PN = "AT32"  !CDS_PN = "AT32";
"VSS316":   PN = "AT34"  !CDS_PN = "AT34";
"VSS317":   PN = "AT38"  !CDS_PN = "AT38";
"VSS318":   PN = "AT4"  !CDS_PN = "AT4";
"VSS319":   PN = "AT40"  !CDS_PN = "AT40";
"VSS320":   PN = "AT44"  !CDS_PN = "AT44";
"VSS321":   PN = "AT51"  !CDS_PN = "AT51";
"VSS322":   PN = "AT53"  !CDS_PN = "AT53";
"VSS323":   PN = "AT57"  !CDS_PN = "AT57";
"VSS324":   PN = "AT59"  !CDS_PN = "AT59";
"VSS325":   PN = "AT63"  !CDS_PN = "AT63";
"VSS326":   PN = "AT65"  !CDS_PN = "AT65";
"VSS327":   PN = "AT69"  !CDS_PN = "AT69";
"VSS328":   PN = "AT71"  !CDS_PN = "AT71";
"VSS329":   PN = "AT75"  !CDS_PN = "AT75";
"VSS330":   PN = "AT77"  !CDS_PN = "AT77";
"VSS331":   PN = "AT79"  !CDS_PN = "AT79";
"VSS332":   PN = "AT8"  !CDS_PN = "AT8";
"VSS333":   PN = "AU27"  !CDS_PN = "AU27";
"VSS334":   PN = "AU31"  !CDS_PN = "AU31";
"VSS335":   PN = "AU37"  !CDS_PN = "AU37";
"VSS336":   PN = "AU39"  !CDS_PN = "AU39";
"VSS337":   PN = "AU41"  !CDS_PN = "AU41";
"VSS338":   PN = "AU45"  !CDS_PN = "AU45";
"VSS339":   PN = "AU48"  !CDS_PN = "AU48";
"VSS340":   PN = "AU70"  !CDS_PN = "AU70";
"VSS341":   PN = "AU72"  !CDS_PN = "AU72";
"VSS342":   PN = "AU74"  !CDS_PN = "AU74";
"VSS343":   PN = "AU76"  !CDS_PN = "AU76";
"VSS344":   PN = "AU80"  !CDS_PN = "AU80";
"VSS345":   PN = "AU84"  !CDS_PN = "AU84";
"VSS346":   PN = "AU88"  !CDS_PN = "AU88";
"VSS347":   PN = "AV12"  !CDS_PN = "AV12";
"VSS348":   PN = "AV16"  !CDS_PN = "AV16";
"VSS349":   PN = "AV4"  !CDS_PN = "AV4";
"VSS350":   PN = "AV77"  !CDS_PN = "AV77";
"VSS351":   PN = "AV8"  !CDS_PN = "AV8";
"VSS352":   PN = "AV87"  !CDS_PN = "AV87";
"VSS353":   PN = "AV91"  !CDS_PN = "AV91";
"VSS354":   PN = "AW1"  !CDS_PN = "AW1";
"VSS355":   PN = "AW13"  !CDS_PN = "AW13";
"VSS359":   PN = "AW5"  !CDS_PN = "AW5";
"VSS368":   PN = "AW9"  !CDS_PN = "AW9";
BODY = "SOCKET4677_AZIF0045P001C01CS","I8": LOCATION = "U1" #&CDS_LOCATION = "U1" &SEC = "39" #&CDS_SEC = "39";
"VSS38":   PN = "AA82"  !CDS_PN = "AA82";
"VSS39":   PN = "AA84"  !CDS_PN = "AA84";
"VSS40":   PN = "AA88"  !CDS_PN = "AA88";
"VSS41":   PN = "AB12"  !CDS_PN = "AB12";
"VSS42":   PN = "AB16"  !CDS_PN = "AB16";
"VSS43":   PN = "AB20"  !CDS_PN = "AB20";
"VSS44":   PN = "AB22"  !CDS_PN = "AB22";
"VSS45":   PN = "AB26"  !CDS_PN = "AB26";
"VSS46":   PN = "AB28"  !CDS_PN = "AB28";
"VSS47":   PN = "AB32"  !CDS_PN = "AB32";
"VSS48":   PN = "AB34"  !CDS_PN = "AB34";
"VSS49":   PN = "AB38"  !CDS_PN = "AB38";
"VSS50":   PN = "AB4"  !CDS_PN = "AB4";
"VSS51":   PN = "AB40"  !CDS_PN = "AB40";
"VSS52":   PN = "AB44"  !CDS_PN = "AB44";
"VSS53":   PN = "AB47"  !CDS_PN = "AB47";
"VSS54":   PN = "AB51"  !CDS_PN = "AB51";
"VSS55":   PN = "AB53"  !CDS_PN = "AB53";
"VSS56":   PN = "AB57"  !CDS_PN = "AB57";
"VSS57":   PN = "AB59"  !CDS_PN = "AB59";
"VSS58":   PN = "AB63"  !CDS_PN = "AB63";
"VSS59":   PN = "AB65"  !CDS_PN = "AB65";
"VSS60":   PN = "AB69"  !CDS_PN = "AB69";
"VSS61":   PN = "AB71"  !CDS_PN = "AB71";
"VSS62":   PN = "AB75"  !CDS_PN = "AB75";
"VSS63":   PN = "AB77"  !CDS_PN = "AB77";
"VSS64":   PN = "AB79"  !CDS_PN = "AB79";
"VSS65":   PN = "AB8"  !CDS_PN = "AB8";
"VSS66":   PN = "AB81"  !CDS_PN = "AB81";
"VSS67":   PN = "AB83"  !CDS_PN = "AB83";
"VSS68":   PN = "AB87"  !CDS_PN = "AB87";
"VSS69":   PN = "AB91"  !CDS_PN = "AB91";
"VSS70":   PN = "AC1"  !CDS_PN = "AC1";
"VSS71":   PN = "AC13"  !CDS_PN = "AC13";
"VSS72":   PN = "AC21"  !CDS_PN = "AC21";
"VSS73":   PN = "AC27"  !CDS_PN = "AC27";
"VSS74":   PN = "AC33"  !CDS_PN = "AC33";
"VSS75":   PN = "AC39"  !CDS_PN = "AC39";
"VSS76":   PN = "AC45"  !CDS_PN = "AC45";
"VSS77":   PN = "AC5"  !CDS_PN = "AC5";
"VSS78":   PN = "AC52"  !CDS_PN = "AC52";
"VSS79":   PN = "AC58"  !CDS_PN = "AC58";
"VSS80":   PN = "AC64"  !CDS_PN = "AC64";
"VSS81":   PN = "AC70"  !CDS_PN = "AC70";
"VSS82":   PN = "AC76"  !CDS_PN = "AC76";
"VSS83":   PN = "AC84"  !CDS_PN = "AC84";
"VSS84":   PN = "AC88"  !CDS_PN = "AC88";
"VSS85":   PN = "AC9"  !CDS_PN = "AC9";
"VSS86":   PN = "AD12"  !CDS_PN = "AD12";
"VSS87":   PN = "AD16"  !CDS_PN = "AD16";
"VSS88":   PN = "AD4"  !CDS_PN = "AD4";
"VSS89":   PN = "AD42"  !CDS_PN = "AD42";
"VSS90":   PN = "AD79"  !CDS_PN = "AD79";
"VSS91":   PN = "AD8"  !CDS_PN = "AD8";
"VSS92":   PN = "AD83"  !CDS_PN = "AD83";
"VSS93":   PN = "AE17"  !CDS_PN = "AE17";
"VSS94":   PN = "AE19"  !CDS_PN = "AE19";
"VSS95":   PN = "AE21"  !CDS_PN = "AE21";
"VSS96":   PN = "AE23"  !CDS_PN = "AE23";
"VSS97":   PN = "AE25"  !CDS_PN = "AE25";
"VSS98":   PN = "AE27"  !CDS_PN = "AE27";
"VSS99":   PN = "AE29"  !CDS_PN = "AE29";
"VSS100":   PN = "AE31"  !CDS_PN = "AE31";
"VSS101":   PN = "AE33"  !CDS_PN = "AE33";
"VSS102":   PN = "AE35"  !CDS_PN = "AE35";
"VSS103":   PN = "AE37"  !CDS_PN = "AE37";
"VSS104":   PN = "AE39"  !CDS_PN = "AE39";
"VSS105":   PN = "AE41"  !CDS_PN = "AE41";
"VSS106":   PN = "AE43"  !CDS_PN = "AE43";
"VSS107":   PN = "AE45"  !CDS_PN = "AE45";
"VSS108":   PN = "AE48"  !CDS_PN = "AE48";
"VSS109":   PN = "AE50"  !CDS_PN = "AE50";
"VSS110":   PN = "AE52"  !CDS_PN = "AE52";
"VSS111":   PN = "AE54"  !CDS_PN = "AE54";
"VSS112":   PN = "AE56"  !CDS_PN = "AE56";
"VSS113":   PN = "AE58"  !CDS_PN = "AE58";
"VSS114":   PN = "AE60"  !CDS_PN = "AE60";
"VSS115":   PN = "AE62"  !CDS_PN = "AE62";
"VSS116":   PN = "AE64"  !CDS_PN = "AE64";
"VSS117":   PN = "AE66"  !CDS_PN = "AE66";
"VSS118":   PN = "AE68"  !CDS_PN = "AE68";
"VSS119":   PN = "AE70"  !CDS_PN = "AE70";
"VSS120":   PN = "AE72"  !CDS_PN = "AE72";
"VSS121":   PN = "AE74"  !CDS_PN = "AE74";
"VSS122":   PN = "AE76"  !CDS_PN = "AE76";
"VSS123":   PN = "AE78"  !CDS_PN = "AE78";
"VSS124":   PN = "AE84"  !CDS_PN = "AE84";
"VSS125":   PN = "AE88"  !CDS_PN = "AE88";
"VSS126":   PN = "AF12"  !CDS_PN = "AF12";
"VSS127":   PN = "AF16"  !CDS_PN = "AF16";
"VSS128":   PN = "AF4"  !CDS_PN = "AF4";
"VSS129":   PN = "AF42"  !CDS_PN = "AF42";
"VSS130":   PN = "AF8"  !CDS_PN = "AF8";
"VSS131":   PN = "AF81"  !CDS_PN = "AF81";
"VSS132":   PN = "AF87"  !CDS_PN = "AF87";
"VSS133":   PN = "AF91"  !CDS_PN = "AF91";
"VSS134":   PN = "AG1"  !CDS_PN = "AG1";
"VSS135":   PN = "AG13"  !CDS_PN = "AG13";
"VSS136":   PN = "AG21"  !CDS_PN = "AG21";
"VSS137":   PN = "AG27"  !CDS_PN = "AG27";
"VSS138":   PN = "AG33"  !CDS_PN = "AG33";
"VSS139":   PN = "AG39"  !CDS_PN = "AG39";
"VSS140":   PN = "AG45"  !CDS_PN = "AG45";
"VSS141":   PN = "AG5"  !CDS_PN = "AG5";
"VSS142":   PN = "AG52"  !CDS_PN = "AG52";
"VSS143":   PN = "AG58"  !CDS_PN = "AG58";
"VSS144":   PN = "AG64"  !CDS_PN = "AG64";
"VSS145":   PN = "AG70"  !CDS_PN = "AG70";
"VSS146":   PN = "AG76"  !CDS_PN = "AG76";
"VSS147":   PN = "AG84"  !CDS_PN = "AG84";
"VSS148":   PN = "AG88"  !CDS_PN = "AG88";
"VSS149":   PN = "AG9"  !CDS_PN = "AG9";
"VSS150":   PN = "AH12"  !CDS_PN = "AH12";
"VSS151":   PN = "AH16"  !CDS_PN = "AH16";
"VSS152":   PN = "AH20"  !CDS_PN = "AH20";
"VSS153":   PN = "AH22"  !CDS_PN = "AH22";
"VSS154":   PN = "AH26"  !CDS_PN = "AH26";
"VSS155":   PN = "AH28"  !CDS_PN = "AH28";
"VSS156":   PN = "AH32"  !CDS_PN = "AH32";
"VSS157":   PN = "AH34"  !CDS_PN = "AH34";
"VSS158":   PN = "AH38"  !CDS_PN = "AH38";
"VSS159":   PN = "AH4"  !CDS_PN = "AH4";
"VSS160":   PN = "AH40"  !CDS_PN = "AH40";
"VSS161":   PN = "AH44"  !CDS_PN = "AH44";
"VSS162":   PN = "AH47"  !CDS_PN = "AH47";
"VSS163":   PN = "AH51"  !CDS_PN = "AH51";
"VSS164":   PN = "AH53"  !CDS_PN = "AH53";
"VSS165":   PN = "AH57"  !CDS_PN = "AH57";
"VSS166":   PN = "AH59"  !CDS_PN = "AH59";
"VSS167":   PN = "AH63"  !CDS_PN = "AH63";
"VSS168":   PN = "AH65"  !CDS_PN = "AH65";
"VSS169":   PN = "AH69"  !CDS_PN = "AH69";
"VSS170":   PN = "AH71"  !CDS_PN = "AH71";
"VSS171":   PN = "AH75"  !CDS_PN = "AH75";
"VSS172":   PN = "AH77"  !CDS_PN = "AH77";
"VSS173":   PN = "AH79"  !CDS_PN = "AH79";
"VSS174":   PN = "AH8"  !CDS_PN = "AH8";
"VSS175":   PN = "AH83"  !CDS_PN = "AH83";
"VSS176":   PN = "AJ19"  !CDS_PN = "AJ19";
"VSS177":   PN = "AJ23"  !CDS_PN = "AJ23";
"VSS178":   PN = "AJ25"  !CDS_PN = "AJ25";
"VSS179":   PN = "AJ29"  !CDS_PN = "AJ29";
"VSS180":   PN = "AJ31"  !CDS_PN = "AJ31";
"VSS181":   PN = "AJ35"  !CDS_PN = "AJ35";
"VSS182":   PN = "AJ37"  !CDS_PN = "AJ37";
"VSS183":   PN = "AJ41"  !CDS_PN = "AJ41";
"VSS184":   PN = "AJ43"  !CDS_PN = "AJ43";
"VSS185":   PN = "AJ48"  !CDS_PN = "AJ48";
"VSS186":   PN = "AJ50"  !CDS_PN = "AJ50";
"VSS187":   PN = "AJ54"  !CDS_PN = "AJ54";
"VSS188":   PN = "AJ56"  !CDS_PN = "AJ56";
"VSS189":   PN = "AJ60"  !CDS_PN = "AJ60";
"VSS190":   PN = "AJ62"  !CDS_PN = "AJ62";
"VSS191":   PN = "AJ66"  !CDS_PN = "AJ66";
"VSS192":   PN = "AJ68"  !CDS_PN = "AJ68";
"VSS193":   PN = "AJ72"  !CDS_PN = "AJ72";
"VSS194":   PN = "AJ74"  !CDS_PN = "AJ74";
"VSS195":   PN = "AJ78"  !CDS_PN = "AJ78";
"VSS196":   PN = "AJ84"  !CDS_PN = "AJ84";
"VSS197":   PN = "AJ88"  !CDS_PN = "AJ88";
DRAWING = "@s9s_mb_2u_lib.s9s_mb_2u(sch_1):page73";
BODY = "SOCKET4677_AZIF0045P001C01CS","I2": LOCATION = "U1" #&CDS_LOCATION = "U1" &SEC = "40" #&CDS_SEC = "40";
"VSS17":   PN = "AA19"  !CDS_PN = "AA19";
"VSS18":   PN = "AA23"  !CDS_PN = "AA23";
"VSS19":   PN = "AA25"  !CDS_PN = "AA25";
"VSS20":   PN = "AA29"  !CDS_PN = "AA29";
"VSS21":   PN = "AA31"  !CDS_PN = "AA31";
"VSS22":   PN = "AA35"  !CDS_PN = "AA35";
"VSS23":   PN = "AA37"  !CDS_PN = "AA37";
"VSS24":   PN = "AA41"  !CDS_PN = "AA41";
"VSS25":   PN = "AA43"  !CDS_PN = "AA43";
"VSS26":   PN = "AA48"  !CDS_PN = "AA48";
"VSS27":   PN = "AA50"  !CDS_PN = "AA50";
"VSS28":   PN = "AA54"  !CDS_PN = "AA54";
"VSS29":   PN = "AA56"  !CDS_PN = "AA56";
"VSS30":   PN = "AA60"  !CDS_PN = "AA60";
"VSS31":   PN = "AA62"  !CDS_PN = "AA62";
"VSS32":   PN = "AA66"  !CDS_PN = "AA66";
"VSS33":   PN = "AA68"  !CDS_PN = "AA68";
"VSS34":   PN = "AA72"  !CDS_PN = "AA72";
"VSS35":   PN = "AA74"  !CDS_PN = "AA74";
"VSS36":   PN = "AA78"  !CDS_PN = "AA78";
"VSS37":   PN = "AA80"  !CDS_PN = "AA80";
"VSS1690":   PN = "P32"  !CDS_PN = "P32";
"VSS1696":   PN = "N76"  !CDS_PN = "N76";
"VSS1697":   PN = "P51"  !CDS_PN = "P51";
"VSS1698":   PN = "N78"  !CDS_PN = "N78";
"VSS1699":   PN = "P57"  !CDS_PN = "P57";
"VSS1700":   PN = "N80"  !CDS_PN = "N80";
"VSS1701":   PN = "N82"  !CDS_PN = "N82";
"VSS1702":   PN = "N84"  !CDS_PN = "N84";
"VSS1703":   PN = "N88"  !CDS_PN = "N88";
"VSS1704":   PN = "P71"  !CDS_PN = "P71";
"VSS1705":   PN = "P12"  !CDS_PN = "P12";
"VSS1706":   PN = "P16"  !CDS_PN = "P16";
"VSS1707":   PN = "P20"  !CDS_PN = "P20";
"VSS1708":   PN = "P22"  !CDS_PN = "P22";
"VSS1709":   PN = "P26"  !CDS_PN = "P26";
"VSS1710":   PN = "P28"  !CDS_PN = "P28";
"VSS1711":   PN = "R1"  !CDS_PN = "R1";
"VSS1712":   PN = "P34"  !CDS_PN = "P34";
"VSS1713":   PN = "P38"  !CDS_PN = "P38";
"VSS1714":   PN = "R19"  !CDS_PN = "R19";
"VSS1715":   PN = "R23"  !CDS_PN = "R23";
"VSS1716":   PN = "P4"  !CDS_PN = "P4";
"VSS1717":   PN = "P40"  !CDS_PN = "P40";
"VSS1718":   PN = "P44"  !CDS_PN = "P44";
"VSS1719":   PN = "P47"  !CDS_PN = "P47";
"VSS1720":   PN = "P53"  !CDS_PN = "P53";
"VSS1721":   PN = "P59"  !CDS_PN = "P59";
"VSS1722":   PN = "P63"  !CDS_PN = "P63";
"VSS1723":   PN = "R48"  !CDS_PN = "R48";
"VSS1724":   PN = "P65"  !CDS_PN = "P65";
"VSS1725":   PN = "P69"  !CDS_PN = "P69";
"VSS1726":   PN = "P75"  !CDS_PN = "P75";
"VSS1727":   PN = "P77"  !CDS_PN = "P77";
"VSS1728":   PN = "R60"  !CDS_PN = "R60";
"VSS1729":   PN = "P8"  !CDS_PN = "P8";
"VSS1730":   PN = "R66"  !CDS_PN = "R66";
"VSS1731":   PN = "P87"  !CDS_PN = "P87";
"VSS1732":   PN = "P91"  !CDS_PN = "P91";
"VSS1733":   PN = "R13"  !CDS_PN = "R13";
"VSS1734":   PN = "R17"  !CDS_PN = "R17";
"VSS1735":   PN = "R25"  !CDS_PN = "R25";
"VSS1736":   PN = "R29"  !CDS_PN = "R29";
"VSS1737":   PN = "R31"  !CDS_PN = "R31";
"VSS1738":   PN = "R35"  !CDS_PN = "R35";
"VSS1739":   PN = "T12"  !CDS_PN = "T12";
"VSS1740":   PN = "T16"  !CDS_PN = "T16";
"VSS1741":   PN = "T18"  !CDS_PN = "T18";
"VSS1742":   PN = "R37"  !CDS_PN = "R37";
"VSS1743":   PN = "R41"  !CDS_PN = "R41";
"VSS1744":   PN = "R43"  !CDS_PN = "R43";
"VSS1745":   PN = "R5"  !CDS_PN = "R5";
"VSS1746":   PN = "T36"  !CDS_PN = "T36";
"VSS1747":   PN = "R50"  !CDS_PN = "R50";
"VSS1748":   PN = "R54"  !CDS_PN = "R54";
"VSS1749":   PN = "T49"  !CDS_PN = "T49";
"VSS1750":   PN = "T55"  !CDS_PN = "T55";
"VSS1751":   PN = "R56"  !CDS_PN = "R56";
"VSS1752":   PN = "R62"  !CDS_PN = "R62";
"VSS1753":   PN = "R68"  !CDS_PN = "R68";
"VSS1754":   PN = "R72"  !CDS_PN = "R72";
"VSS1755":   PN = "R74"  !CDS_PN = "R74";
"VSS1756":   PN = "R78"  !CDS_PN = "R78";
"VSS1757":   PN = "R84"  !CDS_PN = "R84";
"VSS1758":   PN = "R88"  !CDS_PN = "R88";
"VSS1759":   PN = "R9"  !CDS_PN = "R9";
"VSS1760":   PN = "T24"  !CDS_PN = "T24";
"VSS1761":   PN = "T30"  !CDS_PN = "T30";
"VSS1762":   PN = "T4"  !CDS_PN = "T4";
"VSS1763":   PN = "T42"  !CDS_PN = "T42";
"VSS1764":   PN = "T61"  !CDS_PN = "T61";
"VSS1765":   PN = "T67"  !CDS_PN = "T67";
"VSS1766":   PN = "U52"  !CDS_PN = "U52";
"VSS1767":   PN = "T73"  !CDS_PN = "T73";
"VSS1768":   PN = "T79"  !CDS_PN = "T79";
"VSS1769":   PN = "T8"  !CDS_PN = "T8";
"VSS1770":   PN = "T83"  !CDS_PN = "T83";
"VSS1771":   PN = "U39"  !CDS_PN = "U39";
"VSS1772":   PN = "U82"  !CDS_PN = "U82";
"VSS1773":   PN = "U84"  !CDS_PN = "U84";
"VSS1774":   PN = "U88"  !CDS_PN = "U88";
"VSS1775":   PN = "V12"  !CDS_PN = "V12";
"VSS1776":   PN = "V16"  !CDS_PN = "V16";
"VSS1777":   PN = "V18"  !CDS_PN = "V18";
"VSS1778":   PN = "V20"  !CDS_PN = "V20";
"VSS1779":   PN = "V22"  !CDS_PN = "V22";
"VSS1780":   PN = "V24"  !CDS_PN = "V24";
"VSS1781":   PN = "V26"  !CDS_PN = "V26";
"VSS1782":   PN = "V28"  !CDS_PN = "V28";
"VSS1783":   PN = "V30"  !CDS_PN = "V30";
"VSS1784":   PN = "V32"  !CDS_PN = "V32";
"VSS1785":   PN = "V34"  !CDS_PN = "V34";
"VSS1786":   PN = "V36"  !CDS_PN = "V36";
"VSS1787":   PN = "V38"  !CDS_PN = "V38";
"VSS1788":   PN = "V4"  !CDS_PN = "V4";
"VSS1789":   PN = "V49"  !CDS_PN = "V49";
"VSS1790":   PN = "V40"  !CDS_PN = "V40";
"VSS1791":   PN = "V42"  !CDS_PN = "V42";
"VSS1792":   PN = "V44"  !CDS_PN = "V44";
"VSS1793":   PN = "V47"  !CDS_PN = "V47";
"VSS1794":   PN = "V51"  !CDS_PN = "V51";
"VSS1795":   PN = "V53"  !CDS_PN = "V53";
"VSS1796":   PN = "V55"  !CDS_PN = "V55";
"VSS1797":   PN = "V57"  !CDS_PN = "V57";
"VSS1798":   PN = "V59"  !CDS_PN = "V59";
"VSS1799":   PN = "V61"  !CDS_PN = "V61";
"VSS1800":   PN = "V71"  !CDS_PN = "V71";
"VSS1801":   PN = "V73"  !CDS_PN = "V73";
"VSS1802":   PN = "V63"  !CDS_PN = "V63";
"VSS1803":   PN = "V65"  !CDS_PN = "V65";
"VSS1804":   PN = "V67"  !CDS_PN = "V67";
"VSS1805":   PN = "V69"  !CDS_PN = "V69";
"VSS1806":   PN = "V75"  !CDS_PN = "V75";
"VSS1807":   PN = "V91"  !CDS_PN = "V91";
"VSS1808":   PN = "W1"  !CDS_PN = "W1";
"VSS1809":   PN = "W13"  !CDS_PN = "W13";
"VSS1810":   PN = "V77"  !CDS_PN = "V77";
"VSS1811":   PN = "V79"  !CDS_PN = "V79";
"VSS1812":   PN = "V8"  !CDS_PN = "V8";
"VSS1813":   PN = "V87"  !CDS_PN = "V87";
"VSS1814":   PN = "W5"  !CDS_PN = "W5";
"VSS1815":   PN = "W52"  !CDS_PN = "W52";
"VSS1816":   PN = "W39"  !CDS_PN = "W39";
"VSS1817":   PN = "W84"  !CDS_PN = "W84";
"VSS1818":   PN = "W88"  !CDS_PN = "W88";
"VSS1819":   PN = "W9"  !CDS_PN = "W9";
"VSS1820":   PN = "Y12"  !CDS_PN = "Y12";
"VSS1821":   PN = "Y16"  !CDS_PN = "Y16";
"VSS1822":   PN = "Y18"  !CDS_PN = "Y18";
"VSS1823":   PN = "Y24"  !CDS_PN = "Y24";
"VSS1824":   PN = "Y30"  !CDS_PN = "Y30";
"VSS1825":   PN = "Y36"  !CDS_PN = "Y36";
"VSS1826":   PN = "Y4"  !CDS_PN = "Y4";
"VSS1827":   PN = "Y42"  !CDS_PN = "Y42";
"VSS1828":   PN = "Y61"  !CDS_PN = "Y61";
"VSS1829":   PN = "Y67"  !CDS_PN = "Y67";
"VSS1830":   PN = "Y49"  !CDS_PN = "Y49";
"VSS1831":   PN = "Y55"  !CDS_PN = "Y55";
"VSS1832":   PN = "Y8"  !CDS_PN = "Y8";
"VSS1833":   PN = "Y73"  !CDS_PN = "Y73";
BODY = "SOCKET4677_AZIF0045P001C01CS","I5": LOCATION = "U1" #&CDS_LOCATION = "U1" &SEC = "41" #&CDS_SEC = "41";
"VSS1126":   PN = "E52"  !CDS_PN = "E52";
"VSS1129":   PN = "E74"  !CDS_PN = "E74";
"VSS1131":   PN = "E78"  !CDS_PN = "E78";
"VSS1272":   PN = "E76"  !CDS_PN = "E76";
"VSS1273":   PN = "E86"  !CDS_PN = "E86";
"VSS1494":   PN = "F12"  !CDS_PN = "F12";
"VSS1495":   PN = "F18"  !CDS_PN = "F18";
"VSS1502":   PN = "F42"  !CDS_PN = "F42";
"VSS1504":   PN = "F55"  !CDS_PN = "F55";
"VSS1507":   PN = "F6"  !CDS_PN = "F6";
"VSS1508":   PN = "F61"  !CDS_PN = "F61";
"VSS1509":   PN = "F67"  !CDS_PN = "F67";
"VSS1510":   PN = "F73"  !CDS_PN = "F73";
"VSS1511":   PN = "F79"  !CDS_PN = "F79";
"VSS1514":   PN = "G11"  !CDS_PN = "G11";
"VSS1516":   PN = "G17"  !CDS_PN = "G17";
"VSS1519":   PN = "G25"  !CDS_PN = "G25";
"VSS1521":   PN = "G3"  !CDS_PN = "G3";
"VSS1523":   PN = "G35"  !CDS_PN = "G35";
"VSS1527":   PN = "G48"  !CDS_PN = "G48";
"VSS1532":   PN = "G60"  !CDS_PN = "G60";
"VSS1534":   PN = "G66"  !CDS_PN = "G66";
"VSS1535":   PN = "G68"  !CDS_PN = "G68";
"VSS1536":   PN = "G7"  !CDS_PN = "G7";
"VSS1538":   PN = "G74"  !CDS_PN = "G74";
"VSS1544":   PN = "H14"  !CDS_PN = "H14";
"VSS1546":   PN = "H2"  !CDS_PN = "H2";
"VSS1558":   PN = "H51"  !CDS_PN = "H51";
"VSS1560":   PN = "H57"  !CDS_PN = "H57";
"VSS1564":   PN = "H65"  !CDS_PN = "H65";
"VSS1567":   PN = "H75"  !CDS_PN = "H75";
"VSS1570":   PN = "F24"  !CDS_PN = "F24";
"VSS1571":   PN = "F30"  !CDS_PN = "F30";
"VSS1572":   PN = "F36"  !CDS_PN = "F36";
"VSS1573":   PN = "F4"  !CDS_PN = "F4";
"VSS1574":   PN = "F49"  !CDS_PN = "F49";
"VSS1575":   PN = "J21"  !CDS_PN = "J21";
"VSS1576":   PN = "F83"  !CDS_PN = "F83";
"VSS1577":   PN = "F89"  !CDS_PN = "F89";
"VSS1578":   PN = "G13"  !CDS_PN = "G13";
"VSS1579":   PN = "G19"  !CDS_PN = "G19";
"VSS1580":   PN = "J39"  !CDS_PN = "J39";
"VSS1581":   PN = "G23"  !CDS_PN = "G23";
"VSS1582":   PN = "J5"  !CDS_PN = "J5";
"VSS1583":   PN = "G29"  !CDS_PN = "G29";
"VSS1584":   PN = "G31"  !CDS_PN = "G31";
"VSS1585":   PN = "G37"  !CDS_PN = "G37";
"VSS1586":   PN = "G41"  !CDS_PN = "G41";
"VSS1587":   PN = "J64"  !CDS_PN = "J64";
"VSS1588":   PN = "G43"  !CDS_PN = "G43";
"VSS1589":   PN = "J70"  !CDS_PN = "J70";
"VSS1590":   PN = "G50"  !CDS_PN = "G50";
"VSS1591":   PN = "G54"  !CDS_PN = "G54";
"VSS1592":   PN = "G56"  !CDS_PN = "G56";
"VSS1593":   PN = "G62"  !CDS_PN = "G62";
"VSS1594":   PN = "G72"  !CDS_PN = "G72";
"VSS1595":   PN = "J88"  !CDS_PN = "J88";
"VSS1596":   PN = "J9"  !CDS_PN = "J9";
"VSS1597":   PN = "K12"  !CDS_PN = "K12";
"VSS1598":   PN = "K14"  !CDS_PN = "K14";
"VSS1599":   PN = "K2"  !CDS_PN = "K2";
"VSS1600":   PN = "G84"  !CDS_PN = "G84";
"VSS1601":   PN = "G88"  !CDS_PN = "G88";
"VSS1602":   PN = "K42"  !CDS_PN = "K42";
"VSS1603":   PN = "K49"  !CDS_PN = "K49";
"VSS1604":   PN = "G90"  !CDS_PN = "G90";
"VSS1605":   PN = "H10"  !CDS_PN = "H10";
"VSS1606":   PN = "H16"  !CDS_PN = "H16";
"VSS1607":   PN = "H20"  !CDS_PN = "H20";
"VSS1608":   PN = "H22"  !CDS_PN = "H22";
"VSS1609":   PN = "H26"  !CDS_PN = "H26";
"VSS1610":   PN = "H28"  !CDS_PN = "H28";
"VSS1611":   PN = "H32"  !CDS_PN = "H32";
"VSS1612":   PN = "H34"  !CDS_PN = "H34";
"VSS1613":   PN = "H38"  !CDS_PN = "H38";
"VSS1614":   PN = "L19"  !CDS_PN = "L19";
"VSS1615":   PN = "H4"  !CDS_PN = "H4";
"VSS1616":   PN = "H40"  !CDS_PN = "H40";
"VSS1617":   PN = "H44"  !CDS_PN = "H44";
"VSS1618":   PN = "H47"  !CDS_PN = "H47";
"VSS1619":   PN = "H53"  !CDS_PN = "H53";
"VSS1620":   PN = "H59"  !CDS_PN = "H59";
"VSS1621":   PN = "H6"  !CDS_PN = "H6";
"VSS1622":   PN = "H63"  !CDS_PN = "H63";
"VSS1623":   PN = "H69"  !CDS_PN = "H69";
"VSS1624":   PN = "H71"  !CDS_PN = "H71";
"VSS1625":   PN = "H79"  !CDS_PN = "H79";
"VSS1626":   PN = "H8"  !CDS_PN = "H8";
"VSS1627":   PN = "H81"  !CDS_PN = "H81";
"VSS1628":   PN = "J15"  !CDS_PN = "J15";
"VSS1629":   PN = "J27"  !CDS_PN = "J27";
"VSS1630":   PN = "J33"  !CDS_PN = "J33";
"VSS1631":   PN = "J45"  !CDS_PN = "J45";
"VSS1632":   PN = "J52"  !CDS_PN = "J52";
"VSS1633":   PN = "J58"  !CDS_PN = "J58";
"VSS1634":   PN = "L58"  !CDS_PN = "L58";
"VSS1635":   PN = "J76"  !CDS_PN = "J76";
"VSS1636":   PN = "J78"  !CDS_PN = "J78";
"VSS1637":   PN = "J84"  !CDS_PN = "J84";
"VSS1638":   PN = "J86"  !CDS_PN = "J86";
"VSS1639":   PN = "K77"  !CDS_PN = "K77";
"VSS1640":   PN = "L70"  !CDS_PN = "L70";
"VSS1641":   PN = "K8"  !CDS_PN = "K8";
"VSS1642":   PN = "K83"  !CDS_PN = "K83";
"VSS1643":   PN = "K85"  !CDS_PN = "K85";
"VSS1644":   PN = "L13"  !CDS_PN = "L13";
"VSS1645":   PN = "L15"  !CDS_PN = "L15";
"VSS1646":   PN = "L88"  !CDS_PN = "L88";
"VSS1647":   PN = "L9"  !CDS_PN = "L9";
"VSS1648":   PN = "L90"  !CDS_PN = "L90";
"VSS1649":   PN = "M12"  !CDS_PN = "M12";
"VSS1650":   PN = "L17"  !CDS_PN = "L17";
"VSS1651":   PN = "L21"  !CDS_PN = "L21";
"VSS1652":   PN = "M4"  !CDS_PN = "M4";
"VSS1653":   PN = "M42"  !CDS_PN = "M42";
"VSS1654":   PN = "M49"  !CDS_PN = "M49";
"VSS1655":   PN = "L23"  !CDS_PN = "L23";
"VSS1656":   PN = "L25"  !CDS_PN = "L25";
"VSS1657":   PN = "M8"  !CDS_PN = "M8";
"VSS1658":   PN = "L27"  !CDS_PN = "L27";
"VSS1659":   PN = "L29"  !CDS_PN = "L29";
"VSS1660":   PN = "L31"  !CDS_PN = "L31";
"VSS1661":   PN = "L33"  !CDS_PN = "L33";
"VSS1662":   PN = "L35"  !CDS_PN = "L35";
"VSS1663":   PN = "L37"  !CDS_PN = "L37";
"VSS1664":   PN = "N21"  !CDS_PN = "N21";
"VSS1665":   PN = "L39"  !CDS_PN = "L39";
"VSS1666":   PN = "L41"  !CDS_PN = "L41";
"VSS1667":   PN = "L43"  !CDS_PN = "L43";
"VSS1668":   PN = "L45"  !CDS_PN = "L45";
"VSS1669":   PN = "N39"  !CDS_PN = "N39";
"VSS1670":   PN = "L48"  !CDS_PN = "L48";
"VSS1671":   PN = "L5"  !CDS_PN = "L5";
"VSS1672":   PN = "L50"  !CDS_PN = "L50";
"VSS1673":   PN = "L52"  !CDS_PN = "L52";
"VSS1674":   PN = "L54"  !CDS_PN = "L54";
"VSS1675":   PN = "N64"  !CDS_PN = "N64";
"VSS1676":   PN = "L56"  !CDS_PN = "L56";
"VSS1677":   PN = "L60"  !CDS_PN = "L60";
"VSS1678":   PN = "L62"  !CDS_PN = "L62";
"VSS1679":   PN = "L64"  !CDS_PN = "L64";
"VSS1680":   PN = "L66"  !CDS_PN = "L66";
"VSS1681":   PN = "L68"  !CDS_PN = "L68";
"VSS1682":   PN = "L72"  !CDS_PN = "L72";
"VSS1683":   PN = "L74"  !CDS_PN = "L74";
"VSS1684":   PN = "L76"  !CDS_PN = "L76";
"VSS1685":   PN = "L78"  !CDS_PN = "L78";
"VSS1686":   PN = "M81"  !CDS_PN = "M81";
"VSS1687":   PN = "M83"  !CDS_PN = "M83";
"VSS1688":   PN = "N15"  !CDS_PN = "N15";
"VSS1689":   PN = "N27"  !CDS_PN = "N27";
"VSS1691":   PN = "N33"  !CDS_PN = "N33";
"VSS1692":   PN = "N45"  !CDS_PN = "N45";
"VSS1693":   PN = "N52"  !CDS_PN = "N52";
"VSS1694":   PN = "N58"  !CDS_PN = "N58";
"VSS1695":   PN = "N70"  !CDS_PN = "N70";
BODY = "SOCKET4677_AZIF0045P001C01CS","I8": LOCATION = "U1" #&CDS_LOCATION = "U1" &SEC = "42" #&CDS_SEC = "42";
"VSS1":   PN = "A11"  !CDS_PN = "A11";
"VSS2":   PN = "A13"  !CDS_PN = "A13";
"VSS3":   PN = "A17"  !CDS_PN = "A17";
"VSS4":   PN = "A19"  !CDS_PN = "A19";
"VSS5":   PN = "A23"  !CDS_PN = "A23";
"VSS6":   PN = "A25"  !CDS_PN = "A25";
"VSS7":   PN = "A29"  !CDS_PN = "A29";
"VSS8":   PN = "A31"  !CDS_PN = "A31";
"VSS9":   PN = "A35"  !CDS_PN = "A35";
"VSS10":   PN = "A37"  !CDS_PN = "A37";
"VSS11":   PN = "A41"  !CDS_PN = "A41";
"VSS12":   PN = "A50"  !CDS_PN = "A50";
"VSS13":   PN = "A54"  !CDS_PN = "A54";
"VSS14":   PN = "A56"  !CDS_PN = "A56";
"VSS15":   PN = "A60"  !CDS_PN = "A60";
"VSS16":   PN = "A62"  !CDS_PN = "A62";
"VSS378":   PN = "B12"  !CDS_PN = "B12";
"VSS379":   PN = "B18"  !CDS_PN = "B18";
"VSS380":   PN = "B24"  !CDS_PN = "B24";
"VSS381":   PN = "B30"  !CDS_PN = "B30";
"VSS382":   PN = "B36"  !CDS_PN = "B36";
"VSS384":   PN = "B42"  !CDS_PN = "B42";
"VSS385":   PN = "B49"  !CDS_PN = "B49";
"VSS386":   PN = "B55"  !CDS_PN = "B55";
"VSS387":   PN = "B6"  !CDS_PN = "B6";
"VSS388":   PN = "B61"  !CDS_PN = "B61";
"VSS389":   PN = "B67"  !CDS_PN = "B67";
"VSS390":   PN = "B75"  !CDS_PN = "B75";
"VSS391":   PN = "B83"  !CDS_PN = "B83";
"VSS392":   PN = "B87"  !CDS_PN = "B87";
"VSS609":   PN = "C39"  !CDS_PN = "C39";
"VSS610":   PN = "C45"  !CDS_PN = "C45";
"VSS612":   PN = "C5"  !CDS_PN = "C5";
"VSS613":   PN = "C52"  !CDS_PN = "C52";
"VSS614":   PN = "C72"  !CDS_PN = "C72";
"VSS615":   PN = "C74"  !CDS_PN = "C74";
"VSS616":   PN = "C78"  !CDS_PN = "C78";
"VSS617":   PN = "C80"  !CDS_PN = "C80";
"VSS618":   PN = "C82"  !CDS_PN = "C82";
"VSS619":   PN = "C86"  !CDS_PN = "C86";
"VSS657":   PN = "D63"  !CDS_PN = "D63";
"VSS658":   PN = "D65"  !CDS_PN = "D65";
"VSS659":   PN = "D67"  !CDS_PN = "D67";
"VSS662":   PN = "D79"  !CDS_PN = "D79";
"VSS663":   PN = "D8"  !CDS_PN = "D8";
"VSS864":   PN = "D10"  !CDS_PN = "D10";
"VSS865":   PN = "D12"  !CDS_PN = "D12";
"VSS866":   PN = "D14"  !CDS_PN = "D14";
"VSS868":   PN = "D16"  !CDS_PN = "D16";
"VSS869":   PN = "D18"  !CDS_PN = "D18";
"VSS871":   PN = "D20"  !CDS_PN = "D20";
"VSS873":   PN = "D22"  !CDS_PN = "D22";
"VSS874":   PN = "D24"  !CDS_PN = "D24";
"VSS875":   PN = "D26"  !CDS_PN = "D26";
"VSS876":   PN = "D28"  !CDS_PN = "D28";
"VSS877":   PN = "D30"  !CDS_PN = "D30";
"VSS878":   PN = "D32"  !CDS_PN = "D32";
"VSS879":   PN = "D34"  !CDS_PN = "D34";
"VSS881":   PN = "D36"  !CDS_PN = "D36";
"VSS884":   PN = "D38"  !CDS_PN = "D38";
"VSS885":   PN = "D40"  !CDS_PN = "D40";
"VSS886":   PN = "D42"  !CDS_PN = "D42";
"VSS888":   PN = "D44"  !CDS_PN = "D44";
"VSS889":   PN = "D47"  !CDS_PN = "D47";
"VSS891":   PN = "D49"  !CDS_PN = "D49";
"VSS892":   PN = "D51"  !CDS_PN = "D51";
"VSS895":   PN = "D53"  !CDS_PN = "D53";
"VSS896":   PN = "D55"  !CDS_PN = "D55";
"VSS897":   PN = "D57"  !CDS_PN = "D57";
"VSS898":   PN = "D59"  !CDS_PN = "D59";
"VSS899":   PN = "D6"  !CDS_PN = "D6";
"VSS900":   PN = "D61"  !CDS_PN = "D61";
"VSS901":   PN = "D69"  !CDS_PN = "D69";
"VSS902":   PN = "D71"  !CDS_PN = "D71";
"VSS906":   PN = "D81"  !CDS_PN = "D81";
"VSS907":   PN = "D83"  !CDS_PN = "D83";
"VSS1125":   PN = "E5"  !CDS_PN = "E5";
"VSS1271":   PN = "E39"  !CDS_PN = "E39";
DRAWING = "@s9s_mb_2u_lib.s9s_mb_2u(sch_1):page74";
BODY = "Q_CAP","I7": LOCATION = "C407" #&CDS_LOCATION = "C407" &SEC = "1" #&CDS_SEC = "1";
"A":   PN = "1"  !CDS_PN = "1";
"B":   PN = "2"  !CDS_PN = "2";
BODY = "Q_CAP","I8": LOCATION = "C409" #&CDS_LOCATION = "C409" &SEC = "1" #&CDS_SEC = "1";
"A":   PN = "1"  !CDS_PN = "1";
"B":   PN = "2"  !CDS_PN = "2";
BODY = "Q_CAP","I9": LOCATION = "C411" #&CDS_LOCATION = "C411" &SEC = "1" #&CDS_SEC = "1";
"A":   PN = "1"  !CDS_PN = "1";
"B":   PN = "2"  !CDS_PN = "2";
BODY = "Q_CAP","I10": LOCATION = "C413" #&CDS_LOCATION = "C413" &SEC = "1" #&CDS_SEC = "1";
"A":   PN = "1"  !CDS_PN = "1";
"B":   PN = "2"  !CDS_PN = "2";
BODY = "Q_CAP","I13": LOCATION = "C101" #&CDS_LOCATION = "C101" &SEC = "1" #&CDS_SEC = "1";
"A":   PN = "1"  !CDS_PN = "1";
"B":   PN = "2"  !CDS_PN = "2";
BODY = "Q_CAP","I15": LOCATION = "C969" #&CDS_LOCATION = "C969" &SEC = "1" #&CDS_SEC = "1";
"A":   PN = "1"  !CDS_PN = "1";
"B":   PN = "2"  !CDS_PN = "2";
BODY = "Q_CAP","I17": LOCATION = "C401" #&CDS_LOCATION = "C401" &SEC = "1" #&CDS_SEC = "1";
"A":   PN = "1"  !CDS_PN = "1";
"B":   PN = "2"  !CDS_PN = "2";
BODY = "Q_CAP","I18": LOCATION = "C212" #&CDS_LOCATION = "C212" &SEC = "1" #&CDS_SEC = "1";
"A":   PN = "1"  !CDS_PN = "1";
"B":   PN = "2"  !CDS_PN = "2";
BODY = "Q_CAP","I19": LOCATION = "C403" #&CDS_LOCATION = "C403" &SEC = "1" #&CDS_SEC = "1";
"A":   PN = "1"  !CDS_PN = "1";
"B":   PN = "2"  !CDS_PN = "2";
BODY = "Q_CAP","I20": LOCATION = "C213" #&CDS_LOCATION = "C213" &SEC = "1" #&CDS_SEC = "1";
"A":   PN = "1"  !CDS_PN = "1";
"B":   PN = "2"  !CDS_PN = "2";
BODY = "Q_CAP","I21": LOCATION = "C973" #&CDS_LOCATION = "C973" &SEC = "1" #&CDS_SEC = "1";
"A":   PN = "1"  !CDS_PN = "1";
"B":   PN = "2"  !CDS_PN = "2";
BODY = "Q_CAP","I22": LOCATION = "C977" #&CDS_LOCATION = "C977" &SEC = "1" #&CDS_SEC = "1";
"A":   PN = "1"  !CDS_PN = "1";
"B":   PN = "2"  !CDS_PN = "2";
BODY = "Q_CAP","I23": LOCATION = "C968" #&CDS_LOCATION = "C968" &SEC = "1" #&CDS_SEC = "1";
"A":   PN = "1"  !CDS_PN = "1";
"B":   PN = "2"  !CDS_PN = "2";
BODY = "Q_CAP","I29": LOCATION = "C976" #&CDS_LOCATION = "C976" &SEC = "1" #&CDS_SEC = "1";
"A":   PN = "1"  !CDS_PN = "1";
"B":   PN = "2"  !CDS_PN = "2";
BODY = "Q_CAP","I30": LOCATION = "C971" #&CDS_LOCATION = "C971" &SEC = "1" #&CDS_SEC = "1";
"A":   PN = "1"  !CDS_PN = "1";
"B":   PN = "2"  !CDS_PN = "2";
BODY = "Q_CAP","I32": LOCATION = "C975" #&CDS_LOCATION = "C975" &SEC = "1" #&CDS_SEC = "1";
"A":   PN = "1"  !CDS_PN = "1";
"B":   PN = "2"  !CDS_PN = "2";
BODY = "Q_CAP","I33": LOCATION = "C974" #&CDS_LOCATION = "C974" &SEC = "1" #&CDS_SEC = "1";
"A":   PN = "1"  !CDS_PN = "1";
"B":   PN = "2"  !CDS_PN = "2";
BODY = "Q_CAP","I35": LOCATION = "C214" #&CDS_LOCATION = "C214" &SEC = "1" #&CDS_SEC = "1";
"A":   PN = "1"  !CDS_PN = "1";
"B":   PN = "2"  !CDS_PN = "2";
BODY = "Q_CAP","I36": LOCATION = "C215" #&CDS_LOCATION = "C215" &SEC = "1" #&CDS_SEC = "1";
"A":   PN = "1"  !CDS_PN = "1";
"B":   PN = "2"  !CDS_PN = "2";
BODY = "Q_CAP","I37": LOCATION = "C981" #&CDS_LOCATION = "C981" &SEC = "1" #&CDS_SEC = "1";
"A":   PN = "1"  !CDS_PN = "1";
"B":   PN = "2"  !CDS_PN = "2";
BODY = "Q_CAP","I38": LOCATION = "C985" #&CDS_LOCATION = "C985" &SEC = "1" #&CDS_SEC = "1";
"A":   PN = "1"  !CDS_PN = "1";
"B":   PN = "2"  !CDS_PN = "2";
BODY = "Q_CAP","I40": LOCATION = "C216" #&CDS_LOCATION = "C216" &SEC = "1" #&CDS_SEC = "1";
"A":   PN = "1"  !CDS_PN = "1";
"B":   PN = "2"  !CDS_PN = "2";
BODY = "Q_CAP","I41": LOCATION = "C410" #&CDS_LOCATION = "C410" &SEC = "1" #&CDS_SEC = "1";
"A":   PN = "1"  !CDS_PN = "1";
"B":   PN = "2"  !CDS_PN = "2";
BODY = "Q_CAP","I42": LOCATION = "C412" #&CDS_LOCATION = "C412" &SEC = "1" #&CDS_SEC = "1";
"A":   PN = "1"  !CDS_PN = "1";
"B":   PN = "2"  !CDS_PN = "2";
BODY = "Q_CAP","I44": LOCATION = "C218" #&CDS_LOCATION = "C218" &SEC = "1" #&CDS_SEC = "1";
"A":   PN = "1"  !CDS_PN = "1";
"B":   PN = "2"  !CDS_PN = "2";
BODY = "Q_CAP","I46": LOCATION = "C993" #&CDS_LOCATION = "C993" &SEC = "1" #&CDS_SEC = "1";
"A":   PN = "1"  !CDS_PN = "1";
"B":   PN = "2"  !CDS_PN = "2";
BODY = "Q_CAP","I47": LOCATION = "C997" #&CDS_LOCATION = "C997" &SEC = "1" #&CDS_SEC = "1";
"A":   PN = "1"  !CDS_PN = "1";
"B":   PN = "2"  !CDS_PN = "2";
BODY = "Q_CAP","I48": LOCATION = "C980" #&CDS_LOCATION = "C980" &SEC = "1" #&CDS_SEC = "1";
"A":   PN = "1"  !CDS_PN = "1";
"B":   PN = "2"  !CDS_PN = "2";
BODY = "Q_CAP","I49": LOCATION = "C984" #&CDS_LOCATION = "C984" &SEC = "1" #&CDS_SEC = "1";
"A":   PN = "1"  !CDS_PN = "1";
"B":   PN = "2"  !CDS_PN = "2";
BODY = "Q_CAP","I50": LOCATION = "C979" #&CDS_LOCATION = "C979" &SEC = "1" #&CDS_SEC = "1";
"A":   PN = "1"  !CDS_PN = "1";
"B":   PN = "2"  !CDS_PN = "2";
BODY = "Q_CAP","I51": LOCATION = "C978" #&CDS_LOCATION = "C978" &SEC = "1" #&CDS_SEC = "1";
"A":   PN = "1"  !CDS_PN = "1";
"B":   PN = "2"  !CDS_PN = "2";
BODY = "Q_CAP","I52": LOCATION = "C983" #&CDS_LOCATION = "C983" &SEC = "1" #&CDS_SEC = "1";
"A":   PN = "1"  !CDS_PN = "1";
"B":   PN = "2"  !CDS_PN = "2";
BODY = "Q_CAP","I53": LOCATION = "C982" #&CDS_LOCATION = "C982" &SEC = "1" #&CDS_SEC = "1";
"A":   PN = "1"  !CDS_PN = "1";
"B":   PN = "2"  !CDS_PN = "2";
BODY = "Q_CAP","I54": LOCATION = "C988" #&CDS_LOCATION = "C988" &SEC = "1" #&CDS_SEC = "1";
"A":   PN = "1"  !CDS_PN = "1";
"B":   PN = "2"  !CDS_PN = "2";
BODY = "Q_CAP","I56": LOCATION = "C996" #&CDS_LOCATION = "C996" &SEC = "1" #&CDS_SEC = "1";
"A":   PN = "1"  !CDS_PN = "1";
"B":   PN = "2"  !CDS_PN = "2";
BODY = "Q_CAP","I58": LOCATION = "C986" #&CDS_LOCATION = "C986" &SEC = "1" #&CDS_SEC = "1";
"A":   PN = "1"  !CDS_PN = "1";
"B":   PN = "2"  !CDS_PN = "2";
BODY = "Q_CAP","I59": LOCATION = "C991" #&CDS_LOCATION = "C991" &SEC = "1" #&CDS_SEC = "1";
"A":   PN = "1"  !CDS_PN = "1";
"B":   PN = "2"  !CDS_PN = "2";
BODY = "Q_CAP","I60": LOCATION = "C990" #&CDS_LOCATION = "C990" &SEC = "1" #&CDS_SEC = "1";
"A":   PN = "1"  !CDS_PN = "1";
"B":   PN = "2"  !CDS_PN = "2";
BODY = "Q_CAP","I61": LOCATION = "C995" #&CDS_LOCATION = "C995" &SEC = "1" #&CDS_SEC = "1";
"A":   PN = "1"  !CDS_PN = "1";
"B":   PN = "2"  !CDS_PN = "2";
BODY = "Q_CAP","I64": LOCATION = "C415" #&CDS_LOCATION = "C415" &SEC = "1" #&CDS_SEC = "1";
"A":   PN = "1"  !CDS_PN = "1";
"B":   PN = "2"  !CDS_PN = "2";
BODY = "Q_CAP","I65": LOCATION = "C417" #&CDS_LOCATION = "C417" &SEC = "1" #&CDS_SEC = "1";
"A":   PN = "1"  !CDS_PN = "1";
"B":   PN = "2"  !CDS_PN = "2";
BODY = "Q_CAP","I68": LOCATION = "C418" #&CDS_LOCATION = "C418" &SEC = "1" #&CDS_SEC = "1";
"A":   PN = "1"  !CDS_PN = "1";
"B":   PN = "2"  !CDS_PN = "2";
BODY = "Q_CAP","I70": LOCATION = "C414" #&CDS_LOCATION = "C414" &SEC = "1" #&CDS_SEC = "1";
"A":   PN = "1"  !CDS_PN = "1";
"B":   PN = "2"  !CDS_PN = "2";
BODY = "Q_CAP","I71": LOCATION = "C219" #&CDS_LOCATION = "C219" &SEC = "1" #&CDS_SEC = "1";
"A":   PN = "1"  !CDS_PN = "1";
"B":   PN = "2"  !CDS_PN = "2";
BODY = "Q_CAP","I72": LOCATION = "C416" #&CDS_LOCATION = "C416" &SEC = "1" #&CDS_SEC = "1";
"A":   PN = "1"  !CDS_PN = "1";
"B":   PN = "2"  !CDS_PN = "2";
BODY = "Q_CAP","I74": LOCATION = "C220" #&CDS_LOCATION = "C220" &SEC = "1" #&CDS_SEC = "1";
"A":   PN = "1"  !CDS_PN = "1";
"B":   PN = "2"  !CDS_PN = "2";
BODY = "Q_CAP","I75": LOCATION = "C1001" #&CDS_LOCATION = "C1001" &SEC = "1" #&CDS_SEC = "1";
"A":   PN = "1"  !CDS_PN = "1";
"B":   PN = "2"  !CDS_PN = "2";
BODY = "Q_CAP","I77": LOCATION = "C1005" #&CDS_LOCATION = "C1005" &SEC = "1" #&CDS_SEC = "1";
"A":   PN = "1"  !CDS_PN = "1";
"B":   PN = "2"  !CDS_PN = "2";
BODY = "Q_CAP","I78": LOCATION = "C1009" #&CDS_LOCATION = "C1009" &SEC = "1" #&CDS_SEC = "1";
"A":   PN = "1"  !CDS_PN = "1";
"B":   PN = "2"  !CDS_PN = "2";
BODY = "Q_CAP","I80": LOCATION = "C1013" #&CDS_LOCATION = "C1013" &SEC = "1" #&CDS_SEC = "1";
"A":   PN = "1"  !CDS_PN = "1";
"B":   PN = "2"  !CDS_PN = "2";
BODY = "Q_CAP","I81": LOCATION = "C1000" #&CDS_LOCATION = "C1000" &SEC = "1" #&CDS_SEC = "1";
"A":   PN = "1"  !CDS_PN = "1";
"B":   PN = "2"  !CDS_PN = "2";
BODY = "Q_CAP","I85": LOCATION = "C999" #&CDS_LOCATION = "C999" &SEC = "1" #&CDS_SEC = "1";
"A":   PN = "1"  !CDS_PN = "1";
"B":   PN = "2"  !CDS_PN = "2";
BODY = "Q_CAP","I86": LOCATION = "C998" #&CDS_LOCATION = "C998" &SEC = "1" #&CDS_SEC = "1";
"A":   PN = "1"  !CDS_PN = "1";
"B":   PN = "2"  !CDS_PN = "2";
BODY = "Q_CAP","I87": LOCATION = "C1003" #&CDS_LOCATION = "C1003" &SEC = "1" #&CDS_SEC = "1";
"A":   PN = "1"  !CDS_PN = "1";
"B":   PN = "2"  !CDS_PN = "2";
BODY = "Q_CAP","I89": LOCATION = "C1002" #&CDS_LOCATION = "C1002" &SEC = "1" #&CDS_SEC = "1";
"A":   PN = "1"  !CDS_PN = "1";
"B":   PN = "2"  !CDS_PN = "2";
BODY = "Q_CAP","I90": LOCATION = "C1008" #&CDS_LOCATION = "C1008" &SEC = "1" #&CDS_SEC = "1";
"A":   PN = "1"  !CDS_PN = "1";
"B":   PN = "2"  !CDS_PN = "2";
BODY = "Q_CAP","I92": LOCATION = "C1012" #&CDS_LOCATION = "C1012" &SEC = "1" #&CDS_SEC = "1";
"A":   PN = "1"  !CDS_PN = "1";
"B":   PN = "2"  !CDS_PN = "2";
BODY = "Q_CAP","I93": LOCATION = "C1007" #&CDS_LOCATION = "C1007" &SEC = "1" #&CDS_SEC = "1";
"A":   PN = "1"  !CDS_PN = "1";
"B":   PN = "2"  !CDS_PN = "2";
BODY = "Q_CAP","I95": LOCATION = "C1006" #&CDS_LOCATION = "C1006" &SEC = "1" #&CDS_SEC = "1";
"A":   PN = "1"  !CDS_PN = "1";
"B":   PN = "2"  !CDS_PN = "2";
BODY = "Q_CAP","I96": LOCATION = "C1011" #&CDS_LOCATION = "C1011" &SEC = "1" #&CDS_SEC = "1";
"A":   PN = "1"  !CDS_PN = "1";
"B":   PN = "2"  !CDS_PN = "2";
BODY = "Q_CAP","I97": LOCATION = "C1010" #&CDS_LOCATION = "C1010" &SEC = "1" #&CDS_SEC = "1";
"A":   PN = "1"  !CDS_PN = "1";
"B":   PN = "2"  !CDS_PN = "2";
BODY = "Q_CAP","I98": LOCATION = "C419" #&CDS_LOCATION = "C419" &SEC = "1" #&CDS_SEC = "1";
"A":   PN = "1"  !CDS_PN = "1";
"B":   PN = "2"  !CDS_PN = "2";
BODY = "Q_CAP","I102": LOCATION = "C590" #&CDS_LOCATION = "C590" &SEC = "1" #&CDS_SEC = "1";
"A":   PN = "1"  !CDS_PN = "1";
"B":   PN = "2"  !CDS_PN = "2";
BODY = "Q_CAP","I103": LOCATION = "C421" #&CDS_LOCATION = "C421" &SEC = "1" #&CDS_SEC = "1";
"A":   PN = "1"  !CDS_PN = "1";
"B":   PN = "2"  !CDS_PN = "2";
BODY = "Q_CAP","I105": LOCATION = "C1017" #&CDS_LOCATION = "C1017" &SEC = "1" #&CDS_SEC = "1";
"A":   PN = "1"  !CDS_PN = "1";
"B":   PN = "2"  !CDS_PN = "2";
BODY = "Q_CAP","I111": LOCATION = "C1016" #&CDS_LOCATION = "C1016" &SEC = "1" #&CDS_SEC = "1";
"A":   PN = "1"  !CDS_PN = "1";
"B":   PN = "2"  !CDS_PN = "2";
BODY = "Q_CAP","I112": LOCATION = "C1020" #&CDS_LOCATION = "C1020" &SEC = "1" #&CDS_SEC = "1";
"A":   PN = "1"  !CDS_PN = "1";
"B":   PN = "2"  !CDS_PN = "2";
BODY = "Q_CAP","I113": LOCATION = "C1015" #&CDS_LOCATION = "C1015" &SEC = "1" #&CDS_SEC = "1";
"A":   PN = "1"  !CDS_PN = "1";
"B":   PN = "2"  !CDS_PN = "2";
BODY = "Q_CAP","I114": LOCATION = "C1014" #&CDS_LOCATION = "C1014" &SEC = "1" #&CDS_SEC = "1";
"A":   PN = "1"  !CDS_PN = "1";
"B":   PN = "2"  !CDS_PN = "2";
BODY = "Q_CAP","I115": LOCATION = "C1019" #&CDS_LOCATION = "C1019" &SEC = "1" #&CDS_SEC = "1";
"A":   PN = "1"  !CDS_PN = "1";
"B":   PN = "2"  !CDS_PN = "2";
BODY = "Q_CAP","I131": LOCATION = "C1036" #&CDS_LOCATION = "C1036" &SEC = "1" #&CDS_SEC = "1";
"A":   PN = "1"  !CDS_PN = "1";
"B":   PN = "2"  !CDS_PN = "2";
BODY = "Q_CAP","I132": LOCATION = "C1040" #&CDS_LOCATION = "C1040" &SEC = "1" #&CDS_SEC = "1";
"A":   PN = "1"  !CDS_PN = "1";
"B":   PN = "2"  !CDS_PN = "2";
BODY = "Q_CAP","I133": LOCATION = "C1035" #&CDS_LOCATION = "C1035" &SEC = "1" #&CDS_SEC = "1";
"A":   PN = "1"  !CDS_PN = "1";
"B":   PN = "2"  !CDS_PN = "2";
BODY = "Q_CAP","I134": LOCATION = "C1034" #&CDS_LOCATION = "C1034" &SEC = "1" #&CDS_SEC = "1";
"A":   PN = "1"  !CDS_PN = "1";
"B":   PN = "2"  !CDS_PN = "2";
BODY = "Q_CAP","I135": LOCATION = "C1039" #&CDS_LOCATION = "C1039" &SEC = "1" #&CDS_SEC = "1";
"A":   PN = "1"  !CDS_PN = "1";
"B":   PN = "2"  !CDS_PN = "2";
BODY = "Q_CAP","I137": LOCATION = "C1038" #&CDS_LOCATION = "C1038" &SEC = "1" #&CDS_SEC = "1";
"A":   PN = "1"  !CDS_PN = "1";
"B":   PN = "2"  !CDS_PN = "2";
BODY = "Q_CAP","I139": LOCATION = "C1044" #&CDS_LOCATION = "C1044" &SEC = "1" #&CDS_SEC = "1";
"A":   PN = "1"  !CDS_PN = "1";
"B":   PN = "2"  !CDS_PN = "2";
BODY = "Q_CAP","I141": LOCATION = "C1043" #&CDS_LOCATION = "C1043" &SEC = "1" #&CDS_SEC = "1";
"A":   PN = "1"  !CDS_PN = "1";
"B":   PN = "2"  !CDS_PN = "2";
BODY = "Q_CAP","I142": LOCATION = "C408" #&CDS_LOCATION = "C408" &SEC = "1" #&CDS_SEC = "1";
"A":   PN = "1"  !CDS_PN = "1";
"B":   PN = "2"  !CDS_PN = "2";
BODY = "Q_CAP","I1": LOCATION = "C400" #&CDS_LOCATION = "C400" &SEC = "1" #&CDS_SEC = "1";
"A":   PN = "1"  !CDS_PN = "1";
"B":   PN = "2"  !CDS_PN = "2";
BODY = "Q_CAP","I3": LOCATION = "C402" #&CDS_LOCATION = "C402" &SEC = "1" #&CDS_SEC = "1";
"A":   PN = "1"  !CDS_PN = "1";
"B":   PN = "2"  !CDS_PN = "2";
BODY = "Q_CAP","I4": LOCATION = "C404" #&CDS_LOCATION = "C404" &SEC = "1" #&CDS_SEC = "1";
"A":   PN = "1"  !CDS_PN = "1";
"B":   PN = "2"  !CDS_PN = "2";
BODY = "Q_CAP","I5": LOCATION = "C406" #&CDS_LOCATION = "C406" &SEC = "1" #&CDS_SEC = "1";
"A":   PN = "1"  !CDS_PN = "1";
"B":   PN = "2"  !CDS_PN = "2";
BODY = "Q_CAP","I11": LOCATION = "C399" #&CDS_LOCATION = "C399" &SEC = "1" #&CDS_SEC = "1";
"A":   PN = "1"  !CDS_PN = "1";
"B":   PN = "2"  !CDS_PN = "2";
BODY = "Q_CAP","I25": LOCATION = "C967" #&CDS_LOCATION = "C967" &SEC = "1" #&CDS_SEC = "1";
"A":   PN = "1"  !CDS_PN = "1";
"B":   PN = "2"  !CDS_PN = "2";
BODY = "Q_CAP","I27": LOCATION = "C966" #&CDS_LOCATION = "C966" &SEC = "1" #&CDS_SEC = "1";
"A":   PN = "1"  !CDS_PN = "1";
"B":   PN = "2"  !CDS_PN = "2";
BODY = "Q_CAP","I28": LOCATION = "C972" #&CDS_LOCATION = "C972" &SEC = "1" #&CDS_SEC = "1";
"A":   PN = "1"  !CDS_PN = "1";
"B":   PN = "2"  !CDS_PN = "2";
BODY = "Q_CAP","I31": LOCATION = "C970" #&CDS_LOCATION = "C970" &SEC = "1" #&CDS_SEC = "1";
"A":   PN = "1"  !CDS_PN = "1";
"B":   PN = "2"  !CDS_PN = "2";
BODY = "Q_CAP","I34": LOCATION = "C405" #&CDS_LOCATION = "C405" &SEC = "1" #&CDS_SEC = "1";
"A":   PN = "1"  !CDS_PN = "1";
"B":   PN = "2"  !CDS_PN = "2";
BODY = "Q_CAP","I43": LOCATION = "C217" #&CDS_LOCATION = "C217" &SEC = "1" #&CDS_SEC = "1";
"A":   PN = "1"  !CDS_PN = "1";
"B":   PN = "2"  !CDS_PN = "2";
BODY = "Q_CAP","I45": LOCATION = "C989" #&CDS_LOCATION = "C989" &SEC = "1" #&CDS_SEC = "1";
"A":   PN = "1"  !CDS_PN = "1";
"B":   PN = "2"  !CDS_PN = "2";
BODY = "Q_CAP","I55": LOCATION = "C992" #&CDS_LOCATION = "C992" &SEC = "1" #&CDS_SEC = "1";
"A":   PN = "1"  !CDS_PN = "1";
"B":   PN = "2"  !CDS_PN = "2";
BODY = "Q_CAP","I57": LOCATION = "C987" #&CDS_LOCATION = "C987" &SEC = "1" #&CDS_SEC = "1";
"A":   PN = "1"  !CDS_PN = "1";
"B":   PN = "2"  !CDS_PN = "2";
BODY = "Q_CAP","I62": LOCATION = "C994" #&CDS_LOCATION = "C994" &SEC = "1" #&CDS_SEC = "1";
"A":   PN = "1"  !CDS_PN = "1";
"B":   PN = "2"  !CDS_PN = "2";
BODY = "Q_CAP","I83": LOCATION = "C1004" #&CDS_LOCATION = "C1004" &SEC = "1" #&CDS_SEC = "1";
"A":   PN = "1"  !CDS_PN = "1";
"B":   PN = "2"  !CDS_PN = "2";
BODY = "Q_CAP","I100": LOCATION = "C420" #&CDS_LOCATION = "C420" &SEC = "1" #&CDS_SEC = "1";
"A":   PN = "1"  !CDS_PN = "1";
"B":   PN = "2"  !CDS_PN = "2";
BODY = "Q_CAP","I106": LOCATION = "C1021" #&CDS_LOCATION = "C1021" &SEC = "1" #&CDS_SEC = "1";
"A":   PN = "1"  !CDS_PN = "1";
"B":   PN = "2"  !CDS_PN = "2";
BODY = "Q_CAP","I107": LOCATION = "C422" #&CDS_LOCATION = "C422" &SEC = "1" #&CDS_SEC = "1";
"A":   PN = "1"  !CDS_PN = "1";
"B":   PN = "2"  !CDS_PN = "2";
BODY = "Q_CAP","I108": LOCATION = "C1025" #&CDS_LOCATION = "C1025" &SEC = "1" #&CDS_SEC = "1";
"A":   PN = "1"  !CDS_PN = "1";
"B":   PN = "2"  !CDS_PN = "2";
BODY = "Q_CAP","I109": LOCATION = "C1029" #&CDS_LOCATION = "C1029" &SEC = "1" #&CDS_SEC = "1";
"A":   PN = "1"  !CDS_PN = "1";
"B":   PN = "2"  !CDS_PN = "2";
BODY = "Q_CAP","I110": LOCATION = "C1033" #&CDS_LOCATION = "C1033" &SEC = "1" #&CDS_SEC = "1";
"A":   PN = "1"  !CDS_PN = "1";
"B":   PN = "2"  !CDS_PN = "2";
BODY = "Q_CAP","I116": LOCATION = "C1018" #&CDS_LOCATION = "C1018" &SEC = "1" #&CDS_SEC = "1";
"A":   PN = "1"  !CDS_PN = "1";
"B":   PN = "2"  !CDS_PN = "2";
BODY = "Q_CAP","I117": LOCATION = "C1024" #&CDS_LOCATION = "C1024" &SEC = "1" #&CDS_SEC = "1";
"A":   PN = "1"  !CDS_PN = "1";
"B":   PN = "2"  !CDS_PN = "2";
BODY = "Q_CAP","I118": LOCATION = "C1028" #&CDS_LOCATION = "C1028" &SEC = "1" #&CDS_SEC = "1";
"A":   PN = "1"  !CDS_PN = "1";
"B":   PN = "2"  !CDS_PN = "2";
BODY = "Q_CAP","I119": LOCATION = "C1032" #&CDS_LOCATION = "C1032" &SEC = "1" #&CDS_SEC = "1";
"A":   PN = "1"  !CDS_PN = "1";
"B":   PN = "2"  !CDS_PN = "2";
BODY = "Q_CAP","I120": LOCATION = "C1023" #&CDS_LOCATION = "C1023" &SEC = "1" #&CDS_SEC = "1";
"A":   PN = "1"  !CDS_PN = "1";
"B":   PN = "2"  !CDS_PN = "2";
BODY = "Q_CAP","I121": LOCATION = "C1027" #&CDS_LOCATION = "C1027" &SEC = "1" #&CDS_SEC = "1";
"A":   PN = "1"  !CDS_PN = "1";
"B":   PN = "2"  !CDS_PN = "2";
BODY = "Q_CAP","I122": LOCATION = "C1022" #&CDS_LOCATION = "C1022" &SEC = "1" #&CDS_SEC = "1";
"A":   PN = "1"  !CDS_PN = "1";
"B":   PN = "2"  !CDS_PN = "2";
BODY = "Q_CAP","I123": LOCATION = "C1026" #&CDS_LOCATION = "C1026" &SEC = "1" #&CDS_SEC = "1";
"A":   PN = "1"  !CDS_PN = "1";
"B":   PN = "2"  !CDS_PN = "2";
BODY = "Q_CAP","I124": LOCATION = "C1031" #&CDS_LOCATION = "C1031" &SEC = "1" #&CDS_SEC = "1";
"A":   PN = "1"  !CDS_PN = "1";
"B":   PN = "2"  !CDS_PN = "2";
BODY = "Q_CAP","I125": LOCATION = "C1030" #&CDS_LOCATION = "C1030" &SEC = "1" #&CDS_SEC = "1";
"A":   PN = "1"  !CDS_PN = "1";
"B":   PN = "2"  !CDS_PN = "2";
BODY = "Q_CAP","I127": LOCATION = "C1037" #&CDS_LOCATION = "C1037" &SEC = "1" #&CDS_SEC = "1";
"A":   PN = "1"  !CDS_PN = "1";
"B":   PN = "2"  !CDS_PN = "2";
BODY = "Q_CAP","I128": LOCATION = "C1041" #&CDS_LOCATION = "C1041" &SEC = "1" #&CDS_SEC = "1";
"A":   PN = "1"  !CDS_PN = "1";
"B":   PN = "2"  !CDS_PN = "2";
BODY = "Q_CAP","I130": LOCATION = "C1045" #&CDS_LOCATION = "C1045" &SEC = "1" #&CDS_SEC = "1";
"A":   PN = "1"  !CDS_PN = "1";
"B":   PN = "2"  !CDS_PN = "2";
DRAWING = "@s9s_mb_2u_lib.s9s_mb_2u(sch_1):page75";
BODY = "Q_CAP","I1": LOCATION = "C493" #&CDS_LOCATION = "C493" &SEC = "1" #&CDS_SEC = "1";
"A":   PN = "1"  !CDS_PN = "1";
"B":   PN = "2"  !CDS_PN = "2";
BODY = "Q_CAP","I3": LOCATION = "C497" #&CDS_LOCATION = "C497" &SEC = "1" #&CDS_SEC = "1";
"A":   PN = "1"  !CDS_PN = "1";
"B":   PN = "2"  !CDS_PN = "2";
BODY = "Q_CAP","I4": LOCATION = "C501" #&CDS_LOCATION = "C501" &SEC = "1" #&CDS_SEC = "1";
"A":   PN = "1"  !CDS_PN = "1";
"B":   PN = "2"  !CDS_PN = "2";
BODY = "Q_CAP","I14": LOCATION = "C532" #&CDS_LOCATION = "C532" &SEC = "1" #&CDS_SEC = "1";
"A":   PN = "1"  !CDS_PN = "1";
"B":   PN = "2"  !CDS_PN = "2";
BODY = "Q_CAP","I25": LOCATION = "C359" #&CDS_LOCATION = "C359" &SEC = "1" #&CDS_SEC = "1";
"A":   PN = "1"  !CDS_PN = "1";
"B":   PN = "2"  !CDS_PN = "2";
BODY = "Q_CAP","I26": LOCATION = "C362" #&CDS_LOCATION = "C362" &SEC = "1" #&CDS_SEC = "1";
"A":   PN = "1"  !CDS_PN = "1";
"B":   PN = "2"  !CDS_PN = "2";
BODY = "Q_CAP","I27": LOCATION = "C358" #&CDS_LOCATION = "C358" &SEC = "1" #&CDS_SEC = "1";
"A":   PN = "1"  !CDS_PN = "1";
"B":   PN = "2"  !CDS_PN = "2";
BODY = "Q_CAP","I28": LOCATION = "C361" #&CDS_LOCATION = "C361" &SEC = "1" #&CDS_SEC = "1";
"A":   PN = "1"  !CDS_PN = "1";
"B":   PN = "2"  !CDS_PN = "2";
BODY = "Q_CAP","I33": LOCATION = "C368" #&CDS_LOCATION = "C368" &SEC = "1" #&CDS_SEC = "1";
"A":   PN = "1"  !CDS_PN = "1";
"B":   PN = "2"  !CDS_PN = "2";
BODY = "Q_CAP","I43": LOCATION = "C1396" #&CDS_LOCATION = "C1396" &SEC = "1" #&CDS_SEC = "1";
"A":   PN = "1"  !CDS_PN = "1";
"B":   PN = "2"  !CDS_PN = "2";
BODY = "Q_CAP","I44": LOCATION = "C1397" #&CDS_LOCATION = "C1397" &SEC = "1" #&CDS_SEC = "1";
"A":   PN = "1"  !CDS_PN = "1";
"B":   PN = "2"  !CDS_PN = "2";
BODY = "Q_CAP","I49": LOCATION = "C391" #&CDS_LOCATION = "C391" &SEC = "1" #&CDS_SEC = "1";
"A":   PN = "1"  !CDS_PN = "1";
"B":   PN = "2"  !CDS_PN = "2";
BODY = "Q_CAP","I50": LOCATION = "C379" #&CDS_LOCATION = "C379" &SEC = "1" #&CDS_SEC = "1";
"A":   PN = "1"  !CDS_PN = "1";
"B":   PN = "2"  !CDS_PN = "2";
BODY = "Q_CAP","I52": LOCATION = "C393" #&CDS_LOCATION = "C393" &SEC = "1" #&CDS_SEC = "1";
"A":   PN = "1"  !CDS_PN = "1";
"B":   PN = "2"  !CDS_PN = "2";
BODY = "Q_CAP","I54": LOCATION = "C360" #&CDS_LOCATION = "C360" &SEC = "1" #&CDS_SEC = "1";
"A":   PN = "1"  !CDS_PN = "1";
"B":   PN = "2"  !CDS_PN = "2";
BODY = "Q_CAP","I67": LOCATION = "C381" #&CDS_LOCATION = "C381" &SEC = "1" #&CDS_SEC = "1";
"A":   PN = "1"  !CDS_PN = "1";
"B":   PN = "2"  !CDS_PN = "2";
BODY = "Q_CAP","I6": LOCATION = "C505" #&CDS_LOCATION = "C505" &SEC = "1" #&CDS_SEC = "1";
"A":   PN = "1"  !CDS_PN = "1";
"B":   PN = "2"  !CDS_PN = "2";
BODY = "Q_CAP","I8": LOCATION = "C509" #&CDS_LOCATION = "C509" &SEC = "1" #&CDS_SEC = "1";
"A":   PN = "1"  !CDS_PN = "1";
"B":   PN = "2"  !CDS_PN = "2";
BODY = "Q_CAP","I9": LOCATION = "C522" #&CDS_LOCATION = "C522" &SEC = "1" #&CDS_SEC = "1";
"A":   PN = "1"  !CDS_PN = "1";
"B":   PN = "2"  !CDS_PN = "2";
BODY = "Q_CAP","I11": LOCATION = "C492" #&CDS_LOCATION = "C492" &SEC = "1" #&CDS_SEC = "1";
"A":   PN = "1"  !CDS_PN = "1";
"B":   PN = "2"  !CDS_PN = "2";
BODY = "Q_CAP","I13": LOCATION = "C491" #&CDS_LOCATION = "C491" &SEC = "1" #&CDS_SEC = "1";
"A":   PN = "1"  !CDS_PN = "1";
"B":   PN = "2"  !CDS_PN = "2";
BODY = "Q_CAP","I16": LOCATION = "C496" #&CDS_LOCATION = "C496" &SEC = "1" #&CDS_SEC = "1";
"A":   PN = "1"  !CDS_PN = "1";
"B":   PN = "2"  !CDS_PN = "2";
BODY = "Q_CAP","I17": LOCATION = "C533" #&CDS_LOCATION = "C533" &SEC = "1" #&CDS_SEC = "1";
"A":   PN = "1"  !CDS_PN = "1";
"B":   PN = "2"  !CDS_PN = "2";
BODY = "Q_CAP","I18": LOCATION = "C495" #&CDS_LOCATION = "C495" &SEC = "1" #&CDS_SEC = "1";
"A":   PN = "1"  !CDS_PN = "1";
"B":   PN = "2"  !CDS_PN = "2";
BODY = "Q_CAP","I19": LOCATION = "C515" #&CDS_LOCATION = "C515" &SEC = "1" #&CDS_SEC = "1";
"A":   PN = "1"  !CDS_PN = "1";
"B":   PN = "2"  !CDS_PN = "2";
BODY = "Q_CAP","I21": LOCATION = "C356" #&CDS_LOCATION = "C356" &SEC = "1" #&CDS_SEC = "1";
"A":   PN = "1"  !CDS_PN = "1";
"B":   PN = "2"  !CDS_PN = "2";
BODY = "Q_CAP","I23": LOCATION = "C355" #&CDS_LOCATION = "C355" &SEC = "1" #&CDS_SEC = "1";
"A":   PN = "1"  !CDS_PN = "1";
"B":   PN = "2"  !CDS_PN = "2";
BODY = "Q_CAP","I29": LOCATION = "C534" #&CDS_LOCATION = "C534" &SEC = "1" #&CDS_SEC = "1";
"A":   PN = "1"  !CDS_PN = "1";
"B":   PN = "2"  !CDS_PN = "2";
BODY = "Q_CAP","I31": LOCATION = "C518" #&CDS_LOCATION = "C518" &SEC = "1" #&CDS_SEC = "1";
"A":   PN = "1"  !CDS_PN = "1";
"B":   PN = "2"  !CDS_PN = "2";
BODY = "Q_CAP","I32": LOCATION = "C365" #&CDS_LOCATION = "C365" &SEC = "1" #&CDS_SEC = "1";
"A":   PN = "1"  !CDS_PN = "1";
"B":   PN = "2"  !CDS_PN = "2";
BODY = "Q_CAP","I34": LOCATION = "C364" #&CDS_LOCATION = "C364" &SEC = "1" #&CDS_SEC = "1";
"A":   PN = "1"  !CDS_PN = "1";
"B":   PN = "2"  !CDS_PN = "2";
BODY = "Q_CAP","I35": LOCATION = "C367" #&CDS_LOCATION = "C367" &SEC = "1" #&CDS_SEC = "1";
"A":   PN = "1"  !CDS_PN = "1";
"B":   PN = "2"  !CDS_PN = "2";
BODY = "Q_CAP","I36": LOCATION = "C371" #&CDS_LOCATION = "C371" &SEC = "1" #&CDS_SEC = "1";
"A":   PN = "1"  !CDS_PN = "1";
"B":   PN = "2"  !CDS_PN = "2";
BODY = "Q_CAP","I37": LOCATION = "C397" #&CDS_LOCATION = "C397" &SEC = "1" #&CDS_SEC = "1";
"A":   PN = "1"  !CDS_PN = "1";
"B":   PN = "2"  !CDS_PN = "2";
BODY = "Q_CAP","I38": LOCATION = "C357" #&CDS_LOCATION = "C357" &SEC = "1" #&CDS_SEC = "1";
"A":   PN = "1"  !CDS_PN = "1";
"B":   PN = "2"  !CDS_PN = "2";
BODY = "Q_CAP","I39": LOCATION = "C370" #&CDS_LOCATION = "C370" &SEC = "1" #&CDS_SEC = "1";
"A":   PN = "1"  !CDS_PN = "1";
"B":   PN = "2"  !CDS_PN = "2";
BODY = "Q_CAP","I40": LOCATION = "C373" #&CDS_LOCATION = "C373" &SEC = "1" #&CDS_SEC = "1";
"A":   PN = "1"  !CDS_PN = "1";
"B":   PN = "2"  !CDS_PN = "2";
BODY = "Q_CAP","I41": LOCATION = "C376" #&CDS_LOCATION = "C376" &SEC = "1" #&CDS_SEC = "1";
"A":   PN = "1"  !CDS_PN = "1";
"B":   PN = "2"  !CDS_PN = "2";
BODY = "Q_CAP","I46": LOCATION = "C395" #&CDS_LOCATION = "C395" &SEC = "1" #&CDS_SEC = "1";
"A":   PN = "1"  !CDS_PN = "1";
"B":   PN = "2"  !CDS_PN = "2";
BODY = "Q_CAP","I47": LOCATION = "C1405" #&CDS_LOCATION = "C1405" &SEC = "1" #&CDS_SEC = "1";
"A":   PN = "1"  !CDS_PN = "1";
"B":   PN = "2"  !CDS_PN = "2";
BODY = "Q_CAP","I48": LOCATION = "C389" #&CDS_LOCATION = "C389" &SEC = "1" #&CDS_SEC = "1";
"A":   PN = "1"  !CDS_PN = "1";
"B":   PN = "2"  !CDS_PN = "2";
BODY = "Q_CAP","I51": LOCATION = "C382" #&CDS_LOCATION = "C382" &SEC = "1" #&CDS_SEC = "1";
"A":   PN = "1"  !CDS_PN = "1";
"B":   PN = "2"  !CDS_PN = "2";
BODY = "Q_CAP","I55": LOCATION = "C385" #&CDS_LOCATION = "C385" &SEC = "1" #&CDS_SEC = "1";
"A":   PN = "1"  !CDS_PN = "1";
"B":   PN = "2"  !CDS_PN = "2";
BODY = "Q_CAP","I56": LOCATION = "C387" #&CDS_LOCATION = "C387" &SEC = "1" #&CDS_SEC = "1";
"A":   PN = "1"  !CDS_PN = "1";
"B":   PN = "2"  !CDS_PN = "2";
BODY = "Q_CAP","I58": LOCATION = "C1398" #&CDS_LOCATION = "C1398" &SEC = "1" #&CDS_SEC = "1";
"A":   PN = "1"  !CDS_PN = "1";
"B":   PN = "2"  !CDS_PN = "2";
BODY = "Q_CAP","I59": LOCATION = "C1436" #&CDS_LOCATION = "C1436" &SEC = "1" #&CDS_SEC = "1";
"A":   PN = "1"  !CDS_PN = "1";
"B":   PN = "2"  !CDS_PN = "2";
BODY = "Q_CAP","I61": LOCATION = "C1406" #&CDS_LOCATION = "C1406" &SEC = "1" #&CDS_SEC = "1";
"A":   PN = "1"  !CDS_PN = "1";
"B":   PN = "2"  !CDS_PN = "2";
BODY = "Q_CAP","I62": LOCATION = "C1407" #&CDS_LOCATION = "C1407" &SEC = "1" #&CDS_SEC = "1";
"A":   PN = "1"  !CDS_PN = "1";
"B":   PN = "2"  !CDS_PN = "2";
BODY = "Q_CAP","I64": LOCATION = "C363" #&CDS_LOCATION = "C363" &SEC = "1" #&CDS_SEC = "1";
"A":   PN = "1"  !CDS_PN = "1";
"B":   PN = "2"  !CDS_PN = "2";
BODY = "Q_CAP","I68": LOCATION = "C527" #&CDS_LOCATION = "C527" &SEC = "1" #&CDS_SEC = "1";
"A":   PN = "1"  !CDS_PN = "1";
"B":   PN = "2"  !CDS_PN = "2";
DRAWING = "@s9s_mb_2u_lib.s9s_mb_2u(sch_1):page76";
BODY = "Q_CAP","I1": LOCATION = "C494" #&CDS_LOCATION = "C494" &SEC = "1" #&CDS_SEC = "1";
"A":   PN = "1"  !CDS_PN = "1";
"B":   PN = "2"  !CDS_PN = "2";
BODY = "Q_CAP","I6": LOCATION = "C528" #&CDS_LOCATION = "C528" &SEC = "1" #&CDS_SEC = "1";
"A":   PN = "1"  !CDS_PN = "1";
"B":   PN = "2"  !CDS_PN = "2";
BODY = "Q_CAP","I7": LOCATION = "C530" #&CDS_LOCATION = "C530" &SEC = "1" #&CDS_SEC = "1";
"A":   PN = "1"  !CDS_PN = "1";
"B":   PN = "2"  !CDS_PN = "2";
BODY = "Q_CAP","I13": LOCATION = "C1399" #&CDS_LOCATION = "C1399" &SEC = "1" #&CDS_SEC = "1";
"A":   PN = "1"  !CDS_PN = "1";
"B":   PN = "2"  !CDS_PN = "2";
BODY = "Q_CAP","I18": LOCATION = "C499" #&CDS_LOCATION = "C499" &SEC = "1" #&CDS_SEC = "1";
"A":   PN = "1"  !CDS_PN = "1";
"B":   PN = "2"  !CDS_PN = "2";
BODY = "Q_CAP","I20": LOCATION = "C503" #&CDS_LOCATION = "C503" &SEC = "1" #&CDS_SEC = "1";
"A":   PN = "1"  !CDS_PN = "1";
"B":   PN = "2"  !CDS_PN = "2";
BODY = "Q_CAP","I27": LOCATION = "C510" #&CDS_LOCATION = "C510" &SEC = "1" #&CDS_SEC = "1";
"A":   PN = "1"  !CDS_PN = "1";
"B":   PN = "2"  !CDS_PN = "2";
BODY = "Q_CAP","I28": LOCATION = "C514" #&CDS_LOCATION = "C514" &SEC = "1" #&CDS_SEC = "1";
"A":   PN = "1"  !CDS_PN = "1";
"B":   PN = "2"  !CDS_PN = "2";
BODY = "Q_CAP","I29": LOCATION = "C517" #&CDS_LOCATION = "C517" &SEC = "1" #&CDS_SEC = "1";
"A":   PN = "1"  !CDS_PN = "1";
"B":   PN = "2"  !CDS_PN = "2";
BODY = "Q_CAP","I31": LOCATION = "C531" #&CDS_LOCATION = "C531" &SEC = "1" #&CDS_SEC = "1";
"A":   PN = "1"  !CDS_PN = "1";
"B":   PN = "2"  !CDS_PN = "2";
BODY = "Q_CAP","I41": LOCATION = "C529" #&CDS_LOCATION = "C529" &SEC = "1" #&CDS_SEC = "1";
"A":   PN = "1"  !CDS_PN = "1";
"B":   PN = "2"  !CDS_PN = "2";
BODY = "Q_CAP","I46": LOCATION = "C396" #&CDS_LOCATION = "C396" &SEC = "1" #&CDS_SEC = "1";
"A":   PN = "1"  !CDS_PN = "1";
"B":   PN = "2"  !CDS_PN = "2";
BODY = "Q_CAP","I47": LOCATION = "C398" #&CDS_LOCATION = "C398" &SEC = "1" #&CDS_SEC = "1";
"A":   PN = "1"  !CDS_PN = "1";
"B":   PN = "2"  !CDS_PN = "2";
BODY = "Q_CAP","I2": LOCATION = "C498" #&CDS_LOCATION = "C498" &SEC = "1" #&CDS_SEC = "1";
"A":   PN = "1"  !CDS_PN = "1";
"B":   PN = "2"  !CDS_PN = "2";
BODY = "Q_CAP","I3": LOCATION = "C502" #&CDS_LOCATION = "C502" &SEC = "1" #&CDS_SEC = "1";
"A":   PN = "1"  !CDS_PN = "1";
"B":   PN = "2"  !CDS_PN = "2";
BODY = "Q_CAP","I5": LOCATION = "C525" #&CDS_LOCATION = "C525" &SEC = "1" #&CDS_SEC = "1";
"A":   PN = "1"  !CDS_PN = "1";
"B":   PN = "2"  !CDS_PN = "2";
BODY = "Q_CAP","I9": LOCATION = "C500" #&CDS_LOCATION = "C500" &SEC = "1" #&CDS_SEC = "1";
"A":   PN = "1"  !CDS_PN = "1";
"B":   PN = "2"  !CDS_PN = "2";
BODY = "Q_CAP","I10": LOCATION = "C504" #&CDS_LOCATION = "C504" &SEC = "1" #&CDS_SEC = "1";
"A":   PN = "1"  !CDS_PN = "1";
"B":   PN = "2"  !CDS_PN = "2";
BODY = "Q_CAP","I11": LOCATION = "C508" #&CDS_LOCATION = "C508" &SEC = "1" #&CDS_SEC = "1";
"A":   PN = "1"  !CDS_PN = "1";
"B":   PN = "2"  !CDS_PN = "2";
BODY = "Q_CAP","I14": LOCATION = "C1400" #&CDS_LOCATION = "C1400" &SEC = "1" #&CDS_SEC = "1";
"A":   PN = "1"  !CDS_PN = "1";
"B":   PN = "2"  !CDS_PN = "2";
BODY = "Q_CAP","I16": LOCATION = "C1362" #&CDS_LOCATION = "C1362" &SEC = "1" #&CDS_SEC = "1";
"A":   PN = "1"  !CDS_PN = "1";
"B":   PN = "2"  !CDS_PN = "2";
BODY = "Q_CAP","I21": LOCATION = "C507" #&CDS_LOCATION = "C507" &SEC = "1" #&CDS_SEC = "1";
"A":   PN = "1"  !CDS_PN = "1";
"B":   PN = "2"  !CDS_PN = "2";
BODY = "Q_CAP","I22": LOCATION = "C386" #&CDS_LOCATION = "C386" &SEC = "1" #&CDS_SEC = "1";
"A":   PN = "1"  !CDS_PN = "1";
"B":   PN = "2"  !CDS_PN = "2";
BODY = "Q_CAP","I23": LOCATION = "C388" #&CDS_LOCATION = "C388" &SEC = "1" #&CDS_SEC = "1";
"A":   PN = "1"  !CDS_PN = "1";
"B":   PN = "2"  !CDS_PN = "2";
BODY = "Q_CAP","I25": LOCATION = "C390" #&CDS_LOCATION = "C390" &SEC = "1" #&CDS_SEC = "1";
"A":   PN = "1"  !CDS_PN = "1";
"B":   PN = "2"  !CDS_PN = "2";
BODY = "Q_CAP","I26": LOCATION = "C506" #&CDS_LOCATION = "C506" &SEC = "1" #&CDS_SEC = "1";
"A":   PN = "1"  !CDS_PN = "1";
"B":   PN = "2"  !CDS_PN = "2";
BODY = "Q_CAP","I32": LOCATION = "C512" #&CDS_LOCATION = "C512" &SEC = "1" #&CDS_SEC = "1";
"A":   PN = "1"  !CDS_PN = "1";
"B":   PN = "2"  !CDS_PN = "2";
BODY = "Q_CAP","I33": LOCATION = "C516" #&CDS_LOCATION = "C516" &SEC = "1" #&CDS_SEC = "1";
"A":   PN = "1"  !CDS_PN = "1";
"B":   PN = "2"  !CDS_PN = "2";
BODY = "Q_CAP","I35": LOCATION = "C519" #&CDS_LOCATION = "C519" &SEC = "1" #&CDS_SEC = "1";
"A":   PN = "1"  !CDS_PN = "1";
"B":   PN = "2"  !CDS_PN = "2";
BODY = "Q_CAP","I36": LOCATION = "C520" #&CDS_LOCATION = "C520" &SEC = "1" #&CDS_SEC = "1";
"A":   PN = "1"  !CDS_PN = "1";
"B":   PN = "2"  !CDS_PN = "2";
BODY = "Q_CAP","I37": LOCATION = "C521" #&CDS_LOCATION = "C521" &SEC = "1" #&CDS_SEC = "1";
"A":   PN = "1"  !CDS_PN = "1";
"B":   PN = "2"  !CDS_PN = "2";
BODY = "Q_CAP","I38": LOCATION = "C523" #&CDS_LOCATION = "C523" &SEC = "1" #&CDS_SEC = "1";
"A":   PN = "1"  !CDS_PN = "1";
"B":   PN = "2"  !CDS_PN = "2";
BODY = "Q_CAP","I39": LOCATION = "C526" #&CDS_LOCATION = "C526" &SEC = "1" #&CDS_SEC = "1";
"A":   PN = "1"  !CDS_PN = "1";
"B":   PN = "2"  !CDS_PN = "2";
BODY = "Q_CAP","I43": LOCATION = "C511" #&CDS_LOCATION = "C511" &SEC = "1" #&CDS_SEC = "1";
"A":   PN = "1"  !CDS_PN = "1";
"B":   PN = "2"  !CDS_PN = "2";
BODY = "Q_CAP","I44": LOCATION = "C392" #&CDS_LOCATION = "C392" &SEC = "1" #&CDS_SEC = "1";
"A":   PN = "1"  !CDS_PN = "1";
"B":   PN = "2"  !CDS_PN = "2";
BODY = "Q_CAP","I45": LOCATION = "C394" #&CDS_LOCATION = "C394" &SEC = "1" #&CDS_SEC = "1";
"A":   PN = "1"  !CDS_PN = "1";
"B":   PN = "2"  !CDS_PN = "2";
BODY = "Q_CAP","I48": LOCATION = "C366" #&CDS_LOCATION = "C366" &SEC = "1" #&CDS_SEC = "1";
"A":   PN = "1"  !CDS_PN = "1";
"B":   PN = "2"  !CDS_PN = "2";
BODY = "Q_CAP","I49": LOCATION = "C369" #&CDS_LOCATION = "C369" &SEC = "1" #&CDS_SEC = "1";
"A":   PN = "1"  !CDS_PN = "1";
"B":   PN = "2"  !CDS_PN = "2";
BODY = "Q_CAP","I50": LOCATION = "C372" #&CDS_LOCATION = "C372" &SEC = "1" #&CDS_SEC = "1";
"A":   PN = "1"  !CDS_PN = "1";
"B":   PN = "2"  !CDS_PN = "2";
BODY = "Q_CAP","I51": LOCATION = "C374" #&CDS_LOCATION = "C374" &SEC = "1" #&CDS_SEC = "1";
"A":   PN = "1"  !CDS_PN = "1";
"B":   PN = "2"  !CDS_PN = "2";
BODY = "Q_CAP","I52": LOCATION = "C377" #&CDS_LOCATION = "C377" &SEC = "1" #&CDS_SEC = "1";
"A":   PN = "1"  !CDS_PN = "1";
"B":   PN = "2"  !CDS_PN = "2";
BODY = "Q_CAP","I53": LOCATION = "C380" #&CDS_LOCATION = "C380" &SEC = "1" #&CDS_SEC = "1";
"A":   PN = "1"  !CDS_PN = "1";
"B":   PN = "2"  !CDS_PN = "2";
BODY = "Q_CAP","I54": LOCATION = "C383" #&CDS_LOCATION = "C383" &SEC = "1" #&CDS_SEC = "1";
"A":   PN = "1"  !CDS_PN = "1";
"B":   PN = "2"  !CDS_PN = "2";
DRAWING = "@s9s_mb_2u_lib.s9s_mb_2u(sch_1):page77";
BODY = "Q_CAP","I1": LOCATION = "C424" #&CDS_LOCATION = "C424" &SEC = "1" #&CDS_SEC = "1";
"A":   PN = "1"  !CDS_PN = "1";
"B":   PN = "2"  !CDS_PN = "2";
BODY = "Q_CAP","I4": LOCATION = "C428" #&CDS_LOCATION = "C428" &SEC = "1" #&CDS_SEC = "1";
"A":   PN = "1"  !CDS_PN = "1";
"B":   PN = "2"  !CDS_PN = "2";
BODY = "Q_CAP","I5": LOCATION = "C430" #&CDS_LOCATION = "C430" &SEC = "1" #&CDS_SEC = "1";
"A":   PN = "1"  !CDS_PN = "1";
"B":   PN = "2"  !CDS_PN = "2";
BODY = "Q_CAP","I7": LOCATION = "C423" #&CDS_LOCATION = "C423" &SEC = "1" #&CDS_SEC = "1";
"A":   PN = "1"  !CDS_PN = "1";
"B":   PN = "2"  !CDS_PN = "2";
BODY = "Q_CAP","I8": LOCATION = "C425" #&CDS_LOCATION = "C425" &SEC = "1" #&CDS_SEC = "1";
"A":   PN = "1"  !CDS_PN = "1";
"B":   PN = "2"  !CDS_PN = "2";
BODY = "Q_CAP","I10": LOCATION = "C225" #&CDS_LOCATION = "C225" &SEC = "1" #&CDS_SEC = "1";
"A":   PN = "1"  !CDS_PN = "1";
"B":   PN = "2"  !CDS_PN = "2";
BODY = "Q_CAP","I11": LOCATION = "C230" #&CDS_LOCATION = "C230" &SEC = "1" #&CDS_SEC = "1";
"A":   PN = "1"  !CDS_PN = "1";
"B":   PN = "2"  !CDS_PN = "2";
BODY = "Q_CAP","I13": LOCATION = "C224" #&CDS_LOCATION = "C224" &SEC = "1" #&CDS_SEC = "1";
"A":   PN = "1"  !CDS_PN = "1";
"B":   PN = "2"  !CDS_PN = "2";
BODY = "Q_CAP","I15": LOCATION = "C427" #&CDS_LOCATION = "C427" &SEC = "1" #&CDS_SEC = "1";
"A":   PN = "1"  !CDS_PN = "1";
"B":   PN = "2"  !CDS_PN = "2";
BODY = "Q_CAP","I17": LOCATION = "C429" #&CDS_LOCATION = "C429" &SEC = "1" #&CDS_SEC = "1";
"A":   PN = "1"  !CDS_PN = "1";
"B":   PN = "2"  !CDS_PN = "2";
BODY = "Q_CAP","I18": LOCATION = "C240" #&CDS_LOCATION = "C240" &SEC = "1" #&CDS_SEC = "1";
"A":   PN = "1"  !CDS_PN = "1";
"B":   PN = "2"  !CDS_PN = "2";
BODY = "Q_CAP","I19": LOCATION = "C234" #&CDS_LOCATION = "C234" &SEC = "1" #&CDS_SEC = "1";
"A":   PN = "1"  !CDS_PN = "1";
"B":   PN = "2"  !CDS_PN = "2";
BODY = "Q_CAP","I20": LOCATION = "C239" #&CDS_LOCATION = "C239" &SEC = "1" #&CDS_SEC = "1";
"A":   PN = "1"  !CDS_PN = "1";
"B":   PN = "2"  !CDS_PN = "2";
BODY = "Q_CAP","I22": LOCATION = "C223" #&CDS_LOCATION = "C223" &SEC = "1" #&CDS_SEC = "1";
"A":   PN = "1"  !CDS_PN = "1";
"B":   PN = "2"  !CDS_PN = "2";
BODY = "Q_CAP","I23": LOCATION = "C228" #&CDS_LOCATION = "C228" &SEC = "1" #&CDS_SEC = "1";
"A":   PN = "1"  !CDS_PN = "1";
"B":   PN = "2"  !CDS_PN = "2";
BODY = "Q_CAP","I25": LOCATION = "C222" #&CDS_LOCATION = "C222" &SEC = "1" #&CDS_SEC = "1";
"A":   PN = "1"  !CDS_PN = "1";
"B":   PN = "2"  !CDS_PN = "2";
BODY = "Q_CAP","I28": LOCATION = "C221" #&CDS_LOCATION = "C221" &SEC = "1" #&CDS_SEC = "1";
"A":   PN = "1"  !CDS_PN = "1";
"B":   PN = "2"  !CDS_PN = "2";
BODY = "Q_CAP","I29": LOCATION = "C226" #&CDS_LOCATION = "C226" &SEC = "1" #&CDS_SEC = "1";
"A":   PN = "1"  !CDS_PN = "1";
"B":   PN = "2"  !CDS_PN = "2";
BODY = "Q_CAP","I30": LOCATION = "C233" #&CDS_LOCATION = "C233" &SEC = "1" #&CDS_SEC = "1";
"A":   PN = "1"  !CDS_PN = "1";
"B":   PN = "2"  !CDS_PN = "2";
BODY = "Q_CAP","I31": LOCATION = "C238" #&CDS_LOCATION = "C238" &SEC = "1" #&CDS_SEC = "1";
"A":   PN = "1"  !CDS_PN = "1";
"B":   PN = "2"  !CDS_PN = "2";
BODY = "Q_CAP","I32": LOCATION = "C232" #&CDS_LOCATION = "C232" &SEC = "1" #&CDS_SEC = "1";
"A":   PN = "1"  !CDS_PN = "1";
"B":   PN = "2"  !CDS_PN = "2";
BODY = "Q_CAP","I33": LOCATION = "C231" #&CDS_LOCATION = "C231" &SEC = "1" #&CDS_SEC = "1";
"A":   PN = "1"  !CDS_PN = "1";
"B":   PN = "2"  !CDS_PN = "2";
BODY = "Q_CAP","I34": LOCATION = "C237" #&CDS_LOCATION = "C237" &SEC = "1" #&CDS_SEC = "1";
"A":   PN = "1"  !CDS_PN = "1";
"B":   PN = "2"  !CDS_PN = "2";
BODY = "Q_CAP","I35": LOCATION = "C236" #&CDS_LOCATION = "C236" &SEC = "1" #&CDS_SEC = "1";
"A":   PN = "1"  !CDS_PN = "1";
"B":   PN = "2"  !CDS_PN = "2";
BODY = "Q_CAP","I37": LOCATION = "C431" #&CDS_LOCATION = "C431" &SEC = "1" #&CDS_SEC = "1";
"A":   PN = "1"  !CDS_PN = "1";
"B":   PN = "2"  !CDS_PN = "2";
BODY = "Q_CAP","I38": LOCATION = "C433" #&CDS_LOCATION = "C433" &SEC = "1" #&CDS_SEC = "1";
"A":   PN = "1"  !CDS_PN = "1";
"B":   PN = "2"  !CDS_PN = "2";
BODY = "Q_CAP","I39": LOCATION = "C435" #&CDS_LOCATION = "C435" &SEC = "1" #&CDS_SEC = "1";
"A":   PN = "1"  !CDS_PN = "1";
"B":   PN = "2"  !CDS_PN = "2";
BODY = "Q_CAP","I41": LOCATION = "C245" #&CDS_LOCATION = "C245" &SEC = "1" #&CDS_SEC = "1";
"A":   PN = "1"  !CDS_PN = "1";
"B":   PN = "2"  !CDS_PN = "2";
BODY = "Q_CAP","I42": LOCATION = "C432" #&CDS_LOCATION = "C432" &SEC = "1" #&CDS_SEC = "1";
"A":   PN = "1"  !CDS_PN = "1";
"B":   PN = "2"  !CDS_PN = "2";
BODY = "Q_CAP","I44": LOCATION = "C250" #&CDS_LOCATION = "C250" &SEC = "1" #&CDS_SEC = "1";
"A":   PN = "1"  !CDS_PN = "1";
"B":   PN = "2"  !CDS_PN = "2";
BODY = "Q_CAP","I45": LOCATION = "C244" #&CDS_LOCATION = "C244" &SEC = "1" #&CDS_SEC = "1";
"A":   PN = "1"  !CDS_PN = "1";
"B":   PN = "2"  !CDS_PN = "2";
BODY = "Q_CAP","I46": LOCATION = "C249" #&CDS_LOCATION = "C249" &SEC = "1" #&CDS_SEC = "1";
"A":   PN = "1"  !CDS_PN = "1";
"B":   PN = "2"  !CDS_PN = "2";
BODY = "Q_CAP","I47": LOCATION = "C434" #&CDS_LOCATION = "C434" &SEC = "1" #&CDS_SEC = "1";
"A":   PN = "1"  !CDS_PN = "1";
"B":   PN = "2"  !CDS_PN = "2";
BODY = "Q_CAP","I48": LOCATION = "C255" #&CDS_LOCATION = "C255" &SEC = "1" #&CDS_SEC = "1";
"A":   PN = "1"  !CDS_PN = "1";
"B":   PN = "2"  !CDS_PN = "2";
BODY = "Q_CAP","I49": LOCATION = "C436" #&CDS_LOCATION = "C436" &SEC = "1" #&CDS_SEC = "1";
"A":   PN = "1"  !CDS_PN = "1";
"B":   PN = "2"  !CDS_PN = "2";
BODY = "Q_CAP","I50": LOCATION = "C260" #&CDS_LOCATION = "C260" &SEC = "1" #&CDS_SEC = "1";
"A":   PN = "1"  !CDS_PN = "1";
"B":   PN = "2"  !CDS_PN = "2";
BODY = "Q_CAP","I51": LOCATION = "C254" #&CDS_LOCATION = "C254" &SEC = "1" #&CDS_SEC = "1";
"A":   PN = "1"  !CDS_PN = "1";
"B":   PN = "2"  !CDS_PN = "2";
BODY = "Q_CAP","I52": LOCATION = "C259" #&CDS_LOCATION = "C259" &SEC = "1" #&CDS_SEC = "1";
"A":   PN = "1"  !CDS_PN = "1";
"B":   PN = "2"  !CDS_PN = "2";
BODY = "Q_CAP","I53": LOCATION = "C439" #&CDS_LOCATION = "C439" &SEC = "1" #&CDS_SEC = "1";
"A":   PN = "1"  !CDS_PN = "1";
"B":   PN = "2"  !CDS_PN = "2";
BODY = "Q_CAP","I55": LOCATION = "C441" #&CDS_LOCATION = "C441" &SEC = "1" #&CDS_SEC = "1";
"A":   PN = "1"  !CDS_PN = "1";
"B":   PN = "2"  !CDS_PN = "2";
BODY = "Q_CAP","I57": LOCATION = "C442" #&CDS_LOCATION = "C442" &SEC = "1" #&CDS_SEC = "1";
"A":   PN = "1"  !CDS_PN = "1";
"B":   PN = "2"  !CDS_PN = "2";
BODY = "Q_CAP","I58": LOCATION = "C438" #&CDS_LOCATION = "C438" &SEC = "1" #&CDS_SEC = "1";
"A":   PN = "1"  !CDS_PN = "1";
"B":   PN = "2"  !CDS_PN = "2";
BODY = "Q_CAP","I59": LOCATION = "C265" #&CDS_LOCATION = "C265" &SEC = "1" #&CDS_SEC = "1";
"A":   PN = "1"  !CDS_PN = "1";
"B":   PN = "2"  !CDS_PN = "2";
BODY = "Q_CAP","I61": LOCATION = "C440" #&CDS_LOCATION = "C440" &SEC = "1" #&CDS_SEC = "1";
"A":   PN = "1"  !CDS_PN = "1";
"B":   PN = "2"  !CDS_PN = "2";
BODY = "Q_CAP","I62": LOCATION = "C270" #&CDS_LOCATION = "C270" &SEC = "1" #&CDS_SEC = "1";
"A":   PN = "1"  !CDS_PN = "1";
"B":   PN = "2"  !CDS_PN = "2";
BODY = "Q_CAP","I63": LOCATION = "C264" #&CDS_LOCATION = "C264" &SEC = "1" #&CDS_SEC = "1";
"A":   PN = "1"  !CDS_PN = "1";
"B":   PN = "2"  !CDS_PN = "2";
BODY = "Q_CAP","I66": LOCATION = "C274" #&CDS_LOCATION = "C274" &SEC = "1" #&CDS_SEC = "1";
"A":   PN = "1"  !CDS_PN = "1";
"B":   PN = "2"  !CDS_PN = "2";
BODY = "Q_CAP","I71": LOCATION = "C278" #&CDS_LOCATION = "C278" &SEC = "1" #&CDS_SEC = "1";
"A":   PN = "1"  !CDS_PN = "1";
"B":   PN = "2"  !CDS_PN = "2";
BODY = "Q_CAP","I73": LOCATION = "C282" #&CDS_LOCATION = "C282" &SEC = "1" #&CDS_SEC = "1";
"A":   PN = "1"  !CDS_PN = "1";
"B":   PN = "2"  !CDS_PN = "2";
BODY = "Q_CAP","I75": LOCATION = "C248" #&CDS_LOCATION = "C248" &SEC = "1" #&CDS_SEC = "1";
"A":   PN = "1"  !CDS_PN = "1";
"B":   PN = "2"  !CDS_PN = "2";
BODY = "Q_CAP","I76": LOCATION = "C242" #&CDS_LOCATION = "C242" &SEC = "1" #&CDS_SEC = "1";
"A":   PN = "1"  !CDS_PN = "1";
"B":   PN = "2"  !CDS_PN = "2";
BODY = "Q_CAP","I78": LOCATION = "C247" #&CDS_LOCATION = "C247" &SEC = "1" #&CDS_SEC = "1";
"A":   PN = "1"  !CDS_PN = "1";
"B":   PN = "2"  !CDS_PN = "2";
BODY = "Q_CAP","I79": LOCATION = "C246" #&CDS_LOCATION = "C246" &SEC = "1" #&CDS_SEC = "1";
"A":   PN = "1"  !CDS_PN = "1";
"B":   PN = "2"  !CDS_PN = "2";
BODY = "Q_CAP","I81": LOCATION = "C258" #&CDS_LOCATION = "C258" &SEC = "1" #&CDS_SEC = "1";
"A":   PN = "1"  !CDS_PN = "1";
"B":   PN = "2"  !CDS_PN = "2";
BODY = "Q_CAP","I83": LOCATION = "C251" #&CDS_LOCATION = "C251" &SEC = "1" #&CDS_SEC = "1";
"A":   PN = "1"  !CDS_PN = "1";
"B":   PN = "2"  !CDS_PN = "2";
BODY = "Q_CAP","I84": LOCATION = "C257" #&CDS_LOCATION = "C257" &SEC = "1" #&CDS_SEC = "1";
"A":   PN = "1"  !CDS_PN = "1";
"B":   PN = "2"  !CDS_PN = "2";
BODY = "Q_CAP","I86": LOCATION = "C263" #&CDS_LOCATION = "C263" &SEC = "1" #&CDS_SEC = "1";
"A":   PN = "1"  !CDS_PN = "1";
"B":   PN = "2"  !CDS_PN = "2";
BODY = "Q_CAP","I88": LOCATION = "C268" #&CDS_LOCATION = "C268" &SEC = "1" #&CDS_SEC = "1";
"A":   PN = "1"  !CDS_PN = "1";
"B":   PN = "2"  !CDS_PN = "2";
BODY = "Q_CAP","I93": LOCATION = "C262" #&CDS_LOCATION = "C262" &SEC = "1" #&CDS_SEC = "1";
"A":   PN = "1"  !CDS_PN = "1";
"B":   PN = "2"  !CDS_PN = "2";
BODY = "Q_CAP","I95": LOCATION = "C261" #&CDS_LOCATION = "C261" &SEC = "1" #&CDS_SEC = "1";
"A":   PN = "1"  !CDS_PN = "1";
"B":   PN = "2"  !CDS_PN = "2";
BODY = "Q_CAP","I98": LOCATION = "C272" #&CDS_LOCATION = "C272" &SEC = "1" #&CDS_SEC = "1";
"A":   PN = "1"  !CDS_PN = "1";
"B":   PN = "2"  !CDS_PN = "2";
BODY = "Q_CAP","I100": LOCATION = "C271" #&CDS_LOCATION = "C271" &SEC = "1" #&CDS_SEC = "1";
"A":   PN = "1"  !CDS_PN = "1";
"B":   PN = "2"  !CDS_PN = "2";
BODY = "Q_CAP","I101": LOCATION = "C277" #&CDS_LOCATION = "C277" &SEC = "1" #&CDS_SEC = "1";
"A":   PN = "1"  !CDS_PN = "1";
"B":   PN = "2"  !CDS_PN = "2";
BODY = "Q_CAP","I102": LOCATION = "C281" #&CDS_LOCATION = "C281" &SEC = "1" #&CDS_SEC = "1";
"A":   PN = "1"  !CDS_PN = "1";
"B":   PN = "2"  !CDS_PN = "2";
BODY = "Q_CAP","I103": LOCATION = "C276" #&CDS_LOCATION = "C276" &SEC = "1" #&CDS_SEC = "1";
"A":   PN = "1"  !CDS_PN = "1";
"B":   PN = "2"  !CDS_PN = "2";
BODY = "Q_CAP","I104": LOCATION = "C275" #&CDS_LOCATION = "C275" &SEC = "1" #&CDS_SEC = "1";
"A":   PN = "1"  !CDS_PN = "1";
"B":   PN = "2"  !CDS_PN = "2";
BODY = "Q_CAP","I105": LOCATION = "C280" #&CDS_LOCATION = "C280" &SEC = "1" #&CDS_SEC = "1";
"A":   PN = "1"  !CDS_PN = "1";
"B":   PN = "2"  !CDS_PN = "2";
BODY = "Q_CAP","I106": LOCATION = "C279" #&CDS_LOCATION = "C279" &SEC = "1" #&CDS_SEC = "1";
"A":   PN = "1"  !CDS_PN = "1";
"B":   PN = "2"  !CDS_PN = "2";
BODY = "Q_CAP","I109": LOCATION = "C444" #&CDS_LOCATION = "C444" &SEC = "1" #&CDS_SEC = "1";
"A":   PN = "1"  !CDS_PN = "1";
"B":   PN = "2"  !CDS_PN = "2";
BODY = "Q_CAP","I110": LOCATION = "C445" #&CDS_LOCATION = "C445" &SEC = "1" #&CDS_SEC = "1";
"A":   PN = "1"  !CDS_PN = "1";
"B":   PN = "2"  !CDS_PN = "2";
BODY = "Q_CAP","I111": LOCATION = "C286" #&CDS_LOCATION = "C286" &SEC = "1" #&CDS_SEC = "1";
"A":   PN = "1"  !CDS_PN = "1";
"B":   PN = "2"  !CDS_PN = "2";
BODY = "Q_CAP","I112": LOCATION = "C290" #&CDS_LOCATION = "C290" &SEC = "1" #&CDS_SEC = "1";
"A":   PN = "1"  !CDS_PN = "1";
"B":   PN = "2"  !CDS_PN = "2";
BODY = "Q_CAP","I113": LOCATION = "C446" #&CDS_LOCATION = "C446" &SEC = "1" #&CDS_SEC = "1";
"A":   PN = "1"  !CDS_PN = "1";
"B":   PN = "2"  !CDS_PN = "2";
BODY = "Q_CAP","I114": LOCATION = "C294" #&CDS_LOCATION = "C294" &SEC = "1" #&CDS_SEC = "1";
"A":   PN = "1"  !CDS_PN = "1";
"B":   PN = "2"  !CDS_PN = "2";
BODY = "Q_CAP","I115": LOCATION = "C298" #&CDS_LOCATION = "C298" &SEC = "1" #&CDS_SEC = "1";
"A":   PN = "1"  !CDS_PN = "1";
"B":   PN = "2"  !CDS_PN = "2";
BODY = "Q_CAP","I117": LOCATION = "C302" #&CDS_LOCATION = "C302" &SEC = "1" #&CDS_SEC = "1";
"A":   PN = "1"  !CDS_PN = "1";
"B":   PN = "2"  !CDS_PN = "2";
BODY = "Q_CAP","I118": LOCATION = "C306" #&CDS_LOCATION = "C306" &SEC = "1" #&CDS_SEC = "1";
"A":   PN = "1"  !CDS_PN = "1";
"B":   PN = "2"  !CDS_PN = "2";
BODY = "Q_CAP","I119": LOCATION = "C285" #&CDS_LOCATION = "C285" &SEC = "1" #&CDS_SEC = "1";
"A":   PN = "1"  !CDS_PN = "1";
"B":   PN = "2"  !CDS_PN = "2";
BODY = "Q_CAP","I120": LOCATION = "C289" #&CDS_LOCATION = "C289" &SEC = "1" #&CDS_SEC = "1";
"A":   PN = "1"  !CDS_PN = "1";
"B":   PN = "2"  !CDS_PN = "2";
BODY = "Q_CAP","I121": LOCATION = "C284" #&CDS_LOCATION = "C284" &SEC = "1" #&CDS_SEC = "1";
"A":   PN = "1"  !CDS_PN = "1";
"B":   PN = "2"  !CDS_PN = "2";
BODY = "Q_CAP","I122": LOCATION = "C283" #&CDS_LOCATION = "C283" &SEC = "1" #&CDS_SEC = "1";
"A":   PN = "1"  !CDS_PN = "1";
"B":   PN = "2"  !CDS_PN = "2";
BODY = "Q_CAP","I123": LOCATION = "C288" #&CDS_LOCATION = "C288" &SEC = "1" #&CDS_SEC = "1";
"A":   PN = "1"  !CDS_PN = "1";
"B":   PN = "2"  !CDS_PN = "2";
BODY = "Q_CAP","I125": LOCATION = "C293" #&CDS_LOCATION = "C293" &SEC = "1" #&CDS_SEC = "1";
"A":   PN = "1"  !CDS_PN = "1";
"B":   PN = "2"  !CDS_PN = "2";
BODY = "Q_CAP","I126": LOCATION = "C297" #&CDS_LOCATION = "C297" &SEC = "1" #&CDS_SEC = "1";
"A":   PN = "1"  !CDS_PN = "1";
"B":   PN = "2"  !CDS_PN = "2";
BODY = "Q_CAP","I129": LOCATION = "C296" #&CDS_LOCATION = "C296" &SEC = "1" #&CDS_SEC = "1";
"A":   PN = "1"  !CDS_PN = "1";
"B":   PN = "2"  !CDS_PN = "2";
BODY = "Q_CAP","I130": LOCATION = "C295" #&CDS_LOCATION = "C295" &SEC = "1" #&CDS_SEC = "1";
"A":   PN = "1"  !CDS_PN = "1";
"B":   PN = "2"  !CDS_PN = "2";
BODY = "Q_CAP","I131": LOCATION = "C299" #&CDS_LOCATION = "C299" &SEC = "1" #&CDS_SEC = "1";
"A":   PN = "1"  !CDS_PN = "1";
"B":   PN = "2"  !CDS_PN = "2";
BODY = "Q_CAP","I132": LOCATION = "C300" #&CDS_LOCATION = "C300" &SEC = "1" #&CDS_SEC = "1";
"A":   PN = "1"  !CDS_PN = "1";
"B":   PN = "2"  !CDS_PN = "2";
BODY = "Q_CAP","I133": LOCATION = "C301" #&CDS_LOCATION = "C301" &SEC = "1" #&CDS_SEC = "1";
"A":   PN = "1"  !CDS_PN = "1";
"B":   PN = "2"  !CDS_PN = "2";
BODY = "Q_CAP","I134": LOCATION = "C305" #&CDS_LOCATION = "C305" &SEC = "1" #&CDS_SEC = "1";
"A":   PN = "1"  !CDS_PN = "1";
"B":   PN = "2"  !CDS_PN = "2";
BODY = "Q_CAP","I136": LOCATION = "C309" #&CDS_LOCATION = "C309" &SEC = "1" #&CDS_SEC = "1";
"A":   PN = "1"  !CDS_PN = "1";
"B":   PN = "2"  !CDS_PN = "2";
BODY = "Q_CAP","I138": LOCATION = "C304" #&CDS_LOCATION = "C304" &SEC = "1" #&CDS_SEC = "1";
"A":   PN = "1"  !CDS_PN = "1";
"B":   PN = "2"  !CDS_PN = "2";
BODY = "Q_CAP","I140": LOCATION = "C308" #&CDS_LOCATION = "C308" &SEC = "1" #&CDS_SEC = "1";
"A":   PN = "1"  !CDS_PN = "1";
"B":   PN = "2"  !CDS_PN = "2";
BODY = "Q_CAP","I2": LOCATION = "C426" #&CDS_LOCATION = "C426" &SEC = "1" #&CDS_SEC = "1";
"A":   PN = "1"  !CDS_PN = "1";
"B":   PN = "2"  !CDS_PN = "2";
BODY = "Q_CAP","I14": LOCATION = "C229" #&CDS_LOCATION = "C229" &SEC = "1" #&CDS_SEC = "1";
"A":   PN = "1"  !CDS_PN = "1";
"B":   PN = "2"  !CDS_PN = "2";
BODY = "Q_CAP","I16": LOCATION = "C235" #&CDS_LOCATION = "C235" &SEC = "1" #&CDS_SEC = "1";
"A":   PN = "1"  !CDS_PN = "1";
"B":   PN = "2"  !CDS_PN = "2";
BODY = "Q_CAP","I26": LOCATION = "C227" #&CDS_LOCATION = "C227" &SEC = "1" #&CDS_SEC = "1";
"A":   PN = "1"  !CDS_PN = "1";
"B":   PN = "2"  !CDS_PN = "2";
BODY = "Q_CAP","I40": LOCATION = "C437" #&CDS_LOCATION = "C437" &SEC = "1" #&CDS_SEC = "1";
"A":   PN = "1"  !CDS_PN = "1";
"B":   PN = "2"  !CDS_PN = "2";
BODY = "Q_CAP","I64": LOCATION = "C269" #&CDS_LOCATION = "C269" &SEC = "1" #&CDS_SEC = "1";
"A":   PN = "1"  !CDS_PN = "1";
"B":   PN = "2"  !CDS_PN = "2";
BODY = "Q_CAP","I67": LOCATION = "C443" #&CDS_LOCATION = "C443" &SEC = "1" #&CDS_SEC = "1";
"A":   PN = "1"  !CDS_PN = "1";
"B":   PN = "2"  !CDS_PN = "2";
BODY = "Q_CAP","I70": LOCATION = "C310" #&CDS_LOCATION = "C310" &SEC = "1" #&CDS_SEC = "1";
"A":   PN = "1"  !CDS_PN = "1";
"B":   PN = "2"  !CDS_PN = "2";
BODY = "Q_CAP","I74": LOCATION = "C243" #&CDS_LOCATION = "C243" &SEC = "1" #&CDS_SEC = "1";
"A":   PN = "1"  !CDS_PN = "1";
"B":   PN = "2"  !CDS_PN = "2";
BODY = "Q_CAP","I77": LOCATION = "C241" #&CDS_LOCATION = "C241" &SEC = "1" #&CDS_SEC = "1";
"A":   PN = "1"  !CDS_PN = "1";
"B":   PN = "2"  !CDS_PN = "2";
BODY = "Q_CAP","I80": LOCATION = "C253" #&CDS_LOCATION = "C253" &SEC = "1" #&CDS_SEC = "1";
"A":   PN = "1"  !CDS_PN = "1";
"B":   PN = "2"  !CDS_PN = "2";
BODY = "Q_CAP","I82": LOCATION = "C252" #&CDS_LOCATION = "C252" &SEC = "1" #&CDS_SEC = "1";
"A":   PN = "1"  !CDS_PN = "1";
"B":   PN = "2"  !CDS_PN = "2";
BODY = "Q_CAP","I85": LOCATION = "C256" #&CDS_LOCATION = "C256" &SEC = "1" #&CDS_SEC = "1";
"A":   PN = "1"  !CDS_PN = "1";
"B":   PN = "2"  !CDS_PN = "2";
BODY = "Q_CAP","I91": LOCATION = "C273" #&CDS_LOCATION = "C273" &SEC = "1" #&CDS_SEC = "1";
"A":   PN = "1"  !CDS_PN = "1";
"B":   PN = "2"  !CDS_PN = "2";
BODY = "Q_CAP","I94": LOCATION = "C267" #&CDS_LOCATION = "C267" &SEC = "1" #&CDS_SEC = "1";
"A":   PN = "1"  !CDS_PN = "1";
"B":   PN = "2"  !CDS_PN = "2";
BODY = "Q_CAP","I97": LOCATION = "C266" #&CDS_LOCATION = "C266" &SEC = "1" #&CDS_SEC = "1";
"A":   PN = "1"  !CDS_PN = "1";
"B":   PN = "2"  !CDS_PN = "2";
BODY = "Q_CAP","I124": LOCATION = "C287" #&CDS_LOCATION = "C287" &SEC = "1" #&CDS_SEC = "1";
"A":   PN = "1"  !CDS_PN = "1";
"B":   PN = "2"  !CDS_PN = "2";
BODY = "Q_CAP","I127": LOCATION = "C292" #&CDS_LOCATION = "C292" &SEC = "1" #&CDS_SEC = "1";
"A":   PN = "1"  !CDS_PN = "1";
"B":   PN = "2"  !CDS_PN = "2";
BODY = "Q_CAP","I128": LOCATION = "C291" #&CDS_LOCATION = "C291" &SEC = "1" #&CDS_SEC = "1";
"A":   PN = "1"  !CDS_PN = "1";
"B":   PN = "2"  !CDS_PN = "2";
BODY = "Q_CAP","I139": LOCATION = "C303" #&CDS_LOCATION = "C303" &SEC = "1" #&CDS_SEC = "1";
"A":   PN = "1"  !CDS_PN = "1";
"B":   PN = "2"  !CDS_PN = "2";
BODY = "Q_CAP","I142": LOCATION = "C307" #&CDS_LOCATION = "C307" &SEC = "1" #&CDS_SEC = "1";
"A":   PN = "1"  !CDS_PN = "1";
"B":   PN = "2"  !CDS_PN = "2";
DRAWING = "@s9s_mb_2u_lib.s9s_mb_2u(sch_1):page78";
BODY = "Q_CAP","I3": LOCATION = "C453" #&CDS_LOCATION = "C453" &SEC = "1" #&CDS_SEC = "1";
"A":   PN = "1"  !CDS_PN = "1";
"B":   PN = "2"  !CDS_PN = "2";
BODY = "Q_CAP","I5": LOCATION = "C461" #&CDS_LOCATION = "C461" &SEC = "1" #&CDS_SEC = "1";
"A":   PN = "1"  !CDS_PN = "1";
"B":   PN = "2"  !CDS_PN = "2";
BODY = "Q_CAP","I7": LOCATION = "C465" #&CDS_LOCATION = "C465" &SEC = "1" #&CDS_SEC = "1";
"A":   PN = "1"  !CDS_PN = "1";
"B":   PN = "2"  !CDS_PN = "2";
BODY = "Q_CAP","I23": LOCATION = "C490" #&CDS_LOCATION = "C490" &SEC = "1" #&CDS_SEC = "1";
"A":   PN = "1"  !CDS_PN = "1";
"B":   PN = "2"  !CDS_PN = "2";
BODY = "Q_CAP","I24": LOCATION = "C451" #&CDS_LOCATION = "C451" &SEC = "1" #&CDS_SEC = "1";
"A":   PN = "1"  !CDS_PN = "1";
"B":   PN = "2"  !CDS_PN = "2";
BODY = "Q_CAP","I27": LOCATION = "C318" #&CDS_LOCATION = "C318" &SEC = "1" #&CDS_SEC = "1";
"A":   PN = "1"  !CDS_PN = "1";
"B":   PN = "2"  !CDS_PN = "2";
BODY = "Q_CAP","I29": LOCATION = "C474" #&CDS_LOCATION = "C474" &SEC = "1" #&CDS_SEC = "1";
"A":   PN = "1"  !CDS_PN = "1";
"B":   PN = "2"  !CDS_PN = "2";
BODY = "Q_CAP","I32": LOCATION = "C327" #&CDS_LOCATION = "C327" &SEC = "1" #&CDS_SEC = "1";
"A":   PN = "1"  !CDS_PN = "1";
"B":   PN = "2"  !CDS_PN = "2";
BODY = "Q_CAP","I35": LOCATION = "C336" #&CDS_LOCATION = "C336" &SEC = "1" #&CDS_SEC = "1";
"A":   PN = "1"  !CDS_PN = "1";
"B":   PN = "2"  !CDS_PN = "2";
BODY = "Q_CAP","I37": LOCATION = "C314" #&CDS_LOCATION = "C314" &SEC = "1" #&CDS_SEC = "1";
"A":   PN = "1"  !CDS_PN = "1";
"B":   PN = "2"  !CDS_PN = "2";
BODY = "Q_CAP","I39": LOCATION = "C320" #&CDS_LOCATION = "C320" &SEC = "1" #&CDS_SEC = "1";
"A":   PN = "1"  !CDS_PN = "1";
"B":   PN = "2"  !CDS_PN = "2";
BODY = "Q_CAP","I40": LOCATION = "C323" #&CDS_LOCATION = "C323" &SEC = "1" #&CDS_SEC = "1";
"A":   PN = "1"  !CDS_PN = "1";
"B":   PN = "2"  !CDS_PN = "2";
BODY = "Q_CAP","I41": LOCATION = "C326" #&CDS_LOCATION = "C326" &SEC = "1" #&CDS_SEC = "1";
"A":   PN = "1"  !CDS_PN = "1";
"B":   PN = "2"  !CDS_PN = "2";
BODY = "Q_CAP","I52": LOCATION = "C1391" #&CDS_LOCATION = "C1391" &SEC = "1" #&CDS_SEC = "1";
"A":   PN = "1"  !CDS_PN = "1";
"B":   PN = "2"  !CDS_PN = "2";
BODY = "Q_CAP","I58": LOCATION = "C313" #&CDS_LOCATION = "C313" &SEC = "1" #&CDS_SEC = "1";
"A":   PN = "1"  !CDS_PN = "1";
"B":   PN = "2"  !CDS_PN = "2";
BODY = "Q_CAP","I60": LOCATION = "C316" #&CDS_LOCATION = "C316" &SEC = "1" #&CDS_SEC = "1";
"A":   PN = "1"  !CDS_PN = "1";
"B":   PN = "2"  !CDS_PN = "2";
BODY = "Q_CAP","I65": LOCATION = "C353" #&CDS_LOCATION = "C353" &SEC = "1" #&CDS_SEC = "1";
"A":   PN = "1"  !CDS_PN = "1";
"B":   PN = "2"  !CDS_PN = "2";
BODY = "Q_CAP","I66": LOCATION = "C337" #&CDS_LOCATION = "C337" &SEC = "1" #&CDS_SEC = "1";
"A":   PN = "1"  !CDS_PN = "1";
"B":   PN = "2"  !CDS_PN = "2";
BODY = "Q_CAP","I68": LOCATION = "C483" #&CDS_LOCATION = "C483" &SEC = "1" #&CDS_SEC = "1";
"A":   PN = "1"  !CDS_PN = "1";
"B":   PN = "2"  !CDS_PN = "2";
BODY = "Q_CAP","I1": LOCATION = "C449" #&CDS_LOCATION = "C449" &SEC = "1" #&CDS_SEC = "1";
"A":   PN = "1"  !CDS_PN = "1";
"B":   PN = "2"  !CDS_PN = "2";
BODY = "Q_CAP","I4": LOCATION = "C457" #&CDS_LOCATION = "C457" &SEC = "1" #&CDS_SEC = "1";
"A":   PN = "1"  !CDS_PN = "1";
"B":   PN = "2"  !CDS_PN = "2";
BODY = "Q_CAP","I8": LOCATION = "C478" #&CDS_LOCATION = "C478" &SEC = "1" #&CDS_SEC = "1";
"A":   PN = "1"  !CDS_PN = "1";
"B":   PN = "2"  !CDS_PN = "2";
BODY = "Q_CAP","I10": LOCATION = "C448" #&CDS_LOCATION = "C448" &SEC = "1" #&CDS_SEC = "1";
"A":   PN = "1"  !CDS_PN = "1";
"B":   PN = "2"  !CDS_PN = "2";
BODY = "Q_CAP","I12": LOCATION = "C447" #&CDS_LOCATION = "C447" &SEC = "1" #&CDS_SEC = "1";
"A":   PN = "1"  !CDS_PN = "1";
"B":   PN = "2"  !CDS_PN = "2";
BODY = "Q_CAP","I14": LOCATION = "C312" #&CDS_LOCATION = "C312" &SEC = "1" #&CDS_SEC = "1";
"A":   PN = "1"  !CDS_PN = "1";
"B":   PN = "2"  !CDS_PN = "2";
BODY = "Q_CAP","I16": LOCATION = "C311" #&CDS_LOCATION = "C311" &SEC = "1" #&CDS_SEC = "1";
"A":   PN = "1"  !CDS_PN = "1";
"B":   PN = "2"  !CDS_PN = "2";
BODY = "Q_CAP","I18": LOCATION = "C488" #&CDS_LOCATION = "C488" &SEC = "1" #&CDS_SEC = "1";
"A":   PN = "1"  !CDS_PN = "1";
"B":   PN = "2"  !CDS_PN = "2";
BODY = "Q_CAP","I19": LOCATION = "C489" #&CDS_LOCATION = "C489" &SEC = "1" #&CDS_SEC = "1";
"A":   PN = "1"  !CDS_PN = "1";
"B":   PN = "2"  !CDS_PN = "2";
BODY = "Q_CAP","I21": LOCATION = "C452" #&CDS_LOCATION = "C452" &SEC = "1" #&CDS_SEC = "1";
"A":   PN = "1"  !CDS_PN = "1";
"B":   PN = "2"  !CDS_PN = "2";
BODY = "Q_CAP","I25": LOCATION = "C471" #&CDS_LOCATION = "C471" &SEC = "1" #&CDS_SEC = "1";
"A":   PN = "1"  !CDS_PN = "1";
"B":   PN = "2"  !CDS_PN = "2";
BODY = "Q_CAP","I26": LOCATION = "C315" #&CDS_LOCATION = "C315" &SEC = "1" #&CDS_SEC = "1";
"A":   PN = "1"  !CDS_PN = "1";
"B":   PN = "2"  !CDS_PN = "2";
BODY = "Q_CAP","I30": LOCATION = "C321" #&CDS_LOCATION = "C321" &SEC = "1" #&CDS_SEC = "1";
"A":   PN = "1"  !CDS_PN = "1";
"B":   PN = "2"  !CDS_PN = "2";
BODY = "Q_CAP","I31": LOCATION = "C324" #&CDS_LOCATION = "C324" &SEC = "1" #&CDS_SEC = "1";
"A":   PN = "1"  !CDS_PN = "1";
"B":   PN = "2"  !CDS_PN = "2";
BODY = "Q_CAP","I33": LOCATION = "C330" #&CDS_LOCATION = "C330" &SEC = "1" #&CDS_SEC = "1";
"A":   PN = "1"  !CDS_PN = "1";
"B":   PN = "2"  !CDS_PN = "2";
BODY = "Q_CAP","I34": LOCATION = "C333" #&CDS_LOCATION = "C333" &SEC = "1" #&CDS_SEC = "1";
"A":   PN = "1"  !CDS_PN = "1";
"B":   PN = "2"  !CDS_PN = "2";
BODY = "Q_CAP","I36": LOCATION = "C339" #&CDS_LOCATION = "C339" &SEC = "1" #&CDS_SEC = "1";
"A":   PN = "1"  !CDS_PN = "1";
"B":   PN = "2"  !CDS_PN = "2";
BODY = "Q_CAP","I38": LOCATION = "C317" #&CDS_LOCATION = "C317" &SEC = "1" #&CDS_SEC = "1";
"A":   PN = "1"  !CDS_PN = "1";
"B":   PN = "2"  !CDS_PN = "2";
BODY = "Q_CAP","I42": LOCATION = "C329" #&CDS_LOCATION = "C329" &SEC = "1" #&CDS_SEC = "1";
"A":   PN = "1"  !CDS_PN = "1";
"B":   PN = "2"  !CDS_PN = "2";
BODY = "Q_CAP","I43": LOCATION = "C332" #&CDS_LOCATION = "C332" &SEC = "1" #&CDS_SEC = "1";
"A":   PN = "1"  !CDS_PN = "1";
"B":   PN = "2"  !CDS_PN = "2";
BODY = "Q_CAP","I44": LOCATION = "C335" #&CDS_LOCATION = "C335" &SEC = "1" #&CDS_SEC = "1";
"A":   PN = "1"  !CDS_PN = "1";
"B":   PN = "2"  !CDS_PN = "2";
BODY = "Q_CAP","I45": LOCATION = "C338" #&CDS_LOCATION = "C338" &SEC = "1" #&CDS_SEC = "1";
"A":   PN = "1"  !CDS_PN = "1";
"B":   PN = "2"  !CDS_PN = "2";
BODY = "Q_CAP","I46": LOCATION = "C1388" #&CDS_LOCATION = "C1388" &SEC = "1" #&CDS_SEC = "1";
"A":   PN = "1"  !CDS_PN = "1";
"B":   PN = "2"  !CDS_PN = "2";
BODY = "Q_CAP","I48": LOCATION = "C1390" #&CDS_LOCATION = "C1390" &SEC = "1" #&CDS_SEC = "1";
"A":   PN = "1"  !CDS_PN = "1";
"B":   PN = "2"  !CDS_PN = "2";
BODY = "Q_CAP","I49": LOCATION = "C1387" #&CDS_LOCATION = "C1387" &SEC = "1" #&CDS_SEC = "1";
"A":   PN = "1"  !CDS_PN = "1";
"B":   PN = "2"  !CDS_PN = "2";
BODY = "Q_CAP","I51": LOCATION = "C1389" #&CDS_LOCATION = "C1389" &SEC = "1" #&CDS_SEC = "1";
"A":   PN = "1"  !CDS_PN = "1";
"B":   PN = "2"  !CDS_PN = "2";
BODY = "Q_CAP","I53": LOCATION = "C1392" #&CDS_LOCATION = "C1392" &SEC = "1" #&CDS_SEC = "1";
"A":   PN = "1"  !CDS_PN = "1";
"B":   PN = "2"  !CDS_PN = "2";
BODY = "Q_CAP","I55": LOCATION = "C1437" #&CDS_LOCATION = "C1437" &SEC = "1" #&CDS_SEC = "1";
"A":   PN = "1"  !CDS_PN = "1";
"B":   PN = "2"  !CDS_PN = "2";
BODY = "Q_CAP","I57": LOCATION = "C1393" #&CDS_LOCATION = "C1393" &SEC = "1" #&CDS_SEC = "1";
"A":   PN = "1"  !CDS_PN = "1";
"B":   PN = "2"  !CDS_PN = "2";
BODY = "Q_CAP","I63": LOCATION = "C349" #&CDS_LOCATION = "C349" &SEC = "1" #&CDS_SEC = "1";
"A":   PN = "1"  !CDS_PN = "1";
"B":   PN = "2"  !CDS_PN = "2";
BODY = "Q_CAP","I64": LOCATION = "C351" #&CDS_LOCATION = "C351" &SEC = "1" #&CDS_SEC = "1";
"A":   PN = "1"  !CDS_PN = "1";
"B":   PN = "2"  !CDS_PN = "2";
DRAWING = "@s9s_mb_2u_lib.s9s_mb_2u(sch_1):page79";
BODY = "Q_CAP","I1": LOCATION = "C450" #&CDS_LOCATION = "C450" &SEC = "1" #&CDS_SEC = "1";
"A":   PN = "1"  !CDS_PN = "1";
"B":   PN = "2"  !CDS_PN = "2";
BODY = "Q_CAP","I3": LOCATION = "C454" #&CDS_LOCATION = "C454" &SEC = "1" #&CDS_SEC = "1";
"A":   PN = "1"  !CDS_PN = "1";
"B":   PN = "2"  !CDS_PN = "2";
BODY = "Q_CAP","I4": LOCATION = "C458" #&CDS_LOCATION = "C458" &SEC = "1" #&CDS_SEC = "1";
"A":   PN = "1"  !CDS_PN = "1";
"B":   PN = "2"  !CDS_PN = "2";
BODY = "Q_CAP","I5": LOCATION = "C462" #&CDS_LOCATION = "C462" &SEC = "1" #&CDS_SEC = "1";
"A":   PN = "1"  !CDS_PN = "1";
"B":   PN = "2"  !CDS_PN = "2";
BODY = "Q_CAP","I7": LOCATION = "C466" #&CDS_LOCATION = "C466" &SEC = "1" #&CDS_SEC = "1";
"A":   PN = "1"  !CDS_PN = "1";
"B":   PN = "2"  !CDS_PN = "2";
BODY = "Q_CAP","I8": LOCATION = "C470" #&CDS_LOCATION = "C470" &SEC = "1" #&CDS_SEC = "1";
"A":   PN = "1"  !CDS_PN = "1";
"B":   PN = "2"  !CDS_PN = "2";
BODY = "Q_CAP","I9": LOCATION = "C473" #&CDS_LOCATION = "C473" &SEC = "1" #&CDS_SEC = "1";
"A":   PN = "1"  !CDS_PN = "1";
"B":   PN = "2"  !CDS_PN = "2";
BODY = "Q_CAP","I10": LOCATION = "C487" #&CDS_LOCATION = "C487" &SEC = "1" #&CDS_SEC = "1";
"A":   PN = "1"  !CDS_PN = "1";
"B":   PN = "2"  !CDS_PN = "2";
BODY = "Q_CAP","I11": LOCATION = "C486" #&CDS_LOCATION = "C486" &SEC = "1" #&CDS_SEC = "1";
"A":   PN = "1"  !CDS_PN = "1";
"B":   PN = "2"  !CDS_PN = "2";
BODY = "Q_CAP","I12": LOCATION = "C484" #&CDS_LOCATION = "C484" &SEC = "1" #&CDS_SEC = "1";
"A":   PN = "1"  !CDS_PN = "1";
"B":   PN = "2"  !CDS_PN = "2";
BODY = "Q_CAP","I13": LOCATION = "C481" #&CDS_LOCATION = "C481" &SEC = "1" #&CDS_SEC = "1";
"A":   PN = "1"  !CDS_PN = "1";
"B":   PN = "2"  !CDS_PN = "2";
BODY = "Q_CAP","I15": LOCATION = "C456" #&CDS_LOCATION = "C456" &SEC = "1" #&CDS_SEC = "1";
"A":   PN = "1"  !CDS_PN = "1";
"B":   PN = "2"  !CDS_PN = "2";
BODY = "Q_CAP","I16": LOCATION = "C460" #&CDS_LOCATION = "C460" &SEC = "1" #&CDS_SEC = "1";
"A":   PN = "1"  !CDS_PN = "1";
"B":   PN = "2"  !CDS_PN = "2";
BODY = "Q_CAP","I17": LOCATION = "C464" #&CDS_LOCATION = "C464" &SEC = "1" #&CDS_SEC = "1";
"A":   PN = "1"  !CDS_PN = "1";
"B":   PN = "2"  !CDS_PN = "2";
BODY = "Q_CAP","I19": LOCATION = "C455" #&CDS_LOCATION = "C455" &SEC = "1" #&CDS_SEC = "1";
"A":   PN = "1"  !CDS_PN = "1";
"B":   PN = "2"  !CDS_PN = "2";
BODY = "Q_CAP","I20": LOCATION = "C459" #&CDS_LOCATION = "C459" &SEC = "1" #&CDS_SEC = "1";
"A":   PN = "1"  !CDS_PN = "1";
"B":   PN = "2"  !CDS_PN = "2";
BODY = "Q_CAP","I21": LOCATION = "C463" #&CDS_LOCATION = "C463" &SEC = "1" #&CDS_SEC = "1";
"A":   PN = "1"  !CDS_PN = "1";
"B":   PN = "2"  !CDS_PN = "2";
BODY = "Q_CAP","I23": LOCATION = "C342" #&CDS_LOCATION = "C342" &SEC = "1" #&CDS_SEC = "1";
"A":   PN = "1"  !CDS_PN = "1";
"B":   PN = "2"  !CDS_PN = "2";
BODY = "Q_CAP","I24": LOCATION = "C344" #&CDS_LOCATION = "C344" &SEC = "1" #&CDS_SEC = "1";
"A":   PN = "1"  !CDS_PN = "1";
"B":   PN = "2"  !CDS_PN = "2";
BODY = "Q_CAP","I25": LOCATION = "C346" #&CDS_LOCATION = "C346" &SEC = "1" #&CDS_SEC = "1";
"A":   PN = "1"  !CDS_PN = "1";
"B":   PN = "2"  !CDS_PN = "2";
BODY = "Q_CAP","I26": LOCATION = "C468" #&CDS_LOCATION = "C468" &SEC = "1" #&CDS_SEC = "1";
"A":   PN = "1"  !CDS_PN = "1";
"B":   PN = "2"  !CDS_PN = "2";
BODY = "Q_CAP","I27": LOCATION = "C472" #&CDS_LOCATION = "C472" &SEC = "1" #&CDS_SEC = "1";
"A":   PN = "1"  !CDS_PN = "1";
"B":   PN = "2"  !CDS_PN = "2";
BODY = "Q_CAP","I29": LOCATION = "C475" #&CDS_LOCATION = "C475" &SEC = "1" #&CDS_SEC = "1";
"A":   PN = "1"  !CDS_PN = "1";
"B":   PN = "2"  !CDS_PN = "2";
BODY = "Q_CAP","I31": LOCATION = "C467" #&CDS_LOCATION = "C467" &SEC = "1" #&CDS_SEC = "1";
"A":   PN = "1"  !CDS_PN = "1";
"B":   PN = "2"  !CDS_PN = "2";
BODY = "Q_CAP","I32": LOCATION = "C348" #&CDS_LOCATION = "C348" &SEC = "1" #&CDS_SEC = "1";
"A":   PN = "1"  !CDS_PN = "1";
"B":   PN = "2"  !CDS_PN = "2";
BODY = "Q_CAP","I33": LOCATION = "C350" #&CDS_LOCATION = "C350" &SEC = "1" #&CDS_SEC = "1";
"A":   PN = "1"  !CDS_PN = "1";
"B":   PN = "2"  !CDS_PN = "2";
BODY = "Q_CAP","I34": LOCATION = "C352" #&CDS_LOCATION = "C352" &SEC = "1" #&CDS_SEC = "1";
"A":   PN = "1"  !CDS_PN = "1";
"B":   PN = "2"  !CDS_PN = "2";
BODY = "Q_CAP","I35": LOCATION = "C354" #&CDS_LOCATION = "C354" &SEC = "1" #&CDS_SEC = "1";
"A":   PN = "1"  !CDS_PN = "1";
"B":   PN = "2"  !CDS_PN = "2";
BODY = "Q_CAP","I37": LOCATION = "C476" #&CDS_LOCATION = "C476" &SEC = "1" #&CDS_SEC = "1";
"A":   PN = "1"  !CDS_PN = "1";
"B":   PN = "2"  !CDS_PN = "2";
BODY = "Q_CAP","I38": LOCATION = "C477" #&CDS_LOCATION = "C477" &SEC = "1" #&CDS_SEC = "1";
"A":   PN = "1"  !CDS_PN = "1";
"B":   PN = "2"  !CDS_PN = "2";
BODY = "Q_CAP","I39": LOCATION = "C479" #&CDS_LOCATION = "C479" &SEC = "1" #&CDS_SEC = "1";
"A":   PN = "1"  !CDS_PN = "1";
"B":   PN = "2"  !CDS_PN = "2";
BODY = "Q_CAP","I41": LOCATION = "C482" #&CDS_LOCATION = "C482" &SEC = "1" #&CDS_SEC = "1";
"A":   PN = "1"  !CDS_PN = "1";
"B":   PN = "2"  !CDS_PN = "2";
BODY = "Q_CAP","I42": LOCATION = "C485" #&CDS_LOCATION = "C485" &SEC = "1" #&CDS_SEC = "1";
"A":   PN = "1"  !CDS_PN = "1";
"B":   PN = "2"  !CDS_PN = "2";
BODY = "Q_CAP","I43": LOCATION = "C1403" #&CDS_LOCATION = "C1403" &SEC = "1" #&CDS_SEC = "1";
"A":   PN = "1"  !CDS_PN = "1";
"B":   PN = "2"  !CDS_PN = "2";
BODY = "Q_CAP","I44": LOCATION = "C1404" #&CDS_LOCATION = "C1404" &SEC = "1" #&CDS_SEC = "1";
"A":   PN = "1"  !CDS_PN = "1";
"B":   PN = "2"  !CDS_PN = "2";
BODY = "Q_CAP","I46": LOCATION = "C322" #&CDS_LOCATION = "C322" &SEC = "1" #&CDS_SEC = "1";
"A":   PN = "1"  !CDS_PN = "1";
"B":   PN = "2"  !CDS_PN = "2";
BODY = "Q_CAP","I47": LOCATION = "C325" #&CDS_LOCATION = "C325" &SEC = "1" #&CDS_SEC = "1";
"A":   PN = "1"  !CDS_PN = "1";
"B":   PN = "2"  !CDS_PN = "2";
BODY = "Q_CAP","I49": LOCATION = "C1353" #&CDS_LOCATION = "C1353" &SEC = "1" #&CDS_SEC = "1";
"A":   PN = "1"  !CDS_PN = "1";
"B":   PN = "2"  !CDS_PN = "2";
BODY = "Q_CAP","I50": LOCATION = "C328" #&CDS_LOCATION = "C328" &SEC = "1" #&CDS_SEC = "1";
"A":   PN = "1"  !CDS_PN = "1";
"B":   PN = "2"  !CDS_PN = "2";
BODY = "Q_CAP","I51": LOCATION = "C341" #&CDS_LOCATION = "C341" &SEC = "1" #&CDS_SEC = "1";
"A":   PN = "1"  !CDS_PN = "1";
"B":   PN = "2"  !CDS_PN = "2";
BODY = "Q_CAP","I52": LOCATION = "C343" #&CDS_LOCATION = "C343" &SEC = "1" #&CDS_SEC = "1";
"A":   PN = "1"  !CDS_PN = "1";
"B":   PN = "2"  !CDS_PN = "2";
BODY = "Q_CAP","I53": LOCATION = "C345" #&CDS_LOCATION = "C345" &SEC = "1" #&CDS_SEC = "1";
"A":   PN = "1"  !CDS_PN = "1";
"B":   PN = "2"  !CDS_PN = "2";
BODY = "Q_CAP","I55": LOCATION = "C347" #&CDS_LOCATION = "C347" &SEC = "1" #&CDS_SEC = "1";
"A":   PN = "1"  !CDS_PN = "1";
"B":   PN = "2"  !CDS_PN = "2";
DRAWING = "@s9s_mb_2u_lib.s9s_mb_2u(sch_1):page80";
BODY = "Q_RES","I8": LOCATION = "R319" #&CDS_LOCATION = "R319" &SEC = "1" #&CDS_SEC = "1";
"A":   PN = "1"  !CDS_PN = "1";
"B":   PN = "2"  !CDS_PN = "2";
BODY = "Q_CAP","I9": LOCATION = "C1364" #&CDS_LOCATION = "C1364" &SEC = "1" #&CDS_SEC = "1";
"A":   PN = "1"  !CDS_PN = "1";
"B":   PN = "2"  !CDS_PN = "2";
BODY = "Q_CAP","I20": LOCATION = "C1365" #&CDS_LOCATION = "C1365" &SEC = "1" #&CDS_SEC = "1";
"A":   PN = "1"  !CDS_PN = "1";
"B":   PN = "2"  !CDS_PN = "2";
BODY = "Q_CAP","I28": LOCATION = "C1366" #&CDS_LOCATION = "C1366" &SEC = "1" #&CDS_SEC = "1";
"A":   PN = "1"  !CDS_PN = "1";
"B":   PN = "2"  !CDS_PN = "2";
BODY = "Q_RES","I1": LOCATION = "R1216" #&CDS_LOCATION = "R1216" &SEC = "1" #&CDS_SEC = "1";
"A":   PN = "1"  !CDS_PN = "1";
"B":   PN = "2"  !CDS_PN = "2";
BODY = "Q_RES","I2": LOCATION = "R321" #&CDS_LOCATION = "R321" &SEC = "1" #&CDS_SEC = "1";
"A":   PN = "1"  !CDS_PN = "1";
"B":   PN = "2"  !CDS_PN = "2";
BODY = "Q_CAP","I5": LOCATION = "C1363" #&CDS_LOCATION = "C1363" &SEC = "1" #&CDS_SEC = "1";
"A":   PN = "1"  !CDS_PN = "1";
"B":   PN = "2"  !CDS_PN = "2";
BODY = "Q_RES","I7": LOCATION = "R320" #&CDS_LOCATION = "R320" &SEC = "1" #&CDS_SEC = "1";
"A":   PN = "1"  !CDS_PN = "1";
"B":   PN = "2"  !CDS_PN = "2";
BODY = "Q_RES","I12": LOCATION = "R324" #&CDS_LOCATION = "R324" &SEC = "1" #&CDS_SEC = "1";
"A":   PN = "1"  !CDS_PN = "1";
"B":   PN = "2"  !CDS_PN = "2";
BODY = "Q_RES","I13": LOCATION = "R323" #&CDS_LOCATION = "R323" &SEC = "1" #&CDS_SEC = "1";
"A":   PN = "1"  !CDS_PN = "1";
"B":   PN = "2"  !CDS_PN = "2";
BODY = "Q_RES","I22": LOCATION = "R1217" #&CDS_LOCATION = "R1217" &SEC = "1" #&CDS_SEC = "1";
"A":   PN = "1"  !CDS_PN = "1";
"B":   PN = "2"  !CDS_PN = "2";
BODY = "Q_RES","I25": LOCATION = "R327" #&CDS_LOCATION = "R327" &SEC = "1" #&CDS_SEC = "1";
"A":   PN = "1"  !CDS_PN = "1";
"B":   PN = "2"  !CDS_PN = "2";
BODY = "Q_RES","I26": LOCATION = "R326" #&CDS_LOCATION = "R326" &SEC = "1" #&CDS_SEC = "1";
"A":   PN = "1"  !CDS_PN = "1";
"B":   PN = "2"  !CDS_PN = "2";
BODY = "Q_RES","I27": LOCATION = "R325" #&CDS_LOCATION = "R325" &SEC = "1" #&CDS_SEC = "1";
"A":   PN = "1"  !CDS_PN = "1";
"B":   PN = "2"  !CDS_PN = "2";
BODY = "Q_RES","I34": LOCATION = "R330" #&CDS_LOCATION = "R330" &SEC = "1" #&CDS_SEC = "1";
"A":   PN = "1"  !CDS_PN = "1";
"B":   PN = "2"  !CDS_PN = "2";
BODY = "Q_RES","I35": LOCATION = "R329" #&CDS_LOCATION = "R329" &SEC = "1" #&CDS_SEC = "1";
"A":   PN = "1"  !CDS_PN = "1";
"B":   PN = "2"  !CDS_PN = "2";
DRAWING = "@s9s_mb_2u_lib.s9s_mb_2u(sch_1):page82";
BODY = "Q_CAP","I188": LOCATION = "C3" #&CDS_LOCATION = "C3" &SEC = "1" #&CDS_SEC = "1";
"A":   PN = "1"  !CDS_PN = "1";
"B":   PN = "2"  !CDS_PN = "2";
BODY = "Q_CAP","I190": LOCATION = "C4" #&CDS_LOCATION = "C4" &SEC = "1" #&CDS_SEC = "1";
"A":   PN = "1"  !CDS_PN = "1";
"B":   PN = "2"  !CDS_PN = "2";
BODY = "Q_CAP","I192": LOCATION = "C2" #&CDS_LOCATION = "C2" &SEC = "1" #&CDS_SEC = "1";
"A":   PN = "1"  !CDS_PN = "1";
"B":   PN = "2"  !CDS_PN = "2";
BODY = "Q_RES","I196": LOCATION = "R26" #&CDS_LOCATION = "R26" &SEC = "1" #&CDS_SEC = "1";
"A":   PN = "1"  !CDS_PN = "1";
"B":   PN = "2"  !CDS_PN = "2";
BODY = "SCONN288_ADR50017P130CC","I198": LOCATION = "J1" #&CDS_LOCATION = "J1" &SEC = "1" #&CDS_SEC = "1";
"ALERT_N":   PN = "62"  !CDS_PN = "62";
"CA0_A":   PN = "66"  !CDS_PN = "66";
"CA0_B":   PN = "76"  !CDS_PN = "76";
"CA1_A":   PN = "211"  !CDS_PN = "211";
"CA1_B":   PN = "221"  !CDS_PN = "221";
"CA2_A":   PN = "68"  !CDS_PN = "68";
"CA2_B":   PN = "78"  !CDS_PN = "78";
"CA3_A":   PN = "213"  !CDS_PN = "213";
"CA3_B":   PN = "223"  !CDS_PN = "223";
"CA4_A":   PN = "70"  !CDS_PN = "70";
"CA4_B":   PN = "80"  !CDS_PN = "80";
"CA5_A":   PN = "215"  !CDS_PN = "215";
"CA5_B":   PN = "225"  !CDS_PN = "225";
"CA6_A":   PN = "72"  !CDS_PN = "72";
"CA6_B":   PN = "82"  !CDS_PN = "82";
"CB0_A":   PN = "51"  !CDS_PN = "51";
"CB0_B":   PN = "96"  !CDS_PN = "96";
"CB1_A":   PN = "53"  !CDS_PN = "53";
"CB1_B":   PN = "98"  !CDS_PN = "98";
"CB2_A":   PN = "196"  !CDS_PN = "196";
"CB2_B":   PN = "241"  !CDS_PN = "241";
"CB3_A":   PN = "198"  !CDS_PN = "198";
"CB3_B":   PN = "243"  !CDS_PN = "243";
"CB4_A":   PN = "58"  !CDS_PN = "58";
"CB4_B":   PN = "89"  !CDS_PN = "89";
"CB5_A":   PN = "60"  !CDS_PN = "60";
"CB5_B":   PN = "91"  !CDS_PN = "91";
"CB6_A":   PN = "203"  !CDS_PN = "203";
"CB6_B":   PN = "234"  !CDS_PN = "234";
"CB7_A":   PN = "205"  !CDS_PN = "205";
"CB7_B":   PN = "236"  !CDS_PN = "236";
"CK_C":   PN = "218"  !CDS_PN = "218";
"CK_T":   PN = "217"  !CDS_PN = "217";
"CS0_A_N":   PN = "64"  !CDS_PN = "64";
"CS0_B_N":   PN = "84"  !CDS_PN = "84";
"CS1_A_N":   PN = "209"  !CDS_PN = "209";
"CS1_B_N":   PN = "229"  !CDS_PN = "229";
"DQ0_A":   PN = "7"  !CDS_PN = "7";
"DQ0_B":   PN = "100"  !CDS_PN = "100";
"DQ1_A":   PN = "9"  !CDS_PN = "9";
"DQ1_B":   PN = "102"  !CDS_PN = "102";
"DQ2_A":   PN = "152"  !CDS_PN = "152";
"DQ2_B":   PN = "245"  !CDS_PN = "245";
"DQ3_A":   PN = "154"  !CDS_PN = "154";
"DQ3_B":   PN = "247"  !CDS_PN = "247";
"DQ4_A":   PN = "14"  !CDS_PN = "14";
"DQ4_B":   PN = "107"  !CDS_PN = "107";
"DQ5_A":   PN = "16"  !CDS_PN = "16";
"DQ5_B":   PN = "109"  !CDS_PN = "109";
"DQ6_A":   PN = "159"  !CDS_PN = "159";
"DQ6_B":   PN = "252"  !CDS_PN = "252";
"DQ7_A":   PN = "161"  !CDS_PN = "161";
"DQ7_B":   PN = "254"  !CDS_PN = "254";
"DQ8_A":   PN = "18"  !CDS_PN = "18";
"DQ8_B":   PN = "111"  !CDS_PN = "111";
"DQ9_A":   PN = "20"  !CDS_PN = "20";
"DQ9_B":   PN = "113"  !CDS_PN = "113";
"DQ10_A":   PN = "163"  !CDS_PN = "163";
"DQ10_B":   PN = "256"  !CDS_PN = "256";
"DQ11_A":   PN = "165"  !CDS_PN = "165";
"DQ11_B":   PN = "258"  !CDS_PN = "258";
"DQ12_A":   PN = "25"  !CDS_PN = "25";
"DQ12_B":   PN = "118"  !CDS_PN = "118";
"DQ13_A":   PN = "27"  !CDS_PN = "27";
"DQ13_B":   PN = "120"  !CDS_PN = "120";
"DQ14_A":   PN = "170"  !CDS_PN = "170";
"DQ14_B":   PN = "263"  !CDS_PN = "263";
"DQ15_A":   PN = "172"  !CDS_PN = "172";
"DQ15_B":   PN = "265"  !CDS_PN = "265";
"DQ16_A":   PN = "29"  !CDS_PN = "29";
"DQ16_B":   PN = "122"  !CDS_PN = "122";
"DQ17_A":   PN = "31"  !CDS_PN = "31";
"DQ17_B":   PN = "124"  !CDS_PN = "124";
"DQ18_A":   PN = "174"  !CDS_PN = "174";
"DQ18_B":   PN = "267"  !CDS_PN = "267";
"DQ19_A":   PN = "176"  !CDS_PN = "176";
"DQ19_B":   PN = "269"  !CDS_PN = "269";
"DQ20_A":   PN = "36"  !CDS_PN = "36";
"DQ20_B":   PN = "129"  !CDS_PN = "129";
"DQ21_A":   PN = "38"  !CDS_PN = "38";
"DQ21_B":   PN = "131"  !CDS_PN = "131";
"DQ22_A":   PN = "181"  !CDS_PN = "181";
"DQ22_B":   PN = "274"  !CDS_PN = "274";
"DQ23_A":   PN = "183"  !CDS_PN = "183";
"DQ23_B":   PN = "276"  !CDS_PN = "276";
"DQ24_A":   PN = "40"  !CDS_PN = "40";
"DQ24_B":   PN = "133"  !CDS_PN = "133";
"DQ25_A":   PN = "42"  !CDS_PN = "42";
"DQ25_B":   PN = "135"  !CDS_PN = "135";
"DQ26_A":   PN = "185"  !CDS_PN = "185";
"DQ26_B":   PN = "278"  !CDS_PN = "278";
"DQ27_A":   PN = "187"  !CDS_PN = "187";
"DQ27_B":   PN = "280"  !CDS_PN = "280";
"DQ28_A":   PN = "47"  !CDS_PN = "47";
"DQ28_B":   PN = "140"  !CDS_PN = "140";
"DQ29_A":   PN = "49"  !CDS_PN = "49";
"DQ29_B":   PN = "142"  !CDS_PN = "142";
"DQ30_A":   PN = "192"  !CDS_PN = "192";
"DQ30_B":   PN = "285"  !CDS_PN = "285";
"DQ31_A":   PN = "194"  !CDS_PN = "194";
"DQ31_B":   PN = "287"  !CDS_PN = "287";
"HSA":   PN = "148"  !CDS_PN = "148";
"HSCL":   PN = "4"  !CDS_PN = "4";
"HSDA":   PN = "5"  !CDS_PN = "5";
"LBD||RSP_A_N":   PN = "86"  !CDS_PN = "86";
"LBS||RSP_B_N":   PN = "87"  !CDS_PN = "87";
"PAR_A":   PN = "74"  !CDS_PN = "74";
"PAR_B":   PN = "227"  !CDS_PN = "227";
"PWR_GOOD||FAIL_N":   PN = "147"  !CDS_PN = "147";
"RESET_N":   PN = "207"  !CDS_PN = "207";
"RFU0":   PN = "2"  !CDS_PN = "2";
"RFU1":   PN = "144"  !CDS_PN = "144";
"RFU2":   PN = "149"  !CDS_PN = "149";
"RFU3":   PN = "150"  !CDS_PN = "150";
"RFU4":   PN = "220"  !CDS_PN = "220";
"RFU5":   PN = "231"  !CDS_PN = "231";
"RFU6":   PN = "232"  !CDS_PN = "232";
"VIN_MGMT":   PN = "3"  !CDS_PN = "3";
BODY = "SCONN288_ADR50017P130CC","I202": #LOCATION = "J1" !CDS_LOCATION = "J1" &SEC = "2" #&CDS_SEC = "2";
"DQS0_A_C":   PN = "12"  !CDS_PN = "12";
"DQS0_A_T":   PN = "11"  !CDS_PN = "11";
"DQS0_B_C":   PN = "105"  !CDS_PN = "105";
"DQS0_B_T":   PN = "104"  !CDS_PN = "104";
"DQS1_A_C":   PN = "23"  !CDS_PN = "23";
"DQS1_A_T":   PN = "22"  !CDS_PN = "22";
"DQS1_B_C":   PN = "116"  !CDS_PN = "116";
"DQS1_B_T":   PN = "115"  !CDS_PN = "115";
"DQS2_A_C":   PN = "34"  !CDS_PN = "34";
"DQS2_A_T":   PN = "33"  !CDS_PN = "33";
"DQS2_B_C":   PN = "127"  !CDS_PN = "127";
"DQS2_B_T":   PN = "126"  !CDS_PN = "126";
"DQS3_A_C":   PN = "45"  !CDS_PN = "45";
"DQS3_A_T":   PN = "44"  !CDS_PN = "44";
"DQS3_B_C":   PN = "138"  !CDS_PN = "138";
"DQS3_B_T":   PN = "137"  !CDS_PN = "137";
"DQS4_A_C":   PN = "56"  !CDS_PN = "56";
"DQS4_A_T":   PN = "55"  !CDS_PN = "55";
"DQS4_B_C":   PN = "238"  !CDS_PN = "238";
"DQS4_B_T":   PN = "239"  !CDS_PN = "239";
"DQS5_A_C||TDQS5_A_C||DQS5_A_T||TDQS5_A_T":   PN = "156"  !CDS_PN = "156";
"DQS5_A_T||TDQS5_A_T":   PN = "157"  !CDS_PN = "157";
"DQS5_B_C||TDQS5_B_C":   PN = "249"  !CDS_PN = "249";
"DQS5_B_T||TDQS5_B_T":   PN = "250"  !CDS_PN = "250";
"DQS6_A_C||TDQS6_A_C||DQS6_A_T||TDQS6_A_T":   PN = "167"  !CDS_PN = "167";
"DQS6_A_T||TDQS6_A_T":   PN = "168"  !CDS_PN = "168";
"DQS6_B_C||TDQS6_B_C":   PN = "260"  !CDS_PN = "260";
"DQS6_B_T||TDQS6_B_T":   PN = "261"  !CDS_PN = "261";
"DQS7_A_C||TDQS7_A_C":   PN = "178"  !CDS_PN = "178";
"DQS7_A_T||TDQS7_A_T":   PN = "179"  !CDS_PN = "179";
"DQS7_B_C||TDQS7_B_C":   PN = "271"  !CDS_PN = "271";
"DQS7_B_T||TDQS7_B_T":   PN = "272"  !CDS_PN = "272";
"DQS8_A_C||TDQS8_A_C":   PN = "189"  !CDS_PN = "189";
"DQS8_A_T||TDQS8_A_T":   PN = "190"  !CDS_PN = "190";
"DQS8_B_C||TDQS8_B_C":   PN = "282"  !CDS_PN = "282";
"DQS8_B_T||TDQS8_B_T":   PN = "283"  !CDS_PN = "283";
"DQS9_A_C||TDQS9_A_C":   PN = "200"  !CDS_PN = "200";
"DQS9_A_T||TDQS9_A_T":   PN = "201"  !CDS_PN = "201";
"DQS9_B_C||TDQS9_B_C":   PN = "94"  !CDS_PN = "94";
"DQS9_B_T||TDQS9_B_T||DBI4_B_N":   PN = "93"  !CDS_PN = "93";
BODY = "SCONN288_ADR50017P130CC","I203": #LOCATION = "J1" !CDS_LOCATION = "J1" &SEC = "3" #&CDS_SEC = "3";
"G1":   PN = "G1"  !CDS_PN = "G1";
"G2":   PN = "G2"  !CDS_PN = "G2";
"G3":   PN = "G3"  !CDS_PN = "G3";
"VIN_BULK0":   PN = "1"  !CDS_PN = "1";
"VIN_BULK1":   PN = "145"  !CDS_PN = "145";
"VIN_BULK2":   PN = "146"  !CDS_PN = "146";
"VSS0":   PN = "6"  !CDS_PN = "6";
"VSS1":   PN = "8"  !CDS_PN = "8";
"VSS2":   PN = "10"  !CDS_PN = "10";
"VSS3":   PN = "13"  !CDS_PN = "13";
"VSS4":   PN = "15"  !CDS_PN = "15";
"VSS5":   PN = "17"  !CDS_PN = "17";
"VSS6":   PN = "19"  !CDS_PN = "19";
"VSS7":   PN = "21"  !CDS_PN = "21";
"VSS8":   PN = "24"  !CDS_PN = "24";
"VSS9":   PN = "26"  !CDS_PN = "26";
"VSS10":   PN = "28"  !CDS_PN = "28";
"VSS11":   PN = "30"  !CDS_PN = "30";
"VSS12":   PN = "32"  !CDS_PN = "32";
"VSS13":   PN = "35"  !CDS_PN = "35";
"VSS14":   PN = "37"  !CDS_PN = "37";
"VSS15":   PN = "39"  !CDS_PN = "39";
"VSS16":   PN = "41"  !CDS_PN = "41";
"VSS17":   PN = "43"  !CDS_PN = "43";
"VSS18":   PN = "46"  !CDS_PN = "46";
"VSS19":   PN = "48"  !CDS_PN = "48";
"VSS20":   PN = "50"  !CDS_PN = "50";
"VSS21":   PN = "52"  !CDS_PN = "52";
"VSS22":   PN = "54"  !CDS_PN = "54";
"VSS23":   PN = "57"  !CDS_PN = "57";
"VSS24":   PN = "59"  !CDS_PN = "59";
"VSS25":   PN = "61"  !CDS_PN = "61";
"VSS26":   PN = "63"  !CDS_PN = "63";
"VSS27":   PN = "65"  !CDS_PN = "65";
"VSS28":   PN = "67"  !CDS_PN = "67";
"VSS29":   PN = "69"  !CDS_PN = "69";
"VSS30":   PN = "71"  !CDS_PN = "71";
"VSS31":   PN = "73"  !CDS_PN = "73";
"VSS32":   PN = "75"  !CDS_PN = "75";
"VSS33":   PN = "77"  !CDS_PN = "77";
"VSS34":   PN = "79"  !CDS_PN = "79";
"VSS35":   PN = "81"  !CDS_PN = "81";
"VSS36":   PN = "83"  !CDS_PN = "83";
"VSS37":   PN = "85"  !CDS_PN = "85";
"VSS38":   PN = "88"  !CDS_PN = "88";
"VSS39":   PN = "90"  !CDS_PN = "90";
"VSS40":   PN = "92"  !CDS_PN = "92";
"VSS41":   PN = "95"  !CDS_PN = "95";
"VSS42":   PN = "97"  !CDS_PN = "97";
"VSS43":   PN = "99"  !CDS_PN = "99";
"VSS44":   PN = "101"  !CDS_PN = "101";
"VSS45":   PN = "103"  !CDS_PN = "103";
"VSS46":   PN = "106"  !CDS_PN = "106";
"VSS47":   PN = "108"  !CDS_PN = "108";
"VSS48":   PN = "110"  !CDS_PN = "110";
"VSS49":   PN = "112"  !CDS_PN = "112";
"VSS50":   PN = "114"  !CDS_PN = "114";
"VSS51":   PN = "117"  !CDS_PN = "117";
"VSS52":   PN = "119"  !CDS_PN = "119";
"VSS53":   PN = "121"  !CDS_PN = "121";
"VSS54":   PN = "123"  !CDS_PN = "123";
"VSS55":   PN = "125"  !CDS_PN = "125";
"VSS56":   PN = "128"  !CDS_PN = "128";
"VSS57":   PN = "130"  !CDS_PN = "130";
"VSS58":   PN = "132"  !CDS_PN = "132";
"VSS59":   PN = "134"  !CDS_PN = "134";
"VSS60":   PN = "136"  !CDS_PN = "136";
"VSS61":   PN = "139"  !CDS_PN = "139";
"VSS62":   PN = "141"  !CDS_PN = "141";
"VSS63":   PN = "143"  !CDS_PN = "143";
"VSS64":   PN = "151"  !CDS_PN = "151";
"VSS65":   PN = "153"  !CDS_PN = "153";
"VSS66":   PN = "155"  !CDS_PN = "155";
"VSS67":   PN = "158"  !CDS_PN = "158";
"VSS68":   PN = "160"  !CDS_PN = "160";
"VSS69":   PN = "162"  !CDS_PN = "162";
"VSS70":   PN = "164"  !CDS_PN = "164";
"VSS71":   PN = "166"  !CDS_PN = "166";
"VSS72":   PN = "169"  !CDS_PN = "169";
"VSS73":   PN = "171"  !CDS_PN = "171";
"VSS74":   PN = "173"  !CDS_PN = "173";
"VSS75":   PN = "175"  !CDS_PN = "175";
"VSS76":   PN = "177"  !CDS_PN = "177";
"VSS77":   PN = "180"  !CDS_PN = "180";
"VSS78":   PN = "182"  !CDS_PN = "182";
"VSS79":   PN = "184"  !CDS_PN = "184";
"VSS80":   PN = "186"  !CDS_PN = "186";
"VSS81":   PN = "188"  !CDS_PN = "188";
"VSS82":   PN = "191"  !CDS_PN = "191";
"VSS83":   PN = "193"  !CDS_PN = "193";
"VSS84":   PN = "195"  !CDS_PN = "195";
"VSS85":   PN = "197"  !CDS_PN = "197";
"VSS86":   PN = "199"  !CDS_PN = "199";
"VSS87":   PN = "202"  !CDS_PN = "202";
"VSS88":   PN = "204"  !CDS_PN = "204";
"VSS89":   PN = "206"  !CDS_PN = "206";
"VSS90":   PN = "208"  !CDS_PN = "208";
"VSS91":   PN = "210"  !CDS_PN = "210";
"VSS92":   PN = "212"  !CDS_PN = "212";
"VSS93":   PN = "214"  !CDS_PN = "214";
"VSS94":   PN = "216"  !CDS_PN = "216";
"VSS95":   PN = "219"  !CDS_PN = "219";
"VSS96":   PN = "222"  !CDS_PN = "222";
"VSS97":   PN = "224"  !CDS_PN = "224";
"VSS98":   PN = "226"  !CDS_PN = "226";
"VSS99":   PN = "228"  !CDS_PN = "228";
"VSS100":   PN = "230"  !CDS_PN = "230";
"VSS101":   PN = "233"  !CDS_PN = "233";
"VSS102":   PN = "235"  !CDS_PN = "235";
"VSS103":   PN = "237"  !CDS_PN = "237";
"VSS104":   PN = "240"  !CDS_PN = "240";
"VSS105":   PN = "242"  !CDS_PN = "242";
"VSS106":   PN = "244"  !CDS_PN = "244";
"VSS107":   PN = "246"  !CDS_PN = "246";
"VSS108":   PN = "248"  !CDS_PN = "248";
"VSS109":   PN = "251"  !CDS_PN = "251";
"VSS110":   PN = "253"  !CDS_PN = "253";
"VSS111":   PN = "255"  !CDS_PN = "255";
"VSS112":   PN = "257"  !CDS_PN = "257";
"VSS113":   PN = "259"  !CDS_PN = "259";
"VSS114":   PN = "262"  !CDS_PN = "262";
"VSS115":   PN = "264"  !CDS_PN = "264";
"VSS116":   PN = "266"  !CDS_PN = "266";
"VSS117":   PN = "268"  !CDS_PN = "268";
"VSS118":   PN = "270"  !CDS_PN = "270";
"VSS119":   PN = "273"  !CDS_PN = "273";
"VSS120":   PN = "275"  !CDS_PN = "275";
"VSS121":   PN = "277"  !CDS_PN = "277";
"VSS122":   PN = "279"  !CDS_PN = "279";
"VSS123":   PN = "281"  !CDS_PN = "281";
"VSS124":   PN = "284"  !CDS_PN = "284";
"VSS125":   PN = "286"  !CDS_PN = "286";
"VSS126":   PN = "288"  !CDS_PN = "288";
BODY = "Q_RES","I204": LOCATION = "R3875" #&CDS_LOCATION = "R3875" &SEC = "1" #&CDS_SEC = "1";
"A":   PN = "1"  !CDS_PN = "1";
"B":   PN = "2"  !CDS_PN = "2";
DRAWING = "@s9s_mb_2u_lib.s9s_mb_2u(sch_1):page83";
BODY = "Q_RES","I10": LOCATION = "R27" #&CDS_LOCATION = "R27" &SEC = "1" #&CDS_SEC = "1";
"A":   PN = "1"  !CDS_PN = "1";
"B":   PN = "2"  !CDS_PN = "2";
BODY = "Q_CAP","I120": LOCATION = "C5" #&CDS_LOCATION = "C5" &SEC = "1" #&CDS_SEC = "1";
"A":   PN = "1"  !CDS_PN = "1";
"B":   PN = "2"  !CDS_PN = "2";
BODY = "Q_CAP","I122": LOCATION = "C6" #&CDS_LOCATION = "C6" &SEC = "1" #&CDS_SEC = "1";
"A":   PN = "1"  !CDS_PN = "1";
"B":   PN = "2"  !CDS_PN = "2";
BODY = "Q_CAP","I144": LOCATION = "C7" #&CDS_LOCATION = "C7" &SEC = "1" #&CDS_SEC = "1";
"A":   PN = "1"  !CDS_PN = "1";
"B":   PN = "2"  !CDS_PN = "2";
BODY = "SCONN288_ADR50017P087CC","I177": LOCATION = "J2" #&CDS_LOCATION = "J2" &SEC = "1" #&CDS_SEC = "1";
"ALERT_N":   PN = "62"  !CDS_PN = "62";
"CA0_A":   PN = "66"  !CDS_PN = "66";
"CA0_B":   PN = "76"  !CDS_PN = "76";
"CA1_A":   PN = "211"  !CDS_PN = "211";
"CA1_B":   PN = "221"  !CDS_PN = "221";
"CA2_A":   PN = "68"  !CDS_PN = "68";
"CA2_B":   PN = "78"  !CDS_PN = "78";
"CA3_A":   PN = "213"  !CDS_PN = "213";
"CA3_B":   PN = "223"  !CDS_PN = "223";
"CA4_A":   PN = "70"  !CDS_PN = "70";
"CA4_B":   PN = "80"  !CDS_PN = "80";
"CA5_A":   PN = "215"  !CDS_PN = "215";
"CA5_B":   PN = "225"  !CDS_PN = "225";
"CA6_A":   PN = "72"  !CDS_PN = "72";
"CA6_B":   PN = "82"  !CDS_PN = "82";
"CB0_A":   PN = "51"  !CDS_PN = "51";
"CB0_B":   PN = "96"  !CDS_PN = "96";
"CB1_A":   PN = "53"  !CDS_PN = "53";
"CB1_B":   PN = "98"  !CDS_PN = "98";
"CB2_A":   PN = "196"  !CDS_PN = "196";
"CB2_B":   PN = "241"  !CDS_PN = "241";
"CB3_A":   PN = "198"  !CDS_PN = "198";
"CB3_B":   PN = "243"  !CDS_PN = "243";
"CB4_A":   PN = "58"  !CDS_PN = "58";
"CB4_B":   PN = "89"  !CDS_PN = "89";
"CB5_A":   PN = "60"  !CDS_PN = "60";
"CB5_B":   PN = "91"  !CDS_PN = "91";
"CB6_A":   PN = "203"  !CDS_PN = "203";
"CB6_B":   PN = "234"  !CDS_PN = "234";
"CB7_A":   PN = "205"  !CDS_PN = "205";
"CB7_B":   PN = "236"  !CDS_PN = "236";
"CK_C":   PN = "218"  !CDS_PN = "218";
"CK_T":   PN = "217"  !CDS_PN = "217";
"CS0_A_N":   PN = "64"  !CDS_PN = "64";
"CS0_B_N":   PN = "84"  !CDS_PN = "84";
"CS1_A_N":   PN = "209"  !CDS_PN = "209";
"CS1_B_N":   PN = "229"  !CDS_PN = "229";
"DQ0_A":   PN = "7"  !CDS_PN = "7";
"DQ0_B":   PN = "100"  !CDS_PN = "100";
"DQ1_A":   PN = "9"  !CDS_PN = "9";
"DQ1_B":   PN = "102"  !CDS_PN = "102";
"DQ2_A":   PN = "152"  !CDS_PN = "152";
"DQ2_B":   PN = "245"  !CDS_PN = "245";
"DQ3_A":   PN = "154"  !CDS_PN = "154";
"DQ3_B":   PN = "247"  !CDS_PN = "247";
"DQ4_A":   PN = "14"  !CDS_PN = "14";
"DQ4_B":   PN = "107"  !CDS_PN = "107";
"DQ5_A":   PN = "16"  !CDS_PN = "16";
"DQ5_B":   PN = "109"  !CDS_PN = "109";
"DQ6_A":   PN = "159"  !CDS_PN = "159";
"DQ6_B":   PN = "252"  !CDS_PN = "252";
"DQ7_A":   PN = "161"  !CDS_PN = "161";
"DQ7_B":   PN = "254"  !CDS_PN = "254";
"DQ8_A":   PN = "18"  !CDS_PN = "18";
"DQ8_B":   PN = "111"  !CDS_PN = "111";
"DQ9_A":   PN = "20"  !CDS_PN = "20";
"DQ9_B":   PN = "113"  !CDS_PN = "113";
"DQ10_A":   PN = "163"  !CDS_PN = "163";
"DQ10_B":   PN = "256"  !CDS_PN = "256";
"DQ11_A":   PN = "165"  !CDS_PN = "165";
"DQ11_B":   PN = "258"  !CDS_PN = "258";
"DQ12_A":   PN = "25"  !CDS_PN = "25";
"DQ12_B":   PN = "118"  !CDS_PN = "118";
"DQ13_A":   PN = "27"  !CDS_PN = "27";
"DQ13_B":   PN = "120"  !CDS_PN = "120";
"DQ14_A":   PN = "170"  !CDS_PN = "170";
"DQ14_B":   PN = "263"  !CDS_PN = "263";
"DQ15_A":   PN = "172"  !CDS_PN = "172";
"DQ15_B":   PN = "265"  !CDS_PN = "265";
"DQ16_A":   PN = "29"  !CDS_PN = "29";
"DQ16_B":   PN = "122"  !CDS_PN = "122";
"DQ17_A":   PN = "31"  !CDS_PN = "31";
"DQ17_B":   PN = "124"  !CDS_PN = "124";
"DQ18_A":   PN = "174"  !CDS_PN = "174";
"DQ18_B":   PN = "267"  !CDS_PN = "267";
"DQ19_A":   PN = "176"  !CDS_PN = "176";
"DQ19_B":   PN = "269"  !CDS_PN = "269";
"DQ20_A":   PN = "36"  !CDS_PN = "36";
"DQ20_B":   PN = "129"  !CDS_PN = "129";
"DQ21_A":   PN = "38"  !CDS_PN = "38";
"DQ21_B":   PN = "131"  !CDS_PN = "131";
"DQ22_A":   PN = "181"  !CDS_PN = "181";
"DQ22_B":   PN = "274"  !CDS_PN = "274";
"DQ23_A":   PN = "183"  !CDS_PN = "183";
"DQ23_B":   PN = "276"  !CDS_PN = "276";
"DQ24_A":   PN = "40"  !CDS_PN = "40";
"DQ24_B":   PN = "133"  !CDS_PN = "133";
"DQ25_A":   PN = "42"  !CDS_PN = "42";
"DQ25_B":   PN = "135"  !CDS_PN = "135";
"DQ26_A":   PN = "185"  !CDS_PN = "185";
"DQ26_B":   PN = "278"  !CDS_PN = "278";
"DQ27_A":   PN = "187"  !CDS_PN = "187";
"DQ27_B":   PN = "280"  !CDS_PN = "280";
"DQ28_A":   PN = "47"  !CDS_PN = "47";
"DQ28_B":   PN = "140"  !CDS_PN = "140";
"DQ29_A":   PN = "49"  !CDS_PN = "49";
"DQ29_B":   PN = "142"  !CDS_PN = "142";
"DQ30_A":   PN = "192"  !CDS_PN = "192";
"DQ30_B":   PN = "285"  !CDS_PN = "285";
"DQ31_A":   PN = "194"  !CDS_PN = "194";
"DQ31_B":   PN = "287"  !CDS_PN = "287";
"HSA":   PN = "148"  !CDS_PN = "148";
"HSCL":   PN = "4"  !CDS_PN = "4";
"HSDA":   PN = "5"  !CDS_PN = "5";
"LBD||RSP_A_N":   PN = "86"  !CDS_PN = "86";
"LBS||RSP_B_N":   PN = "87"  !CDS_PN = "87";
"PAR_A":   PN = "74"  !CDS_PN = "74";
"PAR_B":   PN = "227"  !CDS_PN = "227";
"PWR_GOOD||FAIL_N":   PN = "147"  !CDS_PN = "147";
"RESET_N":   PN = "207"  !CDS_PN = "207";
"RFU0":   PN = "2"  !CDS_PN = "2";
"RFU1":   PN = "144"  !CDS_PN = "144";
"RFU2":   PN = "149"  !CDS_PN = "149";
"RFU3":   PN = "150"  !CDS_PN = "150";
"RFU4":   PN = "220"  !CDS_PN = "220";
"RFU5":   PN = "231"  !CDS_PN = "231";
"RFU6":   PN = "232"  !CDS_PN = "232";
"VIN_MGMT":   PN = "3"  !CDS_PN = "3";
BODY = "SCONN288_ADR50017P087CC","I179": LOCATION = "J2" #&CDS_LOCATION = "J2" &SEC = "3" #&CDS_SEC = "3";
"G1":   PN = "G1"  !CDS_PN = "G1";
"G2":   PN = "G2"  !CDS_PN = "G2";
"G3":   PN = "G3"  !CDS_PN = "G3";
"VIN_BULK0":   PN = "1"  !CDS_PN = "1";
"VIN_BULK1":   PN = "145"  !CDS_PN = "145";
"VIN_BULK2":   PN = "146"  !CDS_PN = "146";
"VSS0":   PN = "6"  !CDS_PN = "6";
"VSS1":   PN = "8"  !CDS_PN = "8";
"VSS2":   PN = "10"  !CDS_PN = "10";
"VSS3":   PN = "13"  !CDS_PN = "13";
"VSS4":   PN = "15"  !CDS_PN = "15";
"VSS5":   PN = "17"  !CDS_PN = "17";
"VSS6":   PN = "19"  !CDS_PN = "19";
"VSS7":   PN = "21"  !CDS_PN = "21";
"VSS8":   PN = "24"  !CDS_PN = "24";
"VSS9":   PN = "26"  !CDS_PN = "26";
"VSS10":   PN = "28"  !CDS_PN = "28";
"VSS11":   PN = "30"  !CDS_PN = "30";
"VSS12":   PN = "32"  !CDS_PN = "32";
"VSS13":   PN = "35"  !CDS_PN = "35";
"VSS14":   PN = "37"  !CDS_PN = "37";
"VSS15":   PN = "39"  !CDS_PN = "39";
"VSS16":   PN = "41"  !CDS_PN = "41";
"VSS17":   PN = "43"  !CDS_PN = "43";
"VSS18":   PN = "46"  !CDS_PN = "46";
"VSS19":   PN = "48"  !CDS_PN = "48";
"VSS20":   PN = "50"  !CDS_PN = "50";
"VSS21":   PN = "52"  !CDS_PN = "52";
"VSS22":   PN = "54"  !CDS_PN = "54";
"VSS23":   PN = "57"  !CDS_PN = "57";
"VSS24":   PN = "59"  !CDS_PN = "59";
"VSS25":   PN = "61"  !CDS_PN = "61";
"VSS26":   PN = "63"  !CDS_PN = "63";
"VSS27":   PN = "65"  !CDS_PN = "65";
"VSS28":   PN = "67"  !CDS_PN = "67";
"VSS29":   PN = "69"  !CDS_PN = "69";
"VSS30":   PN = "71"  !CDS_PN = "71";
"VSS31":   PN = "73"  !CDS_PN = "73";
"VSS32":   PN = "75"  !CDS_PN = "75";
"VSS33":   PN = "77"  !CDS_PN = "77";
"VSS34":   PN = "79"  !CDS_PN = "79";
"VSS35":   PN = "81"  !CDS_PN = "81";
"VSS36":   PN = "83"  !CDS_PN = "83";
"VSS37":   PN = "85"  !CDS_PN = "85";
"VSS38":   PN = "88"  !CDS_PN = "88";
"VSS39":   PN = "90"  !CDS_PN = "90";
"VSS40":   PN = "92"  !CDS_PN = "92";
"VSS41":   PN = "95"  !CDS_PN = "95";
"VSS42":   PN = "97"  !CDS_PN = "97";
"VSS43":   PN = "99"  !CDS_PN = "99";
"VSS44":   PN = "101"  !CDS_PN = "101";
"VSS45":   PN = "103"  !CDS_PN = "103";
"VSS46":   PN = "106"  !CDS_PN = "106";
"VSS47":   PN = "108"  !CDS_PN = "108";
"VSS48":   PN = "110"  !CDS_PN = "110";
"VSS49":   PN = "112"  !CDS_PN = "112";
"VSS50":   PN = "114"  !CDS_PN = "114";
"VSS51":   PN = "117"  !CDS_PN = "117";
"VSS52":   PN = "119"  !CDS_PN = "119";
"VSS53":   PN = "121"  !CDS_PN = "121";
"VSS54":   PN = "123"  !CDS_PN = "123";
"VSS55":   PN = "125"  !CDS_PN = "125";
"VSS56":   PN = "128"  !CDS_PN = "128";
"VSS57":   PN = "130"  !CDS_PN = "130";
"VSS58":   PN = "132"  !CDS_PN = "132";
"VSS59":   PN = "134"  !CDS_PN = "134";
"VSS60":   PN = "136"  !CDS_PN = "136";
"VSS61":   PN = "139"  !CDS_PN = "139";
"VSS62":   PN = "141"  !CDS_PN = "141";
"VSS63":   PN = "143"  !CDS_PN = "143";
"VSS64":   PN = "151"  !CDS_PN = "151";
"VSS65":   PN = "153"  !CDS_PN = "153";
"VSS66":   PN = "155"  !CDS_PN = "155";
"VSS67":   PN = "158"  !CDS_PN = "158";
"VSS68":   PN = "160"  !CDS_PN = "160";
"VSS69":   PN = "162"  !CDS_PN = "162";
"VSS70":   PN = "164"  !CDS_PN = "164";
"VSS71":   PN = "166"  !CDS_PN = "166";
"VSS72":   PN = "169"  !CDS_PN = "169";
"VSS73":   PN = "171"  !CDS_PN = "171";
"VSS74":   PN = "173"  !CDS_PN = "173";
"VSS75":   PN = "175"  !CDS_PN = "175";
"VSS76":   PN = "177"  !CDS_PN = "177";
"VSS77":   PN = "180"  !CDS_PN = "180";
"VSS78":   PN = "182"  !CDS_PN = "182";
"VSS79":   PN = "184"  !CDS_PN = "184";
"VSS80":   PN = "186"  !CDS_PN = "186";
"VSS81":   PN = "188"  !CDS_PN = "188";
"VSS82":   PN = "191"  !CDS_PN = "191";
"VSS83":   PN = "193"  !CDS_PN = "193";
"VSS84":   PN = "195"  !CDS_PN = "195";
"VSS85":   PN = "197"  !CDS_PN = "197";
"VSS86":   PN = "199"  !CDS_PN = "199";
"VSS87":   PN = "202"  !CDS_PN = "202";
"VSS88":   PN = "204"  !CDS_PN = "204";
"VSS89":   PN = "206"  !CDS_PN = "206";
"VSS90":   PN = "208"  !CDS_PN = "208";
"VSS91":   PN = "210"  !CDS_PN = "210";
"VSS92":   PN = "212"  !CDS_PN = "212";
"VSS93":   PN = "214"  !CDS_PN = "214";
"VSS94":   PN = "216"  !CDS_PN = "216";
"VSS95":   PN = "219"  !CDS_PN = "219";
"VSS96":   PN = "222"  !CDS_PN = "222";
"VSS97":   PN = "224"  !CDS_PN = "224";
"VSS98":   PN = "226"  !CDS_PN = "226";
"VSS99":   PN = "228"  !CDS_PN = "228";
"VSS100":   PN = "230"  !CDS_PN = "230";
"VSS101":   PN = "233"  !CDS_PN = "233";
"VSS102":   PN = "235"  !CDS_PN = "235";
"VSS103":   PN = "237"  !CDS_PN = "237";
"VSS104":   PN = "240"  !CDS_PN = "240";
"VSS105":   PN = "242"  !CDS_PN = "242";
"VSS106":   PN = "244"  !CDS_PN = "244";
"VSS107":   PN = "246"  !CDS_PN = "246";
"VSS108":   PN = "248"  !CDS_PN = "248";
"VSS109":   PN = "251"  !CDS_PN = "251";
"VSS110":   PN = "253"  !CDS_PN = "253";
"VSS111":   PN = "255"  !CDS_PN = "255";
"VSS112":   PN = "257"  !CDS_PN = "257";
"VSS113":   PN = "259"  !CDS_PN = "259";
"VSS114":   PN = "262"  !CDS_PN = "262";
"VSS115":   PN = "264"  !CDS_PN = "264";
"VSS116":   PN = "266"  !CDS_PN = "266";
"VSS117":   PN = "268"  !CDS_PN = "268";
"VSS118":   PN = "270"  !CDS_PN = "270";
"VSS119":   PN = "273"  !CDS_PN = "273";
"VSS120":   PN = "275"  !CDS_PN = "275";
"VSS121":   PN = "277"  !CDS_PN = "277";
"VSS122":   PN = "279"  !CDS_PN = "279";
"VSS123":   PN = "281"  !CDS_PN = "281";
"VSS124":   PN = "284"  !CDS_PN = "284";
"VSS125":   PN = "286"  !CDS_PN = "286";
"VSS126":   PN = "288"  !CDS_PN = "288";
BODY = "SCONN288_ADR50017P087CC","I181": #LOCATION = "J2" !CDS_LOCATION = "J2" &SEC = "2" #&CDS_SEC = "2";
"DQS0_A_C":   PN = "12"  !CDS_PN = "12";
"DQS0_A_T":   PN = "11"  !CDS_PN = "11";
"DQS0_B_C":   PN = "105"  !CDS_PN = "105";
"DQS0_B_T":   PN = "104"  !CDS_PN = "104";
"DQS1_A_C":   PN = "23"  !CDS_PN = "23";
"DQS1_A_T":   PN = "22"  !CDS_PN = "22";
"DQS1_B_C":   PN = "116"  !CDS_PN = "116";
"DQS1_B_T":   PN = "115"  !CDS_PN = "115";
"DQS2_A_C":   PN = "34"  !CDS_PN = "34";
"DQS2_A_T":   PN = "33"  !CDS_PN = "33";
"DQS2_B_C":   PN = "127"  !CDS_PN = "127";
"DQS2_B_T":   PN = "126"  !CDS_PN = "126";
"DQS3_A_C":   PN = "45"  !CDS_PN = "45";
"DQS3_A_T":   PN = "44"  !CDS_PN = "44";
"DQS3_B_C":   PN = "138"  !CDS_PN = "138";
"DQS3_B_T":   PN = "137"  !CDS_PN = "137";
"DQS4_A_C":   PN = "56"  !CDS_PN = "56";
"DQS4_A_T":   PN = "55"  !CDS_PN = "55";
"DQS4_B_C":   PN = "238"  !CDS_PN = "238";
"DQS4_B_T":   PN = "239"  !CDS_PN = "239";
"DQS5_A_C||TDQS5_A_C||DQS5_A_T||TDQS5_A_T":   PN = "156"  !CDS_PN = "156";
"DQS5_A_T||TDQS5_A_T":   PN = "157"  !CDS_PN = "157";
"DQS5_B_C||TDQS5_B_C":   PN = "249"  !CDS_PN = "249";
"DQS5_B_T||TDQS5_B_T":   PN = "250"  !CDS_PN = "250";
"DQS6_A_C||TDQS6_A_C||DQS6_A_T||TDQS6_A_T":   PN = "167"  !CDS_PN = "167";
"DQS6_A_T||TDQS6_A_T":   PN = "168"  !CDS_PN = "168";
"DQS6_B_C||TDQS6_B_C":   PN = "260"  !CDS_PN = "260";
"DQS6_B_T||TDQS6_B_T":   PN = "261"  !CDS_PN = "261";
"DQS7_A_C||TDQS7_A_C":   PN = "178"  !CDS_PN = "178";
"DQS7_A_T||TDQS7_A_T":   PN = "179"  !CDS_PN = "179";
"DQS7_B_C||TDQS7_B_C":   PN = "271"  !CDS_PN = "271";
"DQS7_B_T||TDQS7_B_T":   PN = "272"  !CDS_PN = "272";
"DQS8_A_C||TDQS8_A_C":   PN = "189"  !CDS_PN = "189";
"DQS8_A_T||TDQS8_A_T":   PN = "190"  !CDS_PN = "190";
"DQS8_B_C||TDQS8_B_C":   PN = "282"  !CDS_PN = "282";
"DQS8_B_T||TDQS8_B_T":   PN = "283"  !CDS_PN = "283";
"DQS9_A_C||TDQS9_A_C":   PN = "200"  !CDS_PN = "200";
"DQS9_A_T||TDQS9_A_T":   PN = "201"  !CDS_PN = "201";
"DQS9_B_C||TDQS9_B_C":   PN = "94"  !CDS_PN = "94";
"DQS9_B_T||TDQS9_B_T||DBI4_B_N":   PN = "93"  !CDS_PN = "93";
BODY = "Q_RES","I182": LOCATION = "R3876" #&CDS_LOCATION = "R3876" &SEC = "1" #&CDS_SEC = "1";
"A":   PN = "1"  !CDS_PN = "1";
"B":   PN = "2"  !CDS_PN = "2";
DRAWING = "@s9s_mb_2u_lib.s9s_mb_2u(sch_1):page84";
BODY = "Q_RES","I10": LOCATION = "R28" #&CDS_LOCATION = "R28" &SEC = "1" #&CDS_SEC = "1";
"A":   PN = "1"  !CDS_PN = "1";
"B":   PN = "2"  !CDS_PN = "2";
BODY = "Q_CAP","I121": LOCATION = "C8" #&CDS_LOCATION = "C8" &SEC = "1" #&CDS_SEC = "1";
"A":   PN = "1"  !CDS_PN = "1";
"B":   PN = "2"  !CDS_PN = "2";
BODY = "Q_CAP","I122": LOCATION = "C9" #&CDS_LOCATION = "C9" &SEC = "1" #&CDS_SEC = "1";
"A":   PN = "1"  !CDS_PN = "1";
"B":   PN = "2"  !CDS_PN = "2";
BODY = "Q_CAP","I144": LOCATION = "C10" #&CDS_LOCATION = "C10" &SEC = "1" #&CDS_SEC = "1";
"A":   PN = "1"  !CDS_PN = "1";
"B":   PN = "2"  !CDS_PN = "2";
BODY = "SCONN288_ADR50017P130CC","I178": #LOCATION = "J3" !CDS_LOCATION = "J3" &SEC = "3" #&CDS_SEC = "3";
"G1":   PN = "G1"  !CDS_PN = "G1";
"G2":   PN = "G2"  !CDS_PN = "G2";
"G3":   PN = "G3"  !CDS_PN = "G3";
"VIN_BULK0":   PN = "1"  !CDS_PN = "1";
"VIN_BULK1":   PN = "145"  !CDS_PN = "145";
"VIN_BULK2":   PN = "146"  !CDS_PN = "146";
"VSS0":   PN = "6"  !CDS_PN = "6";
"VSS1":   PN = "8"  !CDS_PN = "8";
"VSS2":   PN = "10"  !CDS_PN = "10";
"VSS3":   PN = "13"  !CDS_PN = "13";
"VSS4":   PN = "15"  !CDS_PN = "15";
"VSS5":   PN = "17"  !CDS_PN = "17";
"VSS6":   PN = "19"  !CDS_PN = "19";
"VSS7":   PN = "21"  !CDS_PN = "21";
"VSS8":   PN = "24"  !CDS_PN = "24";
"VSS9":   PN = "26"  !CDS_PN = "26";
"VSS10":   PN = "28"  !CDS_PN = "28";
"VSS11":   PN = "30"  !CDS_PN = "30";
"VSS12":   PN = "32"  !CDS_PN = "32";
"VSS13":   PN = "35"  !CDS_PN = "35";
"VSS14":   PN = "37"  !CDS_PN = "37";
"VSS15":   PN = "39"  !CDS_PN = "39";
"VSS16":   PN = "41"  !CDS_PN = "41";
"VSS17":   PN = "43"  !CDS_PN = "43";
"VSS18":   PN = "46"  !CDS_PN = "46";
"VSS19":   PN = "48"  !CDS_PN = "48";
"VSS20":   PN = "50"  !CDS_PN = "50";
"VSS21":   PN = "52"  !CDS_PN = "52";
"VSS22":   PN = "54"  !CDS_PN = "54";
"VSS23":   PN = "57"  !CDS_PN = "57";
"VSS24":   PN = "59"  !CDS_PN = "59";
"VSS25":   PN = "61"  !CDS_PN = "61";
"VSS26":   PN = "63"  !CDS_PN = "63";
"VSS27":   PN = "65"  !CDS_PN = "65";
"VSS28":   PN = "67"  !CDS_PN = "67";
"VSS29":   PN = "69"  !CDS_PN = "69";
"VSS30":   PN = "71"  !CDS_PN = "71";
"VSS31":   PN = "73"  !CDS_PN = "73";
"VSS32":   PN = "75"  !CDS_PN = "75";
"VSS33":   PN = "77"  !CDS_PN = "77";
"VSS34":   PN = "79"  !CDS_PN = "79";
"VSS35":   PN = "81"  !CDS_PN = "81";
"VSS36":   PN = "83"  !CDS_PN = "83";
"VSS37":   PN = "85"  !CDS_PN = "85";
"VSS38":   PN = "88"  !CDS_PN = "88";
"VSS39":   PN = "90"  !CDS_PN = "90";
"VSS40":   PN = "92"  !CDS_PN = "92";
"VSS41":   PN = "95"  !CDS_PN = "95";
"VSS42":   PN = "97"  !CDS_PN = "97";
"VSS43":   PN = "99"  !CDS_PN = "99";
"VSS44":   PN = "101"  !CDS_PN = "101";
"VSS45":   PN = "103"  !CDS_PN = "103";
"VSS46":   PN = "106"  !CDS_PN = "106";
"VSS47":   PN = "108"  !CDS_PN = "108";
"VSS48":   PN = "110"  !CDS_PN = "110";
"VSS49":   PN = "112"  !CDS_PN = "112";
"VSS50":   PN = "114"  !CDS_PN = "114";
"VSS51":   PN = "117"  !CDS_PN = "117";
"VSS52":   PN = "119"  !CDS_PN = "119";
"VSS53":   PN = "121"  !CDS_PN = "121";
"VSS54":   PN = "123"  !CDS_PN = "123";
"VSS55":   PN = "125"  !CDS_PN = "125";
"VSS56":   PN = "128"  !CDS_PN = "128";
"VSS57":   PN = "130"  !CDS_PN = "130";
"VSS58":   PN = "132"  !CDS_PN = "132";
"VSS59":   PN = "134"  !CDS_PN = "134";
"VSS60":   PN = "136"  !CDS_PN = "136";
"VSS61":   PN = "139"  !CDS_PN = "139";
"VSS62":   PN = "141"  !CDS_PN = "141";
"VSS63":   PN = "143"  !CDS_PN = "143";
"VSS64":   PN = "151"  !CDS_PN = "151";
"VSS65":   PN = "153"  !CDS_PN = "153";
"VSS66":   PN = "155"  !CDS_PN = "155";
"VSS67":   PN = "158"  !CDS_PN = "158";
"VSS68":   PN = "160"  !CDS_PN = "160";
"VSS69":   PN = "162"  !CDS_PN = "162";
"VSS70":   PN = "164"  !CDS_PN = "164";
"VSS71":   PN = "166"  !CDS_PN = "166";
"VSS72":   PN = "169"  !CDS_PN = "169";
"VSS73":   PN = "171"  !CDS_PN = "171";
"VSS74":   PN = "173"  !CDS_PN = "173";
"VSS75":   PN = "175"  !CDS_PN = "175";
"VSS76":   PN = "177"  !CDS_PN = "177";
"VSS77":   PN = "180"  !CDS_PN = "180";
"VSS78":   PN = "182"  !CDS_PN = "182";
"VSS79":   PN = "184"  !CDS_PN = "184";
"VSS80":   PN = "186"  !CDS_PN = "186";
"VSS81":   PN = "188"  !CDS_PN = "188";
"VSS82":   PN = "191"  !CDS_PN = "191";
"VSS83":   PN = "193"  !CDS_PN = "193";
"VSS84":   PN = "195"  !CDS_PN = "195";
"VSS85":   PN = "197"  !CDS_PN = "197";
"VSS86":   PN = "199"  !CDS_PN = "199";
"VSS87":   PN = "202"  !CDS_PN = "202";
"VSS88":   PN = "204"  !CDS_PN = "204";
"VSS89":   PN = "206"  !CDS_PN = "206";
"VSS90":   PN = "208"  !CDS_PN = "208";
"VSS91":   PN = "210"  !CDS_PN = "210";
"VSS92":   PN = "212"  !CDS_PN = "212";
"VSS93":   PN = "214"  !CDS_PN = "214";
"VSS94":   PN = "216"  !CDS_PN = "216";
"VSS95":   PN = "219"  !CDS_PN = "219";
"VSS96":   PN = "222"  !CDS_PN = "222";
"VSS97":   PN = "224"  !CDS_PN = "224";
"VSS98":   PN = "226"  !CDS_PN = "226";
"VSS99":   PN = "228"  !CDS_PN = "228";
"VSS100":   PN = "230"  !CDS_PN = "230";
"VSS101":   PN = "233"  !CDS_PN = "233";
"VSS102":   PN = "235"  !CDS_PN = "235";
"VSS103":   PN = "237"  !CDS_PN = "237";
"VSS104":   PN = "240"  !CDS_PN = "240";
"VSS105":   PN = "242"  !CDS_PN = "242";
"VSS106":   PN = "244"  !CDS_PN = "244";
"VSS107":   PN = "246"  !CDS_PN = "246";
"VSS108":   PN = "248"  !CDS_PN = "248";
"VSS109":   PN = "251"  !CDS_PN = "251";
"VSS110":   PN = "253"  !CDS_PN = "253";
"VSS111":   PN = "255"  !CDS_PN = "255";
"VSS112":   PN = "257"  !CDS_PN = "257";
"VSS113":   PN = "259"  !CDS_PN = "259";
"VSS114":   PN = "262"  !CDS_PN = "262";
"VSS115":   PN = "264"  !CDS_PN = "264";
"VSS116":   PN = "266"  !CDS_PN = "266";
"VSS117":   PN = "268"  !CDS_PN = "268";
"VSS118":   PN = "270"  !CDS_PN = "270";
"VSS119":   PN = "273"  !CDS_PN = "273";
"VSS120":   PN = "275"  !CDS_PN = "275";
"VSS121":   PN = "277"  !CDS_PN = "277";
"VSS122":   PN = "279"  !CDS_PN = "279";
"VSS123":   PN = "281"  !CDS_PN = "281";
"VSS124":   PN = "284"  !CDS_PN = "284";
"VSS125":   PN = "286"  !CDS_PN = "286";
"VSS126":   PN = "288"  !CDS_PN = "288";
BODY = "SCONN288_ADR50017P130CC","I179": #LOCATION = "J3" !CDS_LOCATION = "J3" &SEC = "2" #&CDS_SEC = "2";
"DQS0_A_C":   PN = "12"  !CDS_PN = "12";
"DQS0_A_T":   PN = "11"  !CDS_PN = "11";
"DQS0_B_C":   PN = "105"  !CDS_PN = "105";
"DQS0_B_T":   PN = "104"  !CDS_PN = "104";
"DQS1_A_C":   PN = "23"  !CDS_PN = "23";
"DQS1_A_T":   PN = "22"  !CDS_PN = "22";
"DQS1_B_C":   PN = "116"  !CDS_PN = "116";
"DQS1_B_T":   PN = "115"  !CDS_PN = "115";
"DQS2_A_C":   PN = "34"  !CDS_PN = "34";
"DQS2_A_T":   PN = "33"  !CDS_PN = "33";
"DQS2_B_C":   PN = "127"  !CDS_PN = "127";
"DQS2_B_T":   PN = "126"  !CDS_PN = "126";
"DQS3_A_C":   PN = "45"  !CDS_PN = "45";
"DQS3_A_T":   PN = "44"  !CDS_PN = "44";
"DQS3_B_C":   PN = "138"  !CDS_PN = "138";
"DQS3_B_T":   PN = "137"  !CDS_PN = "137";
"DQS4_A_C":   PN = "56"  !CDS_PN = "56";
"DQS4_A_T":   PN = "55"  !CDS_PN = "55";
"DQS4_B_C":   PN = "238"  !CDS_PN = "238";
"DQS4_B_T":   PN = "239"  !CDS_PN = "239";
"DQS5_A_C||TDQS5_A_C||DQS5_A_T||TDQS5_A_T":   PN = "156"  !CDS_PN = "156";
"DQS5_A_T||TDQS5_A_T":   PN = "157"  !CDS_PN = "157";
"DQS5_B_C||TDQS5_B_C":   PN = "249"  !CDS_PN = "249";
"DQS5_B_T||TDQS5_B_T":   PN = "250"  !CDS_PN = "250";
"DQS6_A_C||TDQS6_A_C||DQS6_A_T||TDQS6_A_T":   PN = "167"  !CDS_PN = "167";
"DQS6_A_T||TDQS6_A_T":   PN = "168"  !CDS_PN = "168";
"DQS6_B_C||TDQS6_B_C":   PN = "260"  !CDS_PN = "260";
"DQS6_B_T||TDQS6_B_T":   PN = "261"  !CDS_PN = "261";
"DQS7_A_C||TDQS7_A_C":   PN = "178"  !CDS_PN = "178";
"DQS7_A_T||TDQS7_A_T":   PN = "179"  !CDS_PN = "179";
"DQS7_B_C||TDQS7_B_C":   PN = "271"  !CDS_PN = "271";
"DQS7_B_T||TDQS7_B_T":   PN = "272"  !CDS_PN = "272";
"DQS8_A_C||TDQS8_A_C":   PN = "189"  !CDS_PN = "189";
"DQS8_A_T||TDQS8_A_T":   PN = "190"  !CDS_PN = "190";
"DQS8_B_C||TDQS8_B_C":   PN = "282"  !CDS_PN = "282";
"DQS8_B_T||TDQS8_B_T":   PN = "283"  !CDS_PN = "283";
"DQS9_A_C||TDQS9_A_C":   PN = "200"  !CDS_PN = "200";
"DQS9_A_T||TDQS9_A_T":   PN = "201"  !CDS_PN = "201";
"DQS9_B_C||TDQS9_B_C":   PN = "94"  !CDS_PN = "94";
"DQS9_B_T||TDQS9_B_T||DBI4_B_N":   PN = "93"  !CDS_PN = "93";
BODY = "SCONN288_ADR50017P130CC","I180": #LOCATION = "J3" !CDS_LOCATION = "J3" &SEC = "1" #&CDS_SEC = "1";
"ALERT_N":   PN = "62"  !CDS_PN = "62";
"CA0_A":   PN = "66"  !CDS_PN = "66";
"CA0_B":   PN = "76"  !CDS_PN = "76";
"CA1_A":   PN = "211"  !CDS_PN = "211";
"CA1_B":   PN = "221"  !CDS_PN = "221";
"CA2_A":   PN = "68"  !CDS_PN = "68";
"CA2_B":   PN = "78"  !CDS_PN = "78";
"CA3_A":   PN = "213"  !CDS_PN = "213";
"CA3_B":   PN = "223"  !CDS_PN = "223";
"CA4_A":   PN = "70"  !CDS_PN = "70";
"CA4_B":   PN = "80"  !CDS_PN = "80";
"CA5_A":   PN = "215"  !CDS_PN = "215";
"CA5_B":   PN = "225"  !CDS_PN = "225";
"CA6_A":   PN = "72"  !CDS_PN = "72";
"CA6_B":   PN = "82"  !CDS_PN = "82";
"CB0_A":   PN = "51"  !CDS_PN = "51";
"CB0_B":   PN = "96"  !CDS_PN = "96";
"CB1_A":   PN = "53"  !CDS_PN = "53";
"CB1_B":   PN = "98"  !CDS_PN = "98";
"CB2_A":   PN = "196"  !CDS_PN = "196";
"CB2_B":   PN = "241"  !CDS_PN = "241";
"CB3_A":   PN = "198"  !CDS_PN = "198";
"CB3_B":   PN = "243"  !CDS_PN = "243";
"CB4_A":   PN = "58"  !CDS_PN = "58";
"CB4_B":   PN = "89"  !CDS_PN = "89";
"CB5_A":   PN = "60"  !CDS_PN = "60";
"CB5_B":   PN = "91"  !CDS_PN = "91";
"CB6_A":   PN = "203"  !CDS_PN = "203";
"CB6_B":   PN = "234"  !CDS_PN = "234";
"CB7_A":   PN = "205"  !CDS_PN = "205";
"CB7_B":   PN = "236"  !CDS_PN = "236";
"CK_C":   PN = "218"  !CDS_PN = "218";
"CK_T":   PN = "217"  !CDS_PN = "217";
"CS0_A_N":   PN = "64"  !CDS_PN = "64";
"CS0_B_N":   PN = "84"  !CDS_PN = "84";
"CS1_A_N":   PN = "209"  !CDS_PN = "209";
"CS1_B_N":   PN = "229"  !CDS_PN = "229";
"DQ0_A":   PN = "7"  !CDS_PN = "7";
"DQ0_B":   PN = "100"  !CDS_PN = "100";
"DQ1_A":   PN = "9"  !CDS_PN = "9";
"DQ1_B":   PN = "102"  !CDS_PN = "102";
"DQ2_A":   PN = "152"  !CDS_PN = "152";
"DQ2_B":   PN = "245"  !CDS_PN = "245";
"DQ3_A":   PN = "154"  !CDS_PN = "154";
"DQ3_B":   PN = "247"  !CDS_PN = "247";
"DQ4_A":   PN = "14"  !CDS_PN = "14";
"DQ4_B":   PN = "107"  !CDS_PN = "107";
"DQ5_A":   PN = "16"  !CDS_PN = "16";
"DQ5_B":   PN = "109"  !CDS_PN = "109";
"DQ6_A":   PN = "159"  !CDS_PN = "159";
"DQ6_B":   PN = "252"  !CDS_PN = "252";
"DQ7_A":   PN = "161"  !CDS_PN = "161";
"DQ7_B":   PN = "254"  !CDS_PN = "254";
"DQ8_A":   PN = "18"  !CDS_PN = "18";
"DQ8_B":   PN = "111"  !CDS_PN = "111";
"DQ9_A":   PN = "20"  !CDS_PN = "20";
"DQ9_B":   PN = "113"  !CDS_PN = "113";
"DQ10_A":   PN = "163"  !CDS_PN = "163";
"DQ10_B":   PN = "256"  !CDS_PN = "256";
"DQ11_A":   PN = "165"  !CDS_PN = "165";
"DQ11_B":   PN = "258"  !CDS_PN = "258";
"DQ12_A":   PN = "25"  !CDS_PN = "25";
"DQ12_B":   PN = "118"  !CDS_PN = "118";
"DQ13_A":   PN = "27"  !CDS_PN = "27";
"DQ13_B":   PN = "120"  !CDS_PN = "120";
"DQ14_A":   PN = "170"  !CDS_PN = "170";
"DQ14_B":   PN = "263"  !CDS_PN = "263";
"DQ15_A":   PN = "172"  !CDS_PN = "172";
"DQ15_B":   PN = "265"  !CDS_PN = "265";
"DQ16_A":   PN = "29"  !CDS_PN = "29";
"DQ16_B":   PN = "122"  !CDS_PN = "122";
"DQ17_A":   PN = "31"  !CDS_PN = "31";
"DQ17_B":   PN = "124"  !CDS_PN = "124";
"DQ18_A":   PN = "174"  !CDS_PN = "174";
"DQ18_B":   PN = "267"  !CDS_PN = "267";
"DQ19_A":   PN = "176"  !CDS_PN = "176";
"DQ19_B":   PN = "269"  !CDS_PN = "269";
"DQ20_A":   PN = "36"  !CDS_PN = "36";
"DQ20_B":   PN = "129"  !CDS_PN = "129";
"DQ21_A":   PN = "38"  !CDS_PN = "38";
"DQ21_B":   PN = "131"  !CDS_PN = "131";
"DQ22_A":   PN = "181"  !CDS_PN = "181";
"DQ22_B":   PN = "274"  !CDS_PN = "274";
"DQ23_A":   PN = "183"  !CDS_PN = "183";
"DQ23_B":   PN = "276"  !CDS_PN = "276";
"DQ24_A":   PN = "40"  !CDS_PN = "40";
"DQ24_B":   PN = "133"  !CDS_PN = "133";
"DQ25_A":   PN = "42"  !CDS_PN = "42";
"DQ25_B":   PN = "135"  !CDS_PN = "135";
"DQ26_A":   PN = "185"  !CDS_PN = "185";
"DQ26_B":   PN = "278"  !CDS_PN = "278";
"DQ27_A":   PN = "187"  !CDS_PN = "187";
"DQ27_B":   PN = "280"  !CDS_PN = "280";
"DQ28_A":   PN = "47"  !CDS_PN = "47";
"DQ28_B":   PN = "140"  !CDS_PN = "140";
"DQ29_A":   PN = "49"  !CDS_PN = "49";
"DQ29_B":   PN = "142"  !CDS_PN = "142";
"DQ30_A":   PN = "192"  !CDS_PN = "192";
"DQ30_B":   PN = "285"  !CDS_PN = "285";
"DQ31_A":   PN = "194"  !CDS_PN = "194";
"DQ31_B":   PN = "287"  !CDS_PN = "287";
"HSA":   PN = "148"  !CDS_PN = "148";
"HSCL":   PN = "4"  !CDS_PN = "4";
"HSDA":   PN = "5"  !CDS_PN = "5";
"LBD||RSP_A_N":   PN = "86"  !CDS_PN = "86";
"LBS||RSP_B_N":   PN = "87"  !CDS_PN = "87";
"PAR_A":   PN = "74"  !CDS_PN = "74";
"PAR_B":   PN = "227"  !CDS_PN = "227";
"PWR_GOOD||FAIL_N":   PN = "147"  !CDS_PN = "147";
"RESET_N":   PN = "207"  !CDS_PN = "207";
"RFU0":   PN = "2"  !CDS_PN = "2";
"RFU1":   PN = "144"  !CDS_PN = "144";
"RFU2":   PN = "149"  !CDS_PN = "149";
"RFU3":   PN = "150"  !CDS_PN = "150";
"RFU4":   PN = "220"  !CDS_PN = "220";
"RFU5":   PN = "231"  !CDS_PN = "231";
"RFU6":   PN = "232"  !CDS_PN = "232";
"VIN_MGMT":   PN = "3"  !CDS_PN = "3";
BODY = "Q_RES","I182": LOCATION = "R3877" #&CDS_LOCATION = "R3877" &SEC = "1" #&CDS_SEC = "1";
"A":   PN = "1"  !CDS_PN = "1";
"B":   PN = "2"  !CDS_PN = "2";
DRAWING = "@s9s_mb_2u_lib.s9s_mb_2u(sch_1):page85";
BODY = "Q_RES","I1": LOCATION = "R29" #&CDS_LOCATION = "R29" &SEC = "1" #&CDS_SEC = "1";
"A":   PN = "1"  !CDS_PN = "1";
"B":   PN = "2"  !CDS_PN = "2";
BODY = "SCONN288_ADR50017P087CC","I23": LOCATION = "J4" #&CDS_LOCATION = "J4" &SEC = "1" #&CDS_SEC = "1";
"ALERT_N":   PN = "62"  !CDS_PN = "62";
"CA0_A":   PN = "66"  !CDS_PN = "66";
"CA0_B":   PN = "76"  !CDS_PN = "76";
"CA1_A":   PN = "211"  !CDS_PN = "211";
"CA1_B":   PN = "221"  !CDS_PN = "221";
"CA2_A":   PN = "68"  !CDS_PN = "68";
"CA2_B":   PN = "78"  !CDS_PN = "78";
"CA3_A":   PN = "213"  !CDS_PN = "213";
"CA3_B":   PN = "223"  !CDS_PN = "223";
"CA4_A":   PN = "70"  !CDS_PN = "70";
"CA4_B":   PN = "80"  !CDS_PN = "80";
"CA5_A":   PN = "215"  !CDS_PN = "215";
"CA5_B":   PN = "225"  !CDS_PN = "225";
"CA6_A":   PN = "72"  !CDS_PN = "72";
"CA6_B":   PN = "82"  !CDS_PN = "82";
"CB0_A":   PN = "51"  !CDS_PN = "51";
"CB0_B":   PN = "96"  !CDS_PN = "96";
"CB1_A":   PN = "53"  !CDS_PN = "53";
"CB1_B":   PN = "98"  !CDS_PN = "98";
"CB2_A":   PN = "196"  !CDS_PN = "196";
"CB2_B":   PN = "241"  !CDS_PN = "241";
"CB3_A":   PN = "198"  !CDS_PN = "198";
"CB3_B":   PN = "243"  !CDS_PN = "243";
"CB4_A":   PN = "58"  !CDS_PN = "58";
"CB4_B":   PN = "89"  !CDS_PN = "89";
"CB5_A":   PN = "60"  !CDS_PN = "60";
"CB5_B":   PN = "91"  !CDS_PN = "91";
"CB6_A":   PN = "203"  !CDS_PN = "203";
"CB6_B":   PN = "234"  !CDS_PN = "234";
"CB7_A":   PN = "205"  !CDS_PN = "205";
"CB7_B":   PN = "236"  !CDS_PN = "236";
"CK_C":   PN = "218"  !CDS_PN = "218";
"CK_T":   PN = "217"  !CDS_PN = "217";
"CS0_A_N":   PN = "64"  !CDS_PN = "64";
"CS0_B_N":   PN = "84"  !CDS_PN = "84";
"CS1_A_N":   PN = "209"  !CDS_PN = "209";
"CS1_B_N":   PN = "229"  !CDS_PN = "229";
"DQ0_A":   PN = "7"  !CDS_PN = "7";
"DQ0_B":   PN = "100"  !CDS_PN = "100";
"DQ1_A":   PN = "9"  !CDS_PN = "9";
"DQ1_B":   PN = "102"  !CDS_PN = "102";
"DQ2_A":   PN = "152"  !CDS_PN = "152";
"DQ2_B":   PN = "245"  !CDS_PN = "245";
"DQ3_A":   PN = "154"  !CDS_PN = "154";
"DQ3_B":   PN = "247"  !CDS_PN = "247";
"DQ4_A":   PN = "14"  !CDS_PN = "14";
"DQ4_B":   PN = "107"  !CDS_PN = "107";
"DQ5_A":   PN = "16"  !CDS_PN = "16";
"DQ5_B":   PN = "109"  !CDS_PN = "109";
"DQ6_A":   PN = "159"  !CDS_PN = "159";
"DQ6_B":   PN = "252"  !CDS_PN = "252";
"DQ7_A":   PN = "161"  !CDS_PN = "161";
"DQ7_B":   PN = "254"  !CDS_PN = "254";
"DQ8_A":   PN = "18"  !CDS_PN = "18";
"DQ8_B":   PN = "111"  !CDS_PN = "111";
"DQ9_A":   PN = "20"  !CDS_PN = "20";
"DQ9_B":   PN = "113"  !CDS_PN = "113";
"DQ10_A":   PN = "163"  !CDS_PN = "163";
"DQ10_B":   PN = "256"  !CDS_PN = "256";
"DQ11_A":   PN = "165"  !CDS_PN = "165";
"DQ11_B":   PN = "258"  !CDS_PN = "258";
"DQ12_A":   PN = "25"  !CDS_PN = "25";
"DQ12_B":   PN = "118"  !CDS_PN = "118";
"DQ13_A":   PN = "27"  !CDS_PN = "27";
"DQ13_B":   PN = "120"  !CDS_PN = "120";
"DQ14_A":   PN = "170"  !CDS_PN = "170";
"DQ14_B":   PN = "263"  !CDS_PN = "263";
"DQ15_A":   PN = "172"  !CDS_PN = "172";
"DQ15_B":   PN = "265"  !CDS_PN = "265";
"DQ16_A":   PN = "29"  !CDS_PN = "29";
"DQ16_B":   PN = "122"  !CDS_PN = "122";
"DQ17_A":   PN = "31"  !CDS_PN = "31";
"DQ17_B":   PN = "124"  !CDS_PN = "124";
"DQ18_A":   PN = "174"  !CDS_PN = "174";
"DQ18_B":   PN = "267"  !CDS_PN = "267";
"DQ19_A":   PN = "176"  !CDS_PN = "176";
"DQ19_B":   PN = "269"  !CDS_PN = "269";
"DQ20_A":   PN = "36"  !CDS_PN = "36";
"DQ20_B":   PN = "129"  !CDS_PN = "129";
"DQ21_A":   PN = "38"  !CDS_PN = "38";
"DQ21_B":   PN = "131"  !CDS_PN = "131";
"DQ22_A":   PN = "181"  !CDS_PN = "181";
"DQ22_B":   PN = "274"  !CDS_PN = "274";
"DQ23_A":   PN = "183"  !CDS_PN = "183";
"DQ23_B":   PN = "276"  !CDS_PN = "276";
"DQ24_A":   PN = "40"  !CDS_PN = "40";
"DQ24_B":   PN = "133"  !CDS_PN = "133";
"DQ25_A":   PN = "42"  !CDS_PN = "42";
"DQ25_B":   PN = "135"  !CDS_PN = "135";
"DQ26_A":   PN = "185"  !CDS_PN = "185";
"DQ26_B":   PN = "278"  !CDS_PN = "278";
"DQ27_A":   PN = "187"  !CDS_PN = "187";
"DQ27_B":   PN = "280"  !CDS_PN = "280";
"DQ28_A":   PN = "47"  !CDS_PN = "47";
"DQ28_B":   PN = "140"  !CDS_PN = "140";
"DQ29_A":   PN = "49"  !CDS_PN = "49";
"DQ29_B":   PN = "142"  !CDS_PN = "142";
"DQ30_A":   PN = "192"  !CDS_PN = "192";
"DQ30_B":   PN = "285"  !CDS_PN = "285";
"DQ31_A":   PN = "194"  !CDS_PN = "194";
"DQ31_B":   PN = "287"  !CDS_PN = "287";
"HSA":   PN = "148"  !CDS_PN = "148";
"HSCL":   PN = "4"  !CDS_PN = "4";
"HSDA":   PN = "5"  !CDS_PN = "5";
"LBD||RSP_A_N":   PN = "86"  !CDS_PN = "86";
"LBS||RSP_B_N":   PN = "87"  !CDS_PN = "87";
"PAR_A":   PN = "74"  !CDS_PN = "74";
"PAR_B":   PN = "227"  !CDS_PN = "227";
"PWR_GOOD||FAIL_N":   PN = "147"  !CDS_PN = "147";
"RESET_N":   PN = "207"  !CDS_PN = "207";
"RFU0":   PN = "2"  !CDS_PN = "2";
"RFU1":   PN = "144"  !CDS_PN = "144";
"RFU2":   PN = "149"  !CDS_PN = "149";
"RFU3":   PN = "150"  !CDS_PN = "150";
"RFU4":   PN = "220"  !CDS_PN = "220";
"RFU5":   PN = "231"  !CDS_PN = "231";
"RFU6":   PN = "232"  !CDS_PN = "232";
"VIN_MGMT":   PN = "3"  !CDS_PN = "3";
BODY = "Q_CAP","I121": LOCATION = "C11" #&CDS_LOCATION = "C11" &SEC = "1" #&CDS_SEC = "1";
"A":   PN = "1"  !CDS_PN = "1";
"B":   PN = "2"  !CDS_PN = "2";
BODY = "Q_CAP","I125": LOCATION = "C12" #&CDS_LOCATION = "C12" &SEC = "1" #&CDS_SEC = "1";
"A":   PN = "1"  !CDS_PN = "1";
"B":   PN = "2"  !CDS_PN = "2";
BODY = "Q_CAP","I127": LOCATION = "C13" #&CDS_LOCATION = "C13" &SEC = "1" #&CDS_SEC = "1";
"A":   PN = "1"  !CDS_PN = "1";
"B":   PN = "2"  !CDS_PN = "2";
BODY = "SCONN288_ADR50017P087CC","I174": LOCATION = "J4" #&CDS_LOCATION = "J4" &SEC = "3" #&CDS_SEC = "3";
"G1":   PN = "G1"  !CDS_PN = "G1";
"G2":   PN = "G2"  !CDS_PN = "G2";
"G3":   PN = "G3"  !CDS_PN = "G3";
"VIN_BULK0":   PN = "1"  !CDS_PN = "1";
"VIN_BULK1":   PN = "145"  !CDS_PN = "145";
"VIN_BULK2":   PN = "146"  !CDS_PN = "146";
"VSS0":   PN = "6"  !CDS_PN = "6";
"VSS1":   PN = "8"  !CDS_PN = "8";
"VSS2":   PN = "10"  !CDS_PN = "10";
"VSS3":   PN = "13"  !CDS_PN = "13";
"VSS4":   PN = "15"  !CDS_PN = "15";
"VSS5":   PN = "17"  !CDS_PN = "17";
"VSS6":   PN = "19"  !CDS_PN = "19";
"VSS7":   PN = "21"  !CDS_PN = "21";
"VSS8":   PN = "24"  !CDS_PN = "24";
"VSS9":   PN = "26"  !CDS_PN = "26";
"VSS10":   PN = "28"  !CDS_PN = "28";
"VSS11":   PN = "30"  !CDS_PN = "30";
"VSS12":   PN = "32"  !CDS_PN = "32";
"VSS13":   PN = "35"  !CDS_PN = "35";
"VSS14":   PN = "37"  !CDS_PN = "37";
"VSS15":   PN = "39"  !CDS_PN = "39";
"VSS16":   PN = "41"  !CDS_PN = "41";
"VSS17":   PN = "43"  !CDS_PN = "43";
"VSS18":   PN = "46"  !CDS_PN = "46";
"VSS19":   PN = "48"  !CDS_PN = "48";
"VSS20":   PN = "50"  !CDS_PN = "50";
"VSS21":   PN = "52"  !CDS_PN = "52";
"VSS22":   PN = "54"  !CDS_PN = "54";
"VSS23":   PN = "57"  !CDS_PN = "57";
"VSS24":   PN = "59"  !CDS_PN = "59";
"VSS25":   PN = "61"  !CDS_PN = "61";
"VSS26":   PN = "63"  !CDS_PN = "63";
"VSS27":   PN = "65"  !CDS_PN = "65";
"VSS28":   PN = "67"  !CDS_PN = "67";
"VSS29":   PN = "69"  !CDS_PN = "69";
"VSS30":   PN = "71"  !CDS_PN = "71";
"VSS31":   PN = "73"  !CDS_PN = "73";
"VSS32":   PN = "75"  !CDS_PN = "75";
"VSS33":   PN = "77"  !CDS_PN = "77";
"VSS34":   PN = "79"  !CDS_PN = "79";
"VSS35":   PN = "81"  !CDS_PN = "81";
"VSS36":   PN = "83"  !CDS_PN = "83";
"VSS37":   PN = "85"  !CDS_PN = "85";
"VSS38":   PN = "88"  !CDS_PN = "88";
"VSS39":   PN = "90"  !CDS_PN = "90";
"VSS40":   PN = "92"  !CDS_PN = "92";
"VSS41":   PN = "95"  !CDS_PN = "95";
"VSS42":   PN = "97"  !CDS_PN = "97";
"VSS43":   PN = "99"  !CDS_PN = "99";
"VSS44":   PN = "101"  !CDS_PN = "101";
"VSS45":   PN = "103"  !CDS_PN = "103";
"VSS46":   PN = "106"  !CDS_PN = "106";
"VSS47":   PN = "108"  !CDS_PN = "108";
"VSS48":   PN = "110"  !CDS_PN = "110";
"VSS49":   PN = "112"  !CDS_PN = "112";
"VSS50":   PN = "114"  !CDS_PN = "114";
"VSS51":   PN = "117"  !CDS_PN = "117";
"VSS52":   PN = "119"  !CDS_PN = "119";
"VSS53":   PN = "121"  !CDS_PN = "121";
"VSS54":   PN = "123"  !CDS_PN = "123";
"VSS55":   PN = "125"  !CDS_PN = "125";
"VSS56":   PN = "128"  !CDS_PN = "128";
"VSS57":   PN = "130"  !CDS_PN = "130";
"VSS58":   PN = "132"  !CDS_PN = "132";
"VSS59":   PN = "134"  !CDS_PN = "134";
"VSS60":   PN = "136"  !CDS_PN = "136";
"VSS61":   PN = "139"  !CDS_PN = "139";
"VSS62":   PN = "141"  !CDS_PN = "141";
"VSS63":   PN = "143"  !CDS_PN = "143";
"VSS64":   PN = "151"  !CDS_PN = "151";
"VSS65":   PN = "153"  !CDS_PN = "153";
"VSS66":   PN = "155"  !CDS_PN = "155";
"VSS67":   PN = "158"  !CDS_PN = "158";
"VSS68":   PN = "160"  !CDS_PN = "160";
"VSS69":   PN = "162"  !CDS_PN = "162";
"VSS70":   PN = "164"  !CDS_PN = "164";
"VSS71":   PN = "166"  !CDS_PN = "166";
"VSS72":   PN = "169"  !CDS_PN = "169";
"VSS73":   PN = "171"  !CDS_PN = "171";
"VSS74":   PN = "173"  !CDS_PN = "173";
"VSS75":   PN = "175"  !CDS_PN = "175";
"VSS76":   PN = "177"  !CDS_PN = "177";
"VSS77":   PN = "180"  !CDS_PN = "180";
"VSS78":   PN = "182"  !CDS_PN = "182";
"VSS79":   PN = "184"  !CDS_PN = "184";
"VSS80":   PN = "186"  !CDS_PN = "186";
"VSS81":   PN = "188"  !CDS_PN = "188";
"VSS82":   PN = "191"  !CDS_PN = "191";
"VSS83":   PN = "193"  !CDS_PN = "193";
"VSS84":   PN = "195"  !CDS_PN = "195";
"VSS85":   PN = "197"  !CDS_PN = "197";
"VSS86":   PN = "199"  !CDS_PN = "199";
"VSS87":   PN = "202"  !CDS_PN = "202";
"VSS88":   PN = "204"  !CDS_PN = "204";
"VSS89":   PN = "206"  !CDS_PN = "206";
"VSS90":   PN = "208"  !CDS_PN = "208";
"VSS91":   PN = "210"  !CDS_PN = "210";
"VSS92":   PN = "212"  !CDS_PN = "212";
"VSS93":   PN = "214"  !CDS_PN = "214";
"VSS94":   PN = "216"  !CDS_PN = "216";
"VSS95":   PN = "219"  !CDS_PN = "219";
"VSS96":   PN = "222"  !CDS_PN = "222";
"VSS97":   PN = "224"  !CDS_PN = "224";
"VSS98":   PN = "226"  !CDS_PN = "226";
"VSS99":   PN = "228"  !CDS_PN = "228";
"VSS100":   PN = "230"  !CDS_PN = "230";
"VSS101":   PN = "233"  !CDS_PN = "233";
"VSS102":   PN = "235"  !CDS_PN = "235";
"VSS103":   PN = "237"  !CDS_PN = "237";
"VSS104":   PN = "240"  !CDS_PN = "240";
"VSS105":   PN = "242"  !CDS_PN = "242";
"VSS106":   PN = "244"  !CDS_PN = "244";
"VSS107":   PN = "246"  !CDS_PN = "246";
"VSS108":   PN = "248"  !CDS_PN = "248";
"VSS109":   PN = "251"  !CDS_PN = "251";
"VSS110":   PN = "253"  !CDS_PN = "253";
"VSS111":   PN = "255"  !CDS_PN = "255";
"VSS112":   PN = "257"  !CDS_PN = "257";
"VSS113":   PN = "259"  !CDS_PN = "259";
"VSS114":   PN = "262"  !CDS_PN = "262";
"VSS115":   PN = "264"  !CDS_PN = "264";
"VSS116":   PN = "266"  !CDS_PN = "266";
"VSS117":   PN = "268"  !CDS_PN = "268";
"VSS118":   PN = "270"  !CDS_PN = "270";
"VSS119":   PN = "273"  !CDS_PN = "273";
"VSS120":   PN = "275"  !CDS_PN = "275";
"VSS121":   PN = "277"  !CDS_PN = "277";
"VSS122":   PN = "279"  !CDS_PN = "279";
"VSS123":   PN = "281"  !CDS_PN = "281";
"VSS124":   PN = "284"  !CDS_PN = "284";
"VSS125":   PN = "286"  !CDS_PN = "286";
"VSS126":   PN = "288"  !CDS_PN = "288";
BODY = "SCONN288_ADR50017P087CC","I178": #LOCATION = "J4" !CDS_LOCATION = "J4" &SEC = "2" #&CDS_SEC = "2";
"DQS0_A_C":   PN = "12"  !CDS_PN = "12";
"DQS0_A_T":   PN = "11"  !CDS_PN = "11";
"DQS0_B_C":   PN = "105"  !CDS_PN = "105";
"DQS0_B_T":   PN = "104"  !CDS_PN = "104";
"DQS1_A_C":   PN = "23"  !CDS_PN = "23";
"DQS1_A_T":   PN = "22"  !CDS_PN = "22";
"DQS1_B_C":   PN = "116"  !CDS_PN = "116";
"DQS1_B_T":   PN = "115"  !CDS_PN = "115";
"DQS2_A_C":   PN = "34"  !CDS_PN = "34";
"DQS2_A_T":   PN = "33"  !CDS_PN = "33";
"DQS2_B_C":   PN = "127"  !CDS_PN = "127";
"DQS2_B_T":   PN = "126"  !CDS_PN = "126";
"DQS3_A_C":   PN = "45"  !CDS_PN = "45";
"DQS3_A_T":   PN = "44"  !CDS_PN = "44";
"DQS3_B_C":   PN = "138"  !CDS_PN = "138";
"DQS3_B_T":   PN = "137"  !CDS_PN = "137";
"DQS4_A_C":   PN = "56"  !CDS_PN = "56";
"DQS4_A_T":   PN = "55"  !CDS_PN = "55";
"DQS4_B_C":   PN = "238"  !CDS_PN = "238";
"DQS4_B_T":   PN = "239"  !CDS_PN = "239";
"DQS5_A_C||TDQS5_A_C||DQS5_A_T||TDQS5_A_T":   PN = "156"  !CDS_PN = "156";
"DQS5_A_T||TDQS5_A_T":   PN = "157"  !CDS_PN = "157";
"DQS5_B_C||TDQS5_B_C":   PN = "249"  !CDS_PN = "249";
"DQS5_B_T||TDQS5_B_T":   PN = "250"  !CDS_PN = "250";
"DQS6_A_C||TDQS6_A_C||DQS6_A_T||TDQS6_A_T":   PN = "167"  !CDS_PN = "167";
"DQS6_A_T||TDQS6_A_T":   PN = "168"  !CDS_PN = "168";
"DQS6_B_C||TDQS6_B_C":   PN = "260"  !CDS_PN = "260";
"DQS6_B_T||TDQS6_B_T":   PN = "261"  !CDS_PN = "261";
"DQS7_A_C||TDQS7_A_C":   PN = "178"  !CDS_PN = "178";
"DQS7_A_T||TDQS7_A_T":   PN = "179"  !CDS_PN = "179";
"DQS7_B_C||TDQS7_B_C":   PN = "271"  !CDS_PN = "271";
"DQS7_B_T||TDQS7_B_T":   PN = "272"  !CDS_PN = "272";
"DQS8_A_C||TDQS8_A_C":   PN = "189"  !CDS_PN = "189";
"DQS8_A_T||TDQS8_A_T":   PN = "190"  !CDS_PN = "190";
"DQS8_B_C||TDQS8_B_C":   PN = "282"  !CDS_PN = "282";
"DQS8_B_T||TDQS8_B_T":   PN = "283"  !CDS_PN = "283";
"DQS9_A_C||TDQS9_A_C":   PN = "200"  !CDS_PN = "200";
"DQS9_A_T||TDQS9_A_T":   PN = "201"  !CDS_PN = "201";
"DQS9_B_C||TDQS9_B_C":   PN = "94"  !CDS_PN = "94";
"DQS9_B_T||TDQS9_B_T||DBI4_B_N":   PN = "93"  !CDS_PN = "93";
BODY = "Q_RES","I180": LOCATION = "R3878" #&CDS_LOCATION = "R3878" &SEC = "1" #&CDS_SEC = "1";
"A":   PN = "1"  !CDS_PN = "1";
"B":   PN = "2"  !CDS_PN = "2";
DRAWING = "@s9s_mb_2u_lib.s9s_mb_2u(sch_1):page86";
BODY = "Q_RES","I3": LOCATION = "R30" #&CDS_LOCATION = "R30" &SEC = "1" #&CDS_SEC = "1";
"A":   PN = "1"  !CDS_PN = "1";
"B":   PN = "2"  !CDS_PN = "2";
BODY = "SCONN288_ADR50017P130CC","I24": LOCATION = "J5" #&CDS_LOCATION = "J5" &SEC = "1" #&CDS_SEC = "1";
"ALERT_N":   PN = "62"  !CDS_PN = "62";
"CA0_A":   PN = "66"  !CDS_PN = "66";
"CA0_B":   PN = "76"  !CDS_PN = "76";
"CA1_A":   PN = "211"  !CDS_PN = "211";
"CA1_B":   PN = "221"  !CDS_PN = "221";
"CA2_A":   PN = "68"  !CDS_PN = "68";
"CA2_B":   PN = "78"  !CDS_PN = "78";
"CA3_A":   PN = "213"  !CDS_PN = "213";
"CA3_B":   PN = "223"  !CDS_PN = "223";
"CA4_A":   PN = "70"  !CDS_PN = "70";
"CA4_B":   PN = "80"  !CDS_PN = "80";
"CA5_A":   PN = "215"  !CDS_PN = "215";
"CA5_B":   PN = "225"  !CDS_PN = "225";
"CA6_A":   PN = "72"  !CDS_PN = "72";
"CA6_B":   PN = "82"  !CDS_PN = "82";
"CB0_A":   PN = "51"  !CDS_PN = "51";
"CB0_B":   PN = "96"  !CDS_PN = "96";
"CB1_A":   PN = "53"  !CDS_PN = "53";
"CB1_B":   PN = "98"  !CDS_PN = "98";
"CB2_A":   PN = "196"  !CDS_PN = "196";
"CB2_B":   PN = "241"  !CDS_PN = "241";
"CB3_A":   PN = "198"  !CDS_PN = "198";
"CB3_B":   PN = "243"  !CDS_PN = "243";
"CB4_A":   PN = "58"  !CDS_PN = "58";
"CB4_B":   PN = "89"  !CDS_PN = "89";
"CB5_A":   PN = "60"  !CDS_PN = "60";
"CB5_B":   PN = "91"  !CDS_PN = "91";
"CB6_A":   PN = "203"  !CDS_PN = "203";
"CB6_B":   PN = "234"  !CDS_PN = "234";
"CB7_A":   PN = "205"  !CDS_PN = "205";
"CB7_B":   PN = "236"  !CDS_PN = "236";
"CK_C":   PN = "218"  !CDS_PN = "218";
"CK_T":   PN = "217"  !CDS_PN = "217";
"CS0_A_N":   PN = "64"  !CDS_PN = "64";
"CS0_B_N":   PN = "84"  !CDS_PN = "84";
"CS1_A_N":   PN = "209"  !CDS_PN = "209";
"CS1_B_N":   PN = "229"  !CDS_PN = "229";
"DQ0_A":   PN = "7"  !CDS_PN = "7";
"DQ0_B":   PN = "100"  !CDS_PN = "100";
"DQ1_A":   PN = "9"  !CDS_PN = "9";
"DQ1_B":   PN = "102"  !CDS_PN = "102";
"DQ2_A":   PN = "152"  !CDS_PN = "152";
"DQ2_B":   PN = "245"  !CDS_PN = "245";
"DQ3_A":   PN = "154"  !CDS_PN = "154";
"DQ3_B":   PN = "247"  !CDS_PN = "247";
"DQ4_A":   PN = "14"  !CDS_PN = "14";
"DQ4_B":   PN = "107"  !CDS_PN = "107";
"DQ5_A":   PN = "16"  !CDS_PN = "16";
"DQ5_B":   PN = "109"  !CDS_PN = "109";
"DQ6_A":   PN = "159"  !CDS_PN = "159";
"DQ6_B":   PN = "252"  !CDS_PN = "252";
"DQ7_A":   PN = "161"  !CDS_PN = "161";
"DQ7_B":   PN = "254"  !CDS_PN = "254";
"DQ8_A":   PN = "18"  !CDS_PN = "18";
"DQ8_B":   PN = "111"  !CDS_PN = "111";
"DQ9_A":   PN = "20"  !CDS_PN = "20";
"DQ9_B":   PN = "113"  !CDS_PN = "113";
"DQ10_A":   PN = "163"  !CDS_PN = "163";
"DQ10_B":   PN = "256"  !CDS_PN = "256";
"DQ11_A":   PN = "165"  !CDS_PN = "165";
"DQ11_B":   PN = "258"  !CDS_PN = "258";
"DQ12_A":   PN = "25"  !CDS_PN = "25";
"DQ12_B":   PN = "118"  !CDS_PN = "118";
"DQ13_A":   PN = "27"  !CDS_PN = "27";
"DQ13_B":   PN = "120"  !CDS_PN = "120";
"DQ14_A":   PN = "170"  !CDS_PN = "170";
"DQ14_B":   PN = "263"  !CDS_PN = "263";
"DQ15_A":   PN = "172"  !CDS_PN = "172";
"DQ15_B":   PN = "265"  !CDS_PN = "265";
"DQ16_A":   PN = "29"  !CDS_PN = "29";
"DQ16_B":   PN = "122"  !CDS_PN = "122";
"DQ17_A":   PN = "31"  !CDS_PN = "31";
"DQ17_B":   PN = "124"  !CDS_PN = "124";
"DQ18_A":   PN = "174"  !CDS_PN = "174";
"DQ18_B":   PN = "267"  !CDS_PN = "267";
"DQ19_A":   PN = "176"  !CDS_PN = "176";
"DQ19_B":   PN = "269"  !CDS_PN = "269";
"DQ20_A":   PN = "36"  !CDS_PN = "36";
"DQ20_B":   PN = "129"  !CDS_PN = "129";
"DQ21_A":   PN = "38"  !CDS_PN = "38";
"DQ21_B":   PN = "131"  !CDS_PN = "131";
"DQ22_A":   PN = "181"  !CDS_PN = "181";
"DQ22_B":   PN = "274"  !CDS_PN = "274";
"DQ23_A":   PN = "183"  !CDS_PN = "183";
"DQ23_B":   PN = "276"  !CDS_PN = "276";
"DQ24_A":   PN = "40"  !CDS_PN = "40";
"DQ24_B":   PN = "133"  !CDS_PN = "133";
"DQ25_A":   PN = "42"  !CDS_PN = "42";
"DQ25_B":   PN = "135"  !CDS_PN = "135";
"DQ26_A":   PN = "185"  !CDS_PN = "185";
"DQ26_B":   PN = "278"  !CDS_PN = "278";
"DQ27_A":   PN = "187"  !CDS_PN = "187";
"DQ27_B":   PN = "280"  !CDS_PN = "280";
"DQ28_A":   PN = "47"  !CDS_PN = "47";
"DQ28_B":   PN = "140"  !CDS_PN = "140";
"DQ29_A":   PN = "49"  !CDS_PN = "49";
"DQ29_B":   PN = "142"  !CDS_PN = "142";
"DQ30_A":   PN = "192"  !CDS_PN = "192";
"DQ30_B":   PN = "285"  !CDS_PN = "285";
"DQ31_A":   PN = "194"  !CDS_PN = "194";
"DQ31_B":   PN = "287"  !CDS_PN = "287";
"HSA":   PN = "148"  !CDS_PN = "148";
"HSCL":   PN = "4"  !CDS_PN = "4";
"HSDA":   PN = "5"  !CDS_PN = "5";
"LBD||RSP_A_N":   PN = "86"  !CDS_PN = "86";
"LBS||RSP_B_N":   PN = "87"  !CDS_PN = "87";
"PAR_A":   PN = "74"  !CDS_PN = "74";
"PAR_B":   PN = "227"  !CDS_PN = "227";
"PWR_GOOD||FAIL_N":   PN = "147"  !CDS_PN = "147";
"RESET_N":   PN = "207"  !CDS_PN = "207";
"RFU0":   PN = "2"  !CDS_PN = "2";
"RFU1":   PN = "144"  !CDS_PN = "144";
"RFU2":   PN = "149"  !CDS_PN = "149";
"RFU3":   PN = "150"  !CDS_PN = "150";
"RFU4":   PN = "220"  !CDS_PN = "220";
"RFU5":   PN = "231"  !CDS_PN = "231";
"RFU6":   PN = "232"  !CDS_PN = "232";
"VIN_MGMT":   PN = "3"  !CDS_PN = "3";
BODY = "Q_CAP","I120": LOCATION = "C14" #&CDS_LOCATION = "C14" &SEC = "1" #&CDS_SEC = "1";
"A":   PN = "1"  !CDS_PN = "1";
"B":   PN = "2"  !CDS_PN = "2";
BODY = "Q_CAP","I121": LOCATION = "C15" #&CDS_LOCATION = "C15" &SEC = "1" #&CDS_SEC = "1";
"A":   PN = "1"  !CDS_PN = "1";
"B":   PN = "2"  !CDS_PN = "2";
BODY = "Q_CAP","I123": LOCATION = "C16" #&CDS_LOCATION = "C16" &SEC = "1" #&CDS_SEC = "1";
"A":   PN = "1"  !CDS_PN = "1";
"B":   PN = "2"  !CDS_PN = "2";
BODY = "SCONN288_ADR50017P130CC","I174": LOCATION = "J5" #&CDS_LOCATION = "J5" &SEC = "3" #&CDS_SEC = "3";
"G1":   PN = "G1"  !CDS_PN = "G1";
"G2":   PN = "G2"  !CDS_PN = "G2";
"G3":   PN = "G3"  !CDS_PN = "G3";
"VIN_BULK0":   PN = "1"  !CDS_PN = "1";
"VIN_BULK1":   PN = "145"  !CDS_PN = "145";
"VIN_BULK2":   PN = "146"  !CDS_PN = "146";
"VSS0":   PN = "6"  !CDS_PN = "6";
"VSS1":   PN = "8"  !CDS_PN = "8";
"VSS2":   PN = "10"  !CDS_PN = "10";
"VSS3":   PN = "13"  !CDS_PN = "13";
"VSS4":   PN = "15"  !CDS_PN = "15";
"VSS5":   PN = "17"  !CDS_PN = "17";
"VSS6":   PN = "19"  !CDS_PN = "19";
"VSS7":   PN = "21"  !CDS_PN = "21";
"VSS8":   PN = "24"  !CDS_PN = "24";
"VSS9":   PN = "26"  !CDS_PN = "26";
"VSS10":   PN = "28"  !CDS_PN = "28";
"VSS11":   PN = "30"  !CDS_PN = "30";
"VSS12":   PN = "32"  !CDS_PN = "32";
"VSS13":   PN = "35"  !CDS_PN = "35";
"VSS14":   PN = "37"  !CDS_PN = "37";
"VSS15":   PN = "39"  !CDS_PN = "39";
"VSS16":   PN = "41"  !CDS_PN = "41";
"VSS17":   PN = "43"  !CDS_PN = "43";
"VSS18":   PN = "46"  !CDS_PN = "46";
"VSS19":   PN = "48"  !CDS_PN = "48";
"VSS20":   PN = "50"  !CDS_PN = "50";
"VSS21":   PN = "52"  !CDS_PN = "52";
"VSS22":   PN = "54"  !CDS_PN = "54";
"VSS23":   PN = "57"  !CDS_PN = "57";
"VSS24":   PN = "59"  !CDS_PN = "59";
"VSS25":   PN = "61"  !CDS_PN = "61";
"VSS26":   PN = "63"  !CDS_PN = "63";
"VSS27":   PN = "65"  !CDS_PN = "65";
"VSS28":   PN = "67"  !CDS_PN = "67";
"VSS29":   PN = "69"  !CDS_PN = "69";
"VSS30":   PN = "71"  !CDS_PN = "71";
"VSS31":   PN = "73"  !CDS_PN = "73";
"VSS32":   PN = "75"  !CDS_PN = "75";
"VSS33":   PN = "77"  !CDS_PN = "77";
"VSS34":   PN = "79"  !CDS_PN = "79";
"VSS35":   PN = "81"  !CDS_PN = "81";
"VSS36":   PN = "83"  !CDS_PN = "83";
"VSS37":   PN = "85"  !CDS_PN = "85";
"VSS38":   PN = "88"  !CDS_PN = "88";
"VSS39":   PN = "90"  !CDS_PN = "90";
"VSS40":   PN = "92"  !CDS_PN = "92";
"VSS41":   PN = "95"  !CDS_PN = "95";
"VSS42":   PN = "97"  !CDS_PN = "97";
"VSS43":   PN = "99"  !CDS_PN = "99";
"VSS44":   PN = "101"  !CDS_PN = "101";
"VSS45":   PN = "103"  !CDS_PN = "103";
"VSS46":   PN = "106"  !CDS_PN = "106";
"VSS47":   PN = "108"  !CDS_PN = "108";
"VSS48":   PN = "110"  !CDS_PN = "110";
"VSS49":   PN = "112"  !CDS_PN = "112";
"VSS50":   PN = "114"  !CDS_PN = "114";
"VSS51":   PN = "117"  !CDS_PN = "117";
"VSS52":   PN = "119"  !CDS_PN = "119";
"VSS53":   PN = "121"  !CDS_PN = "121";
"VSS54":   PN = "123"  !CDS_PN = "123";
"VSS55":   PN = "125"  !CDS_PN = "125";
"VSS56":   PN = "128"  !CDS_PN = "128";
"VSS57":   PN = "130"  !CDS_PN = "130";
"VSS58":   PN = "132"  !CDS_PN = "132";
"VSS59":   PN = "134"  !CDS_PN = "134";
"VSS60":   PN = "136"  !CDS_PN = "136";
"VSS61":   PN = "139"  !CDS_PN = "139";
"VSS62":   PN = "141"  !CDS_PN = "141";
"VSS63":   PN = "143"  !CDS_PN = "143";
"VSS64":   PN = "151"  !CDS_PN = "151";
"VSS65":   PN = "153"  !CDS_PN = "153";
"VSS66":   PN = "155"  !CDS_PN = "155";
"VSS67":   PN = "158"  !CDS_PN = "158";
"VSS68":   PN = "160"  !CDS_PN = "160";
"VSS69":   PN = "162"  !CDS_PN = "162";
"VSS70":   PN = "164"  !CDS_PN = "164";
"VSS71":   PN = "166"  !CDS_PN = "166";
"VSS72":   PN = "169"  !CDS_PN = "169";
"VSS73":   PN = "171"  !CDS_PN = "171";
"VSS74":   PN = "173"  !CDS_PN = "173";
"VSS75":   PN = "175"  !CDS_PN = "175";
"VSS76":   PN = "177"  !CDS_PN = "177";
"VSS77":   PN = "180"  !CDS_PN = "180";
"VSS78":   PN = "182"  !CDS_PN = "182";
"VSS79":   PN = "184"  !CDS_PN = "184";
"VSS80":   PN = "186"  !CDS_PN = "186";
"VSS81":   PN = "188"  !CDS_PN = "188";
"VSS82":   PN = "191"  !CDS_PN = "191";
"VSS83":   PN = "193"  !CDS_PN = "193";
"VSS84":   PN = "195"  !CDS_PN = "195";
"VSS85":   PN = "197"  !CDS_PN = "197";
"VSS86":   PN = "199"  !CDS_PN = "199";
"VSS87":   PN = "202"  !CDS_PN = "202";
"VSS88":   PN = "204"  !CDS_PN = "204";
"VSS89":   PN = "206"  !CDS_PN = "206";
"VSS90":   PN = "208"  !CDS_PN = "208";
"VSS91":   PN = "210"  !CDS_PN = "210";
"VSS92":   PN = "212"  !CDS_PN = "212";
"VSS93":   PN = "214"  !CDS_PN = "214";
"VSS94":   PN = "216"  !CDS_PN = "216";
"VSS95":   PN = "219"  !CDS_PN = "219";
"VSS96":   PN = "222"  !CDS_PN = "222";
"VSS97":   PN = "224"  !CDS_PN = "224";
"VSS98":   PN = "226"  !CDS_PN = "226";
"VSS99":   PN = "228"  !CDS_PN = "228";
"VSS100":   PN = "230"  !CDS_PN = "230";
"VSS101":   PN = "233"  !CDS_PN = "233";
"VSS102":   PN = "235"  !CDS_PN = "235";
"VSS103":   PN = "237"  !CDS_PN = "237";
"VSS104":   PN = "240"  !CDS_PN = "240";
"VSS105":   PN = "242"  !CDS_PN = "242";
"VSS106":   PN = "244"  !CDS_PN = "244";
"VSS107":   PN = "246"  !CDS_PN = "246";
"VSS108":   PN = "248"  !CDS_PN = "248";
"VSS109":   PN = "251"  !CDS_PN = "251";
"VSS110":   PN = "253"  !CDS_PN = "253";
"VSS111":   PN = "255"  !CDS_PN = "255";
"VSS112":   PN = "257"  !CDS_PN = "257";
"VSS113":   PN = "259"  !CDS_PN = "259";
"VSS114":   PN = "262"  !CDS_PN = "262";
"VSS115":   PN = "264"  !CDS_PN = "264";
"VSS116":   PN = "266"  !CDS_PN = "266";
"VSS117":   PN = "268"  !CDS_PN = "268";
"VSS118":   PN = "270"  !CDS_PN = "270";
"VSS119":   PN = "273"  !CDS_PN = "273";
"VSS120":   PN = "275"  !CDS_PN = "275";
"VSS121":   PN = "277"  !CDS_PN = "277";
"VSS122":   PN = "279"  !CDS_PN = "279";
"VSS123":   PN = "281"  !CDS_PN = "281";
"VSS124":   PN = "284"  !CDS_PN = "284";
"VSS125":   PN = "286"  !CDS_PN = "286";
"VSS126":   PN = "288"  !CDS_PN = "288";
BODY = "SCONN288_ADR50017P130CC","I178": #LOCATION = "J5" !CDS_LOCATION = "J5" &SEC = "2" #&CDS_SEC = "2";
"DQS0_A_C":   PN = "12"  !CDS_PN = "12";
"DQS0_A_T":   PN = "11"  !CDS_PN = "11";
"DQS0_B_C":   PN = "105"  !CDS_PN = "105";
"DQS0_B_T":   PN = "104"  !CDS_PN = "104";
"DQS1_A_C":   PN = "23"  !CDS_PN = "23";
"DQS1_A_T":   PN = "22"  !CDS_PN = "22";
"DQS1_B_C":   PN = "116"  !CDS_PN = "116";
"DQS1_B_T":   PN = "115"  !CDS_PN = "115";
"DQS2_A_C":   PN = "34"  !CDS_PN = "34";
"DQS2_A_T":   PN = "33"  !CDS_PN = "33";
"DQS2_B_C":   PN = "127"  !CDS_PN = "127";
"DQS2_B_T":   PN = "126"  !CDS_PN = "126";
"DQS3_A_C":   PN = "45"  !CDS_PN = "45";
"DQS3_A_T":   PN = "44"  !CDS_PN = "44";
"DQS3_B_C":   PN = "138"  !CDS_PN = "138";
"DQS3_B_T":   PN = "137"  !CDS_PN = "137";
"DQS4_A_C":   PN = "56"  !CDS_PN = "56";
"DQS4_A_T":   PN = "55"  !CDS_PN = "55";
"DQS4_B_C":   PN = "238"  !CDS_PN = "238";
"DQS4_B_T":   PN = "239"  !CDS_PN = "239";
"DQS5_A_C||TDQS5_A_C||DQS5_A_T||TDQS5_A_T":   PN = "156"  !CDS_PN = "156";
"DQS5_A_T||TDQS5_A_T":   PN = "157"  !CDS_PN = "157";
"DQS5_B_C||TDQS5_B_C":   PN = "249"  !CDS_PN = "249";
"DQS5_B_T||TDQS5_B_T":   PN = "250"  !CDS_PN = "250";
"DQS6_A_C||TDQS6_A_C||DQS6_A_T||TDQS6_A_T":   PN = "167"  !CDS_PN = "167";
"DQS6_A_T||TDQS6_A_T":   PN = "168"  !CDS_PN = "168";
"DQS6_B_C||TDQS6_B_C":   PN = "260"  !CDS_PN = "260";
"DQS6_B_T||TDQS6_B_T":   PN = "261"  !CDS_PN = "261";
"DQS7_A_C||TDQS7_A_C":   PN = "178"  !CDS_PN = "178";
"DQS7_A_T||TDQS7_A_T":   PN = "179"  !CDS_PN = "179";
"DQS7_B_C||TDQS7_B_C":   PN = "271"  !CDS_PN = "271";
"DQS7_B_T||TDQS7_B_T":   PN = "272"  !CDS_PN = "272";
"DQS8_A_C||TDQS8_A_C":   PN = "189"  !CDS_PN = "189";
"DQS8_A_T||TDQS8_A_T":   PN = "190"  !CDS_PN = "190";
"DQS8_B_C||TDQS8_B_C":   PN = "282"  !CDS_PN = "282";
"DQS8_B_T||TDQS8_B_T":   PN = "283"  !CDS_PN = "283";
"DQS9_A_C||TDQS9_A_C":   PN = "200"  !CDS_PN = "200";
"DQS9_A_T||TDQS9_A_T":   PN = "201"  !CDS_PN = "201";
"DQS9_B_C||TDQS9_B_C":   PN = "94"  !CDS_PN = "94";
"DQS9_B_T||TDQS9_B_T||DBI4_B_N":   PN = "93"  !CDS_PN = "93";
BODY = "Q_RES","I180": LOCATION = "R3879" #&CDS_LOCATION = "R3879" &SEC = "1" #&CDS_SEC = "1";
"A":   PN = "1"  !CDS_PN = "1";
"B":   PN = "2"  !CDS_PN = "2";
DRAWING = "@s9s_mb_2u_lib.s9s_mb_2u(sch_1):page87";
BODY = "Q_RES","I45": LOCATION = "R31" #&CDS_LOCATION = "R31" &SEC = "1" #&CDS_SEC = "1";
"A":   PN = "1"  !CDS_PN = "1";
"B":   PN = "2"  !CDS_PN = "2";
BODY = "SCONN288_ADR50017P087CC","I46": LOCATION = "J6" #&CDS_LOCATION = "J6" &SEC = "1" #&CDS_SEC = "1";
"ALERT_N":   PN = "62"  !CDS_PN = "62";
"CA0_A":   PN = "66"  !CDS_PN = "66";
"CA0_B":   PN = "76"  !CDS_PN = "76";
"CA1_A":   PN = "211"  !CDS_PN = "211";
"CA1_B":   PN = "221"  !CDS_PN = "221";
"CA2_A":   PN = "68"  !CDS_PN = "68";
"CA2_B":   PN = "78"  !CDS_PN = "78";
"CA3_A":   PN = "213"  !CDS_PN = "213";
"CA3_B":   PN = "223"  !CDS_PN = "223";
"CA4_A":   PN = "70"  !CDS_PN = "70";
"CA4_B":   PN = "80"  !CDS_PN = "80";
"CA5_A":   PN = "215"  !CDS_PN = "215";
"CA5_B":   PN = "225"  !CDS_PN = "225";
"CA6_A":   PN = "72"  !CDS_PN = "72";
"CA6_B":   PN = "82"  !CDS_PN = "82";
"CB0_A":   PN = "51"  !CDS_PN = "51";
"CB0_B":   PN = "96"  !CDS_PN = "96";
"CB1_A":   PN = "53"  !CDS_PN = "53";
"CB1_B":   PN = "98"  !CDS_PN = "98";
"CB2_A":   PN = "196"  !CDS_PN = "196";
"CB2_B":   PN = "241"  !CDS_PN = "241";
"CB3_A":   PN = "198"  !CDS_PN = "198";
"CB3_B":   PN = "243"  !CDS_PN = "243";
"CB4_A":   PN = "58"  !CDS_PN = "58";
"CB4_B":   PN = "89"  !CDS_PN = "89";
"CB5_A":   PN = "60"  !CDS_PN = "60";
"CB5_B":   PN = "91"  !CDS_PN = "91";
"CB6_A":   PN = "203"  !CDS_PN = "203";
"CB6_B":   PN = "234"  !CDS_PN = "234";
"CB7_A":   PN = "205"  !CDS_PN = "205";
"CB7_B":   PN = "236"  !CDS_PN = "236";
"CK_C":   PN = "218"  !CDS_PN = "218";
"CK_T":   PN = "217"  !CDS_PN = "217";
"CS0_A_N":   PN = "64"  !CDS_PN = "64";
"CS0_B_N":   PN = "84"  !CDS_PN = "84";
"CS1_A_N":   PN = "209"  !CDS_PN = "209";
"CS1_B_N":   PN = "229"  !CDS_PN = "229";
"DQ0_A":   PN = "7"  !CDS_PN = "7";
"DQ0_B":   PN = "100"  !CDS_PN = "100";
"DQ1_A":   PN = "9"  !CDS_PN = "9";
"DQ1_B":   PN = "102"  !CDS_PN = "102";
"DQ2_A":   PN = "152"  !CDS_PN = "152";
"DQ2_B":   PN = "245"  !CDS_PN = "245";
"DQ3_A":   PN = "154"  !CDS_PN = "154";
"DQ3_B":   PN = "247"  !CDS_PN = "247";
"DQ4_A":   PN = "14"  !CDS_PN = "14";
"DQ4_B":   PN = "107"  !CDS_PN = "107";
"DQ5_A":   PN = "16"  !CDS_PN = "16";
"DQ5_B":   PN = "109"  !CDS_PN = "109";
"DQ6_A":   PN = "159"  !CDS_PN = "159";
"DQ6_B":   PN = "252"  !CDS_PN = "252";
"DQ7_A":   PN = "161"  !CDS_PN = "161";
"DQ7_B":   PN = "254"  !CDS_PN = "254";
"DQ8_A":   PN = "18"  !CDS_PN = "18";
"DQ8_B":   PN = "111"  !CDS_PN = "111";
"DQ9_A":   PN = "20"  !CDS_PN = "20";
"DQ9_B":   PN = "113"  !CDS_PN = "113";
"DQ10_A":   PN = "163"  !CDS_PN = "163";
"DQ10_B":   PN = "256"  !CDS_PN = "256";
"DQ11_A":   PN = "165"  !CDS_PN = "165";
"DQ11_B":   PN = "258"  !CDS_PN = "258";
"DQ12_A":   PN = "25"  !CDS_PN = "25";
"DQ12_B":   PN = "118"  !CDS_PN = "118";
"DQ13_A":   PN = "27"  !CDS_PN = "27";
"DQ13_B":   PN = "120"  !CDS_PN = "120";
"DQ14_A":   PN = "170"  !CDS_PN = "170";
"DQ14_B":   PN = "263"  !CDS_PN = "263";
"DQ15_A":   PN = "172"  !CDS_PN = "172";
"DQ15_B":   PN = "265"  !CDS_PN = "265";
"DQ16_A":   PN = "29"  !CDS_PN = "29";
"DQ16_B":   PN = "122"  !CDS_PN = "122";
"DQ17_A":   PN = "31"  !CDS_PN = "31";
"DQ17_B":   PN = "124"  !CDS_PN = "124";
"DQ18_A":   PN = "174"  !CDS_PN = "174";
"DQ18_B":   PN = "267"  !CDS_PN = "267";
"DQ19_A":   PN = "176"  !CDS_PN = "176";
"DQ19_B":   PN = "269"  !CDS_PN = "269";
"DQ20_A":   PN = "36"  !CDS_PN = "36";
"DQ20_B":   PN = "129"  !CDS_PN = "129";
"DQ21_A":   PN = "38"  !CDS_PN = "38";
"DQ21_B":   PN = "131"  !CDS_PN = "131";
"DQ22_A":   PN = "181"  !CDS_PN = "181";
"DQ22_B":   PN = "274"  !CDS_PN = "274";
"DQ23_A":   PN = "183"  !CDS_PN = "183";
"DQ23_B":   PN = "276"  !CDS_PN = "276";
"DQ24_A":   PN = "40"  !CDS_PN = "40";
"DQ24_B":   PN = "133"  !CDS_PN = "133";
"DQ25_A":   PN = "42"  !CDS_PN = "42";
"DQ25_B":   PN = "135"  !CDS_PN = "135";
"DQ26_A":   PN = "185"  !CDS_PN = "185";
"DQ26_B":   PN = "278"  !CDS_PN = "278";
"DQ27_A":   PN = "187"  !CDS_PN = "187";
"DQ27_B":   PN = "280"  !CDS_PN = "280";
"DQ28_A":   PN = "47"  !CDS_PN = "47";
"DQ28_B":   PN = "140"  !CDS_PN = "140";
"DQ29_A":   PN = "49"  !CDS_PN = "49";
"DQ29_B":   PN = "142"  !CDS_PN = "142";
"DQ30_A":   PN = "192"  !CDS_PN = "192";
"DQ30_B":   PN = "285"  !CDS_PN = "285";
"DQ31_A":   PN = "194"  !CDS_PN = "194";
"DQ31_B":   PN = "287"  !CDS_PN = "287";
"HSA":   PN = "148"  !CDS_PN = "148";
"HSCL":   PN = "4"  !CDS_PN = "4";
"HSDA":   PN = "5"  !CDS_PN = "5";
"LBD||RSP_A_N":   PN = "86"  !CDS_PN = "86";
"LBS||RSP_B_N":   PN = "87"  !CDS_PN = "87";
"PAR_A":   PN = "74"  !CDS_PN = "74";
"PAR_B":   PN = "227"  !CDS_PN = "227";
"PWR_GOOD||FAIL_N":   PN = "147"  !CDS_PN = "147";
"RESET_N":   PN = "207"  !CDS_PN = "207";
"RFU0":   PN = "2"  !CDS_PN = "2";
"RFU1":   PN = "144"  !CDS_PN = "144";
"RFU2":   PN = "149"  !CDS_PN = "149";
"RFU3":   PN = "150"  !CDS_PN = "150";
"RFU4":   PN = "220"  !CDS_PN = "220";
"RFU5":   PN = "231"  !CDS_PN = "231";
"RFU6":   PN = "232"  !CDS_PN = "232";
"VIN_MGMT":   PN = "3"  !CDS_PN = "3";
BODY = "Q_CAP","I120": LOCATION = "C17" #&CDS_LOCATION = "C17" &SEC = "1" #&CDS_SEC = "1";
"A":   PN = "1"  !CDS_PN = "1";
"B":   PN = "2"  !CDS_PN = "2";
BODY = "Q_CAP","I124": LOCATION = "C18" #&CDS_LOCATION = "C18" &SEC = "1" #&CDS_SEC = "1";
"A":   PN = "1"  !CDS_PN = "1";
"B":   PN = "2"  !CDS_PN = "2";
BODY = "Q_CAP","I127": LOCATION = "C19" #&CDS_LOCATION = "C19" &SEC = "1" #&CDS_SEC = "1";
"A":   PN = "1"  !CDS_PN = "1";
"B":   PN = "2"  !CDS_PN = "2";
BODY = "SCONN288_ADR50017P087CC","I175": LOCATION = "J6" #&CDS_LOCATION = "J6" &SEC = "3" #&CDS_SEC = "3";
"G1":   PN = "G1"  !CDS_PN = "G1";
"G2":   PN = "G2"  !CDS_PN = "G2";
"G3":   PN = "G3"  !CDS_PN = "G3";
"VIN_BULK0":   PN = "1"  !CDS_PN = "1";
"VIN_BULK1":   PN = "145"  !CDS_PN = "145";
"VIN_BULK2":   PN = "146"  !CDS_PN = "146";
"VSS0":   PN = "6"  !CDS_PN = "6";
"VSS1":   PN = "8"  !CDS_PN = "8";
"VSS2":   PN = "10"  !CDS_PN = "10";
"VSS3":   PN = "13"  !CDS_PN = "13";
"VSS4":   PN = "15"  !CDS_PN = "15";
"VSS5":   PN = "17"  !CDS_PN = "17";
"VSS6":   PN = "19"  !CDS_PN = "19";
"VSS7":   PN = "21"  !CDS_PN = "21";
"VSS8":   PN = "24"  !CDS_PN = "24";
"VSS9":   PN = "26"  !CDS_PN = "26";
"VSS10":   PN = "28"  !CDS_PN = "28";
"VSS11":   PN = "30"  !CDS_PN = "30";
"VSS12":   PN = "32"  !CDS_PN = "32";
"VSS13":   PN = "35"  !CDS_PN = "35";
"VSS14":   PN = "37"  !CDS_PN = "37";
"VSS15":   PN = "39"  !CDS_PN = "39";
"VSS16":   PN = "41"  !CDS_PN = "41";
"VSS17":   PN = "43"  !CDS_PN = "43";
"VSS18":   PN = "46"  !CDS_PN = "46";
"VSS19":   PN = "48"  !CDS_PN = "48";
"VSS20":   PN = "50"  !CDS_PN = "50";
"VSS21":   PN = "52"  !CDS_PN = "52";
"VSS22":   PN = "54"  !CDS_PN = "54";
"VSS23":   PN = "57"  !CDS_PN = "57";
"VSS24":   PN = "59"  !CDS_PN = "59";
"VSS25":   PN = "61"  !CDS_PN = "61";
"VSS26":   PN = "63"  !CDS_PN = "63";
"VSS27":   PN = "65"  !CDS_PN = "65";
"VSS28":   PN = "67"  !CDS_PN = "67";
"VSS29":   PN = "69"  !CDS_PN = "69";
"VSS30":   PN = "71"  !CDS_PN = "71";
"VSS31":   PN = "73"  !CDS_PN = "73";
"VSS32":   PN = "75"  !CDS_PN = "75";
"VSS33":   PN = "77"  !CDS_PN = "77";
"VSS34":   PN = "79"  !CDS_PN = "79";
"VSS35":   PN = "81"  !CDS_PN = "81";
"VSS36":   PN = "83"  !CDS_PN = "83";
"VSS37":   PN = "85"  !CDS_PN = "85";
"VSS38":   PN = "88"  !CDS_PN = "88";
"VSS39":   PN = "90"  !CDS_PN = "90";
"VSS40":   PN = "92"  !CDS_PN = "92";
"VSS41":   PN = "95"  !CDS_PN = "95";
"VSS42":   PN = "97"  !CDS_PN = "97";
"VSS43":   PN = "99"  !CDS_PN = "99";
"VSS44":   PN = "101"  !CDS_PN = "101";
"VSS45":   PN = "103"  !CDS_PN = "103";
"VSS46":   PN = "106"  !CDS_PN = "106";
"VSS47":   PN = "108"  !CDS_PN = "108";
"VSS48":   PN = "110"  !CDS_PN = "110";
"VSS49":   PN = "112"  !CDS_PN = "112";
"VSS50":   PN = "114"  !CDS_PN = "114";
"VSS51":   PN = "117"  !CDS_PN = "117";
"VSS52":   PN = "119"  !CDS_PN = "119";
"VSS53":   PN = "121"  !CDS_PN = "121";
"VSS54":   PN = "123"  !CDS_PN = "123";
"VSS55":   PN = "125"  !CDS_PN = "125";
"VSS56":   PN = "128"  !CDS_PN = "128";
"VSS57":   PN = "130"  !CDS_PN = "130";
"VSS58":   PN = "132"  !CDS_PN = "132";
"VSS59":   PN = "134"  !CDS_PN = "134";
"VSS60":   PN = "136"  !CDS_PN = "136";
"VSS61":   PN = "139"  !CDS_PN = "139";
"VSS62":   PN = "141"  !CDS_PN = "141";
"VSS63":   PN = "143"  !CDS_PN = "143";
"VSS64":   PN = "151"  !CDS_PN = "151";
"VSS65":   PN = "153"  !CDS_PN = "153";
"VSS66":   PN = "155"  !CDS_PN = "155";
"VSS67":   PN = "158"  !CDS_PN = "158";
"VSS68":   PN = "160"  !CDS_PN = "160";
"VSS69":   PN = "162"  !CDS_PN = "162";
"VSS70":   PN = "164"  !CDS_PN = "164";
"VSS71":   PN = "166"  !CDS_PN = "166";
"VSS72":   PN = "169"  !CDS_PN = "169";
"VSS73":   PN = "171"  !CDS_PN = "171";
"VSS74":   PN = "173"  !CDS_PN = "173";
"VSS75":   PN = "175"  !CDS_PN = "175";
"VSS76":   PN = "177"  !CDS_PN = "177";
"VSS77":   PN = "180"  !CDS_PN = "180";
"VSS78":   PN = "182"  !CDS_PN = "182";
"VSS79":   PN = "184"  !CDS_PN = "184";
"VSS80":   PN = "186"  !CDS_PN = "186";
"VSS81":   PN = "188"  !CDS_PN = "188";
"VSS82":   PN = "191"  !CDS_PN = "191";
"VSS83":   PN = "193"  !CDS_PN = "193";
"VSS84":   PN = "195"  !CDS_PN = "195";
"VSS85":   PN = "197"  !CDS_PN = "197";
"VSS86":   PN = "199"  !CDS_PN = "199";
"VSS87":   PN = "202"  !CDS_PN = "202";
"VSS88":   PN = "204"  !CDS_PN = "204";
"VSS89":   PN = "206"  !CDS_PN = "206";
"VSS90":   PN = "208"  !CDS_PN = "208";
"VSS91":   PN = "210"  !CDS_PN = "210";
"VSS92":   PN = "212"  !CDS_PN = "212";
"VSS93":   PN = "214"  !CDS_PN = "214";
"VSS94":   PN = "216"  !CDS_PN = "216";
"VSS95":   PN = "219"  !CDS_PN = "219";
"VSS96":   PN = "222"  !CDS_PN = "222";
"VSS97":   PN = "224"  !CDS_PN = "224";
"VSS98":   PN = "226"  !CDS_PN = "226";
"VSS99":   PN = "228"  !CDS_PN = "228";
"VSS100":   PN = "230"  !CDS_PN = "230";
"VSS101":   PN = "233"  !CDS_PN = "233";
"VSS102":   PN = "235"  !CDS_PN = "235";
"VSS103":   PN = "237"  !CDS_PN = "237";
"VSS104":   PN = "240"  !CDS_PN = "240";
"VSS105":   PN = "242"  !CDS_PN = "242";
"VSS106":   PN = "244"  !CDS_PN = "244";
"VSS107":   PN = "246"  !CDS_PN = "246";
"VSS108":   PN = "248"  !CDS_PN = "248";
"VSS109":   PN = "251"  !CDS_PN = "251";
"VSS110":   PN = "253"  !CDS_PN = "253";
"VSS111":   PN = "255"  !CDS_PN = "255";
"VSS112":   PN = "257"  !CDS_PN = "257";
"VSS113":   PN = "259"  !CDS_PN = "259";
"VSS114":   PN = "262"  !CDS_PN = "262";
"VSS115":   PN = "264"  !CDS_PN = "264";
"VSS116":   PN = "266"  !CDS_PN = "266";
"VSS117":   PN = "268"  !CDS_PN = "268";
"VSS118":   PN = "270"  !CDS_PN = "270";
"VSS119":   PN = "273"  !CDS_PN = "273";
"VSS120":   PN = "275"  !CDS_PN = "275";
"VSS121":   PN = "277"  !CDS_PN = "277";
"VSS122":   PN = "279"  !CDS_PN = "279";
"VSS123":   PN = "281"  !CDS_PN = "281";
"VSS124":   PN = "284"  !CDS_PN = "284";
"VSS125":   PN = "286"  !CDS_PN = "286";
"VSS126":   PN = "288"  !CDS_PN = "288";
BODY = "SCONN288_ADR50017P087CC","I178": #LOCATION = "J6" !CDS_LOCATION = "J6" &SEC = "2" #&CDS_SEC = "2";
"DQS0_A_C":   PN = "12"  !CDS_PN = "12";
"DQS0_A_T":   PN = "11"  !CDS_PN = "11";
"DQS0_B_C":   PN = "105"  !CDS_PN = "105";
"DQS0_B_T":   PN = "104"  !CDS_PN = "104";
"DQS1_A_C":   PN = "23"  !CDS_PN = "23";
"DQS1_A_T":   PN = "22"  !CDS_PN = "22";
"DQS1_B_C":   PN = "116"  !CDS_PN = "116";
"DQS1_B_T":   PN = "115"  !CDS_PN = "115";
"DQS2_A_C":   PN = "34"  !CDS_PN = "34";
"DQS2_A_T":   PN = "33"  !CDS_PN = "33";
"DQS2_B_C":   PN = "127"  !CDS_PN = "127";
"DQS2_B_T":   PN = "126"  !CDS_PN = "126";
"DQS3_A_C":   PN = "45"  !CDS_PN = "45";
"DQS3_A_T":   PN = "44"  !CDS_PN = "44";
"DQS3_B_C":   PN = "138"  !CDS_PN = "138";
"DQS3_B_T":   PN = "137"  !CDS_PN = "137";
"DQS4_A_C":   PN = "56"  !CDS_PN = "56";
"DQS4_A_T":   PN = "55"  !CDS_PN = "55";
"DQS4_B_C":   PN = "238"  !CDS_PN = "238";
"DQS4_B_T":   PN = "239"  !CDS_PN = "239";
"DQS5_A_C||TDQS5_A_C||DQS5_A_T||TDQS5_A_T":   PN = "156"  !CDS_PN = "156";
"DQS5_A_T||TDQS5_A_T":   PN = "157"  !CDS_PN = "157";
"DQS5_B_C||TDQS5_B_C":   PN = "249"  !CDS_PN = "249";
"DQS5_B_T||TDQS5_B_T":   PN = "250"  !CDS_PN = "250";
"DQS6_A_C||TDQS6_A_C||DQS6_A_T||TDQS6_A_T":   PN = "167"  !CDS_PN = "167";
"DQS6_A_T||TDQS6_A_T":   PN = "168"  !CDS_PN = "168";
"DQS6_B_C||TDQS6_B_C":   PN = "260"  !CDS_PN = "260";
"DQS6_B_T||TDQS6_B_T":   PN = "261"  !CDS_PN = "261";
"DQS7_A_C||TDQS7_A_C":   PN = "178"  !CDS_PN = "178";
"DQS7_A_T||TDQS7_A_T":   PN = "179"  !CDS_PN = "179";
"DQS7_B_C||TDQS7_B_C":   PN = "271"  !CDS_PN = "271";
"DQS7_B_T||TDQS7_B_T":   PN = "272"  !CDS_PN = "272";
"DQS8_A_C||TDQS8_A_C":   PN = "189"  !CDS_PN = "189";
"DQS8_A_T||TDQS8_A_T":   PN = "190"  !CDS_PN = "190";
"DQS8_B_C||TDQS8_B_C":   PN = "282"  !CDS_PN = "282";
"DQS8_B_T||TDQS8_B_T":   PN = "283"  !CDS_PN = "283";
"DQS9_A_C||TDQS9_A_C":   PN = "200"  !CDS_PN = "200";
"DQS9_A_T||TDQS9_A_T":   PN = "201"  !CDS_PN = "201";
"DQS9_B_C||TDQS9_B_C":   PN = "94"  !CDS_PN = "94";
"DQS9_B_T||TDQS9_B_T||DBI4_B_N":   PN = "93"  !CDS_PN = "93";
BODY = "Q_RES","I180": LOCATION = "R3880" #&CDS_LOCATION = "R3880" &SEC = "1" #&CDS_SEC = "1";
"A":   PN = "1"  !CDS_PN = "1";
"B":   PN = "2"  !CDS_PN = "2";
DRAWING = "@s9s_mb_2u_lib.s9s_mb_2u(sch_1):page88";
BODY = "Q_RES","I2": LOCATION = "R32" #&CDS_LOCATION = "R32" &SEC = "1" #&CDS_SEC = "1";
"A":   PN = "1"  !CDS_PN = "1";
"B":   PN = "2"  !CDS_PN = "2";
BODY = "SCONN288_ADR50017P130CC","I12": LOCATION = "J7" #&CDS_LOCATION = "J7" &SEC = "1" #&CDS_SEC = "1";
"ALERT_N":   PN = "62"  !CDS_PN = "62";
"CA0_A":   PN = "66"  !CDS_PN = "66";
"CA0_B":   PN = "76"  !CDS_PN = "76";
"CA1_A":   PN = "211"  !CDS_PN = "211";
"CA1_B":   PN = "221"  !CDS_PN = "221";
"CA2_A":   PN = "68"  !CDS_PN = "68";
"CA2_B":   PN = "78"  !CDS_PN = "78";
"CA3_A":   PN = "213"  !CDS_PN = "213";
"CA3_B":   PN = "223"  !CDS_PN = "223";
"CA4_A":   PN = "70"  !CDS_PN = "70";
"CA4_B":   PN = "80"  !CDS_PN = "80";
"CA5_A":   PN = "215"  !CDS_PN = "215";
"CA5_B":   PN = "225"  !CDS_PN = "225";
"CA6_A":   PN = "72"  !CDS_PN = "72";
"CA6_B":   PN = "82"  !CDS_PN = "82";
"CB0_A":   PN = "51"  !CDS_PN = "51";
"CB0_B":   PN = "96"  !CDS_PN = "96";
"CB1_A":   PN = "53"  !CDS_PN = "53";
"CB1_B":   PN = "98"  !CDS_PN = "98";
"CB2_A":   PN = "196"  !CDS_PN = "196";
"CB2_B":   PN = "241"  !CDS_PN = "241";
"CB3_A":   PN = "198"  !CDS_PN = "198";
"CB3_B":   PN = "243"  !CDS_PN = "243";
"CB4_A":   PN = "58"  !CDS_PN = "58";
"CB4_B":   PN = "89"  !CDS_PN = "89";
"CB5_A":   PN = "60"  !CDS_PN = "60";
"CB5_B":   PN = "91"  !CDS_PN = "91";
"CB6_A":   PN = "203"  !CDS_PN = "203";
"CB6_B":   PN = "234"  !CDS_PN = "234";
"CB7_A":   PN = "205"  !CDS_PN = "205";
"CB7_B":   PN = "236"  !CDS_PN = "236";
"CK_C":   PN = "218"  !CDS_PN = "218";
"CK_T":   PN = "217"  !CDS_PN = "217";
"CS0_A_N":   PN = "64"  !CDS_PN = "64";
"CS0_B_N":   PN = "84"  !CDS_PN = "84";
"CS1_A_N":   PN = "209"  !CDS_PN = "209";
"CS1_B_N":   PN = "229"  !CDS_PN = "229";
"DQ0_A":   PN = "7"  !CDS_PN = "7";
"DQ0_B":   PN = "100"  !CDS_PN = "100";
"DQ1_A":   PN = "9"  !CDS_PN = "9";
"DQ1_B":   PN = "102"  !CDS_PN = "102";
"DQ2_A":   PN = "152"  !CDS_PN = "152";
"DQ2_B":   PN = "245"  !CDS_PN = "245";
"DQ3_A":   PN = "154"  !CDS_PN = "154";
"DQ3_B":   PN = "247"  !CDS_PN = "247";
"DQ4_A":   PN = "14"  !CDS_PN = "14";
"DQ4_B":   PN = "107"  !CDS_PN = "107";
"DQ5_A":   PN = "16"  !CDS_PN = "16";
"DQ5_B":   PN = "109"  !CDS_PN = "109";
"DQ6_A":   PN = "159"  !CDS_PN = "159";
"DQ6_B":   PN = "252"  !CDS_PN = "252";
"DQ7_A":   PN = "161"  !CDS_PN = "161";
"DQ7_B":   PN = "254"  !CDS_PN = "254";
"DQ8_A":   PN = "18"  !CDS_PN = "18";
"DQ8_B":   PN = "111"  !CDS_PN = "111";
"DQ9_A":   PN = "20"  !CDS_PN = "20";
"DQ9_B":   PN = "113"  !CDS_PN = "113";
"DQ10_A":   PN = "163"  !CDS_PN = "163";
"DQ10_B":   PN = "256"  !CDS_PN = "256";
"DQ11_A":   PN = "165"  !CDS_PN = "165";
"DQ11_B":   PN = "258"  !CDS_PN = "258";
"DQ12_A":   PN = "25"  !CDS_PN = "25";
"DQ12_B":   PN = "118"  !CDS_PN = "118";
"DQ13_A":   PN = "27"  !CDS_PN = "27";
"DQ13_B":   PN = "120"  !CDS_PN = "120";
"DQ14_A":   PN = "170"  !CDS_PN = "170";
"DQ14_B":   PN = "263"  !CDS_PN = "263";
"DQ15_A":   PN = "172"  !CDS_PN = "172";
"DQ15_B":   PN = "265"  !CDS_PN = "265";
"DQ16_A":   PN = "29"  !CDS_PN = "29";
"DQ16_B":   PN = "122"  !CDS_PN = "122";
"DQ17_A":   PN = "31"  !CDS_PN = "31";
"DQ17_B":   PN = "124"  !CDS_PN = "124";
"DQ18_A":   PN = "174"  !CDS_PN = "174";
"DQ18_B":   PN = "267"  !CDS_PN = "267";
"DQ19_A":   PN = "176"  !CDS_PN = "176";
"DQ19_B":   PN = "269"  !CDS_PN = "269";
"DQ20_A":   PN = "36"  !CDS_PN = "36";
"DQ20_B":   PN = "129"  !CDS_PN = "129";
"DQ21_A":   PN = "38"  !CDS_PN = "38";
"DQ21_B":   PN = "131"  !CDS_PN = "131";
"DQ22_A":   PN = "181"  !CDS_PN = "181";
"DQ22_B":   PN = "274"  !CDS_PN = "274";
"DQ23_A":   PN = "183"  !CDS_PN = "183";
"DQ23_B":   PN = "276"  !CDS_PN = "276";
"DQ24_A":   PN = "40"  !CDS_PN = "40";
"DQ24_B":   PN = "133"  !CDS_PN = "133";
"DQ25_A":   PN = "42"  !CDS_PN = "42";
"DQ25_B":   PN = "135"  !CDS_PN = "135";
"DQ26_A":   PN = "185"  !CDS_PN = "185";
"DQ26_B":   PN = "278"  !CDS_PN = "278";
"DQ27_A":   PN = "187"  !CDS_PN = "187";
"DQ27_B":   PN = "280"  !CDS_PN = "280";
"DQ28_A":   PN = "47"  !CDS_PN = "47";
"DQ28_B":   PN = "140"  !CDS_PN = "140";
"DQ29_A":   PN = "49"  !CDS_PN = "49";
"DQ29_B":   PN = "142"  !CDS_PN = "142";
"DQ30_A":   PN = "192"  !CDS_PN = "192";
"DQ30_B":   PN = "285"  !CDS_PN = "285";
"DQ31_A":   PN = "194"  !CDS_PN = "194";
"DQ31_B":   PN = "287"  !CDS_PN = "287";
"HSA":   PN = "148"  !CDS_PN = "148";
"HSCL":   PN = "4"  !CDS_PN = "4";
"HSDA":   PN = "5"  !CDS_PN = "5";
"LBD||RSP_A_N":   PN = "86"  !CDS_PN = "86";
"LBS||RSP_B_N":   PN = "87"  !CDS_PN = "87";
"PAR_A":   PN = "74"  !CDS_PN = "74";
"PAR_B":   PN = "227"  !CDS_PN = "227";
"PWR_GOOD||FAIL_N":   PN = "147"  !CDS_PN = "147";
"RESET_N":   PN = "207"  !CDS_PN = "207";
"RFU0":   PN = "2"  !CDS_PN = "2";
"RFU1":   PN = "144"  !CDS_PN = "144";
"RFU2":   PN = "149"  !CDS_PN = "149";
"RFU3":   PN = "150"  !CDS_PN = "150";
"RFU4":   PN = "220"  !CDS_PN = "220";
"RFU5":   PN = "231"  !CDS_PN = "231";
"RFU6":   PN = "232"  !CDS_PN = "232";
"VIN_MGMT":   PN = "3"  !CDS_PN = "3";
BODY = "Q_CAP","I123": LOCATION = "C20" #&CDS_LOCATION = "C20" &SEC = "1" #&CDS_SEC = "1";
"A":   PN = "1"  !CDS_PN = "1";
"B":   PN = "2"  !CDS_PN = "2";
BODY = "Q_CAP","I126": LOCATION = "C21" #&CDS_LOCATION = "C21" &SEC = "1" #&CDS_SEC = "1";
"A":   PN = "1"  !CDS_PN = "1";
"B":   PN = "2"  !CDS_PN = "2";
BODY = "Q_CAP","I166": LOCATION = "C22" #&CDS_LOCATION = "C22" &SEC = "1" #&CDS_SEC = "1";
"A":   PN = "1"  !CDS_PN = "1";
"B":   PN = "2"  !CDS_PN = "2";
BODY = "SCONN288_ADR50017P130CC","I168": LOCATION = "J7" #&CDS_LOCATION = "J7" &SEC = "3" #&CDS_SEC = "3";
"G1":   PN = "G1"  !CDS_PN = "G1";
"G2":   PN = "G2"  !CDS_PN = "G2";
"G3":   PN = "G3"  !CDS_PN = "G3";
"VIN_BULK0":   PN = "1"  !CDS_PN = "1";
"VIN_BULK1":   PN = "145"  !CDS_PN = "145";
"VIN_BULK2":   PN = "146"  !CDS_PN = "146";
"VSS0":   PN = "6"  !CDS_PN = "6";
"VSS1":   PN = "8"  !CDS_PN = "8";
"VSS2":   PN = "10"  !CDS_PN = "10";
"VSS3":   PN = "13"  !CDS_PN = "13";
"VSS4":   PN = "15"  !CDS_PN = "15";
"VSS5":   PN = "17"  !CDS_PN = "17";
"VSS6":   PN = "19"  !CDS_PN = "19";
"VSS7":   PN = "21"  !CDS_PN = "21";
"VSS8":   PN = "24"  !CDS_PN = "24";
"VSS9":   PN = "26"  !CDS_PN = "26";
"VSS10":   PN = "28"  !CDS_PN = "28";
"VSS11":   PN = "30"  !CDS_PN = "30";
"VSS12":   PN = "32"  !CDS_PN = "32";
"VSS13":   PN = "35"  !CDS_PN = "35";
"VSS14":   PN = "37"  !CDS_PN = "37";
"VSS15":   PN = "39"  !CDS_PN = "39";
"VSS16":   PN = "41"  !CDS_PN = "41";
"VSS17":   PN = "43"  !CDS_PN = "43";
"VSS18":   PN = "46"  !CDS_PN = "46";
"VSS19":   PN = "48"  !CDS_PN = "48";
"VSS20":   PN = "50"  !CDS_PN = "50";
"VSS21":   PN = "52"  !CDS_PN = "52";
"VSS22":   PN = "54"  !CDS_PN = "54";
"VSS23":   PN = "57"  !CDS_PN = "57";
"VSS24":   PN = "59"  !CDS_PN = "59";
"VSS25":   PN = "61"  !CDS_PN = "61";
"VSS26":   PN = "63"  !CDS_PN = "63";
"VSS27":   PN = "65"  !CDS_PN = "65";
"VSS28":   PN = "67"  !CDS_PN = "67";
"VSS29":   PN = "69"  !CDS_PN = "69";
"VSS30":   PN = "71"  !CDS_PN = "71";
"VSS31":   PN = "73"  !CDS_PN = "73";
"VSS32":   PN = "75"  !CDS_PN = "75";
"VSS33":   PN = "77"  !CDS_PN = "77";
"VSS34":   PN = "79"  !CDS_PN = "79";
"VSS35":   PN = "81"  !CDS_PN = "81";
"VSS36":   PN = "83"  !CDS_PN = "83";
"VSS37":   PN = "85"  !CDS_PN = "85";
"VSS38":   PN = "88"  !CDS_PN = "88";
"VSS39":   PN = "90"  !CDS_PN = "90";
"VSS40":   PN = "92"  !CDS_PN = "92";
"VSS41":   PN = "95"  !CDS_PN = "95";
"VSS42":   PN = "97"  !CDS_PN = "97";
"VSS43":   PN = "99"  !CDS_PN = "99";
"VSS44":   PN = "101"  !CDS_PN = "101";
"VSS45":   PN = "103"  !CDS_PN = "103";
"VSS46":   PN = "106"  !CDS_PN = "106";
"VSS47":   PN = "108"  !CDS_PN = "108";
"VSS48":   PN = "110"  !CDS_PN = "110";
"VSS49":   PN = "112"  !CDS_PN = "112";
"VSS50":   PN = "114"  !CDS_PN = "114";
"VSS51":   PN = "117"  !CDS_PN = "117";
"VSS52":   PN = "119"  !CDS_PN = "119";
"VSS53":   PN = "121"  !CDS_PN = "121";
"VSS54":   PN = "123"  !CDS_PN = "123";
"VSS55":   PN = "125"  !CDS_PN = "125";
"VSS56":   PN = "128"  !CDS_PN = "128";
"VSS57":   PN = "130"  !CDS_PN = "130";
"VSS58":   PN = "132"  !CDS_PN = "132";
"VSS59":   PN = "134"  !CDS_PN = "134";
"VSS60":   PN = "136"  !CDS_PN = "136";
"VSS61":   PN = "139"  !CDS_PN = "139";
"VSS62":   PN = "141"  !CDS_PN = "141";
"VSS63":   PN = "143"  !CDS_PN = "143";
"VSS64":   PN = "151"  !CDS_PN = "151";
"VSS65":   PN = "153"  !CDS_PN = "153";
"VSS66":   PN = "155"  !CDS_PN = "155";
"VSS67":   PN = "158"  !CDS_PN = "158";
"VSS68":   PN = "160"  !CDS_PN = "160";
"VSS69":   PN = "162"  !CDS_PN = "162";
"VSS70":   PN = "164"  !CDS_PN = "164";
"VSS71":   PN = "166"  !CDS_PN = "166";
"VSS72":   PN = "169"  !CDS_PN = "169";
"VSS73":   PN = "171"  !CDS_PN = "171";
"VSS74":   PN = "173"  !CDS_PN = "173";
"VSS75":   PN = "175"  !CDS_PN = "175";
"VSS76":   PN = "177"  !CDS_PN = "177";
"VSS77":   PN = "180"  !CDS_PN = "180";
"VSS78":   PN = "182"  !CDS_PN = "182";
"VSS79":   PN = "184"  !CDS_PN = "184";
"VSS80":   PN = "186"  !CDS_PN = "186";
"VSS81":   PN = "188"  !CDS_PN = "188";
"VSS82":   PN = "191"  !CDS_PN = "191";
"VSS83":   PN = "193"  !CDS_PN = "193";
"VSS84":   PN = "195"  !CDS_PN = "195";
"VSS85":   PN = "197"  !CDS_PN = "197";
"VSS86":   PN = "199"  !CDS_PN = "199";
"VSS87":   PN = "202"  !CDS_PN = "202";
"VSS88":   PN = "204"  !CDS_PN = "204";
"VSS89":   PN = "206"  !CDS_PN = "206";
"VSS90":   PN = "208"  !CDS_PN = "208";
"VSS91":   PN = "210"  !CDS_PN = "210";
"VSS92":   PN = "212"  !CDS_PN = "212";
"VSS93":   PN = "214"  !CDS_PN = "214";
"VSS94":   PN = "216"  !CDS_PN = "216";
"VSS95":   PN = "219"  !CDS_PN = "219";
"VSS96":   PN = "222"  !CDS_PN = "222";
"VSS97":   PN = "224"  !CDS_PN = "224";
"VSS98":   PN = "226"  !CDS_PN = "226";
"VSS99":   PN = "228"  !CDS_PN = "228";
"VSS100":   PN = "230"  !CDS_PN = "230";
"VSS101":   PN = "233"  !CDS_PN = "233";
"VSS102":   PN = "235"  !CDS_PN = "235";
"VSS103":   PN = "237"  !CDS_PN = "237";
"VSS104":   PN = "240"  !CDS_PN = "240";
"VSS105":   PN = "242"  !CDS_PN = "242";
"VSS106":   PN = "244"  !CDS_PN = "244";
"VSS107":   PN = "246"  !CDS_PN = "246";
"VSS108":   PN = "248"  !CDS_PN = "248";
"VSS109":   PN = "251"  !CDS_PN = "251";
"VSS110":   PN = "253"  !CDS_PN = "253";
"VSS111":   PN = "255"  !CDS_PN = "255";
"VSS112":   PN = "257"  !CDS_PN = "257";
"VSS113":   PN = "259"  !CDS_PN = "259";
"VSS114":   PN = "262"  !CDS_PN = "262";
"VSS115":   PN = "264"  !CDS_PN = "264";
"VSS116":   PN = "266"  !CDS_PN = "266";
"VSS117":   PN = "268"  !CDS_PN = "268";
"VSS118":   PN = "270"  !CDS_PN = "270";
"VSS119":   PN = "273"  !CDS_PN = "273";
"VSS120":   PN = "275"  !CDS_PN = "275";
"VSS121":   PN = "277"  !CDS_PN = "277";
"VSS122":   PN = "279"  !CDS_PN = "279";
"VSS123":   PN = "281"  !CDS_PN = "281";
"VSS124":   PN = "284"  !CDS_PN = "284";
"VSS125":   PN = "286"  !CDS_PN = "286";
"VSS126":   PN = "288"  !CDS_PN = "288";
BODY = "SCONN288_ADR50017P130CC","I178": #LOCATION = "J7" !CDS_LOCATION = "J7" &SEC = "2" #&CDS_SEC = "2";
"DQS0_A_C":   PN = "12"  !CDS_PN = "12";
"DQS0_A_T":   PN = "11"  !CDS_PN = "11";
"DQS0_B_C":   PN = "105"  !CDS_PN = "105";
"DQS0_B_T":   PN = "104"  !CDS_PN = "104";
"DQS1_A_C":   PN = "23"  !CDS_PN = "23";
"DQS1_A_T":   PN = "22"  !CDS_PN = "22";
"DQS1_B_C":   PN = "116"  !CDS_PN = "116";
"DQS1_B_T":   PN = "115"  !CDS_PN = "115";
"DQS2_A_C":   PN = "34"  !CDS_PN = "34";
"DQS2_A_T":   PN = "33"  !CDS_PN = "33";
"DQS2_B_C":   PN = "127"  !CDS_PN = "127";
"DQS2_B_T":   PN = "126"  !CDS_PN = "126";
"DQS3_A_C":   PN = "45"  !CDS_PN = "45";
"DQS3_A_T":   PN = "44"  !CDS_PN = "44";
"DQS3_B_C":   PN = "138"  !CDS_PN = "138";
"DQS3_B_T":   PN = "137"  !CDS_PN = "137";
"DQS4_A_C":   PN = "56"  !CDS_PN = "56";
"DQS4_A_T":   PN = "55"  !CDS_PN = "55";
"DQS4_B_C":   PN = "238"  !CDS_PN = "238";
"DQS4_B_T":   PN = "239"  !CDS_PN = "239";
"DQS5_A_C||TDQS5_A_C||DQS5_A_T||TDQS5_A_T":   PN = "156"  !CDS_PN = "156";
"DQS5_A_T||TDQS5_A_T":   PN = "157"  !CDS_PN = "157";
"DQS5_B_C||TDQS5_B_C":   PN = "249"  !CDS_PN = "249";
"DQS5_B_T||TDQS5_B_T":   PN = "250"  !CDS_PN = "250";
"DQS6_A_C||TDQS6_A_C||DQS6_A_T||TDQS6_A_T":   PN = "167"  !CDS_PN = "167";
"DQS6_A_T||TDQS6_A_T":   PN = "168"  !CDS_PN = "168";
"DQS6_B_C||TDQS6_B_C":   PN = "260"  !CDS_PN = "260";
"DQS6_B_T||TDQS6_B_T":   PN = "261"  !CDS_PN = "261";
"DQS7_A_C||TDQS7_A_C":   PN = "178"  !CDS_PN = "178";
"DQS7_A_T||TDQS7_A_T":   PN = "179"  !CDS_PN = "179";
"DQS7_B_C||TDQS7_B_C":   PN = "271"  !CDS_PN = "271";
"DQS7_B_T||TDQS7_B_T":   PN = "272"  !CDS_PN = "272";
"DQS8_A_C||TDQS8_A_C":   PN = "189"  !CDS_PN = "189";
"DQS8_A_T||TDQS8_A_T":   PN = "190"  !CDS_PN = "190";
"DQS8_B_C||TDQS8_B_C":   PN = "282"  !CDS_PN = "282";
"DQS8_B_T||TDQS8_B_T":   PN = "283"  !CDS_PN = "283";
"DQS9_A_C||TDQS9_A_C":   PN = "200"  !CDS_PN = "200";
"DQS9_A_T||TDQS9_A_T":   PN = "201"  !CDS_PN = "201";
"DQS9_B_C||TDQS9_B_C":   PN = "94"  !CDS_PN = "94";
"DQS9_B_T||TDQS9_B_T||DBI4_B_N":   PN = "93"  !CDS_PN = "93";
BODY = "Q_RES","I180": LOCATION = "R3881" #&CDS_LOCATION = "R3881" &SEC = "1" #&CDS_SEC = "1";
"A":   PN = "1"  !CDS_PN = "1";
"B":   PN = "2"  !CDS_PN = "2";
DRAWING = "@s9s_mb_2u_lib.s9s_mb_2u(sch_1):page89";
BODY = "Q_RES","I2": LOCATION = "R33" #&CDS_LOCATION = "R33" &SEC = "1" #&CDS_SEC = "1";
"A":   PN = "1"  !CDS_PN = "1";
"B":   PN = "2"  !CDS_PN = "2";
BODY = "SCONN288_ADR50017P087CC","I50": LOCATION = "J8" #&CDS_LOCATION = "J8" &SEC = "1" #&CDS_SEC = "1";
"ALERT_N":   PN = "62"  !CDS_PN = "62";
"CA0_A":   PN = "66"  !CDS_PN = "66";
"CA0_B":   PN = "76"  !CDS_PN = "76";
"CA1_A":   PN = "211"  !CDS_PN = "211";
"CA1_B":   PN = "221"  !CDS_PN = "221";
"CA2_A":   PN = "68"  !CDS_PN = "68";
"CA2_B":   PN = "78"  !CDS_PN = "78";
"CA3_A":   PN = "213"  !CDS_PN = "213";
"CA3_B":   PN = "223"  !CDS_PN = "223";
"CA4_A":   PN = "70"  !CDS_PN = "70";
"CA4_B":   PN = "80"  !CDS_PN = "80";
"CA5_A":   PN = "215"  !CDS_PN = "215";
"CA5_B":   PN = "225"  !CDS_PN = "225";
"CA6_A":   PN = "72"  !CDS_PN = "72";
"CA6_B":   PN = "82"  !CDS_PN = "82";
"CB0_A":   PN = "51"  !CDS_PN = "51";
"CB0_B":   PN = "96"  !CDS_PN = "96";
"CB1_A":   PN = "53"  !CDS_PN = "53";
"CB1_B":   PN = "98"  !CDS_PN = "98";
"CB2_A":   PN = "196"  !CDS_PN = "196";
"CB2_B":   PN = "241"  !CDS_PN = "241";
"CB3_A":   PN = "198"  !CDS_PN = "198";
"CB3_B":   PN = "243"  !CDS_PN = "243";
"CB4_A":   PN = "58"  !CDS_PN = "58";
"CB4_B":   PN = "89"  !CDS_PN = "89";
"CB5_A":   PN = "60"  !CDS_PN = "60";
"CB5_B":   PN = "91"  !CDS_PN = "91";
"CB6_A":   PN = "203"  !CDS_PN = "203";
"CB6_B":   PN = "234"  !CDS_PN = "234";
"CB7_A":   PN = "205"  !CDS_PN = "205";
"CB7_B":   PN = "236"  !CDS_PN = "236";
"CK_C":   PN = "218"  !CDS_PN = "218";
"CK_T":   PN = "217"  !CDS_PN = "217";
"CS0_A_N":   PN = "64"  !CDS_PN = "64";
"CS0_B_N":   PN = "84"  !CDS_PN = "84";
"CS1_A_N":   PN = "209"  !CDS_PN = "209";
"CS1_B_N":   PN = "229"  !CDS_PN = "229";
"DQ0_A":   PN = "7"  !CDS_PN = "7";
"DQ0_B":   PN = "100"  !CDS_PN = "100";
"DQ1_A":   PN = "9"  !CDS_PN = "9";
"DQ1_B":   PN = "102"  !CDS_PN = "102";
"DQ2_A":   PN = "152"  !CDS_PN = "152";
"DQ2_B":   PN = "245"  !CDS_PN = "245";
"DQ3_A":   PN = "154"  !CDS_PN = "154";
"DQ3_B":   PN = "247"  !CDS_PN = "247";
"DQ4_A":   PN = "14"  !CDS_PN = "14";
"DQ4_B":   PN = "107"  !CDS_PN = "107";
"DQ5_A":   PN = "16"  !CDS_PN = "16";
"DQ5_B":   PN = "109"  !CDS_PN = "109";
"DQ6_A":   PN = "159"  !CDS_PN = "159";
"DQ6_B":   PN = "252"  !CDS_PN = "252";
"DQ7_A":   PN = "161"  !CDS_PN = "161";
"DQ7_B":   PN = "254"  !CDS_PN = "254";
"DQ8_A":   PN = "18"  !CDS_PN = "18";
"DQ8_B":   PN = "111"  !CDS_PN = "111";
"DQ9_A":   PN = "20"  !CDS_PN = "20";
"DQ9_B":   PN = "113"  !CDS_PN = "113";
"DQ10_A":   PN = "163"  !CDS_PN = "163";
"DQ10_B":   PN = "256"  !CDS_PN = "256";
"DQ11_A":   PN = "165"  !CDS_PN = "165";
"DQ11_B":   PN = "258"  !CDS_PN = "258";
"DQ12_A":   PN = "25"  !CDS_PN = "25";
"DQ12_B":   PN = "118"  !CDS_PN = "118";
"DQ13_A":   PN = "27"  !CDS_PN = "27";
"DQ13_B":   PN = "120"  !CDS_PN = "120";
"DQ14_A":   PN = "170"  !CDS_PN = "170";
"DQ14_B":   PN = "263"  !CDS_PN = "263";
"DQ15_A":   PN = "172"  !CDS_PN = "172";
"DQ15_B":   PN = "265"  !CDS_PN = "265";
"DQ16_A":   PN = "29"  !CDS_PN = "29";
"DQ16_B":   PN = "122"  !CDS_PN = "122";
"DQ17_A":   PN = "31"  !CDS_PN = "31";
"DQ17_B":   PN = "124"  !CDS_PN = "124";
"DQ18_A":   PN = "174"  !CDS_PN = "174";
"DQ18_B":   PN = "267"  !CDS_PN = "267";
"DQ19_A":   PN = "176"  !CDS_PN = "176";
"DQ19_B":   PN = "269"  !CDS_PN = "269";
"DQ20_A":   PN = "36"  !CDS_PN = "36";
"DQ20_B":   PN = "129"  !CDS_PN = "129";
"DQ21_A":   PN = "38"  !CDS_PN = "38";
"DQ21_B":   PN = "131"  !CDS_PN = "131";
"DQ22_A":   PN = "181"  !CDS_PN = "181";
"DQ22_B":   PN = "274"  !CDS_PN = "274";
"DQ23_A":   PN = "183"  !CDS_PN = "183";
"DQ23_B":   PN = "276"  !CDS_PN = "276";
"DQ24_A":   PN = "40"  !CDS_PN = "40";
"DQ24_B":   PN = "133"  !CDS_PN = "133";
"DQ25_A":   PN = "42"  !CDS_PN = "42";
"DQ25_B":   PN = "135"  !CDS_PN = "135";
"DQ26_A":   PN = "185"  !CDS_PN = "185";
"DQ26_B":   PN = "278"  !CDS_PN = "278";
"DQ27_A":   PN = "187"  !CDS_PN = "187";
"DQ27_B":   PN = "280"  !CDS_PN = "280";
"DQ28_A":   PN = "47"  !CDS_PN = "47";
"DQ28_B":   PN = "140"  !CDS_PN = "140";
"DQ29_A":   PN = "49"  !CDS_PN = "49";
"DQ29_B":   PN = "142"  !CDS_PN = "142";
"DQ30_A":   PN = "192"  !CDS_PN = "192";
"DQ30_B":   PN = "285"  !CDS_PN = "285";
"DQ31_A":   PN = "194"  !CDS_PN = "194";
"DQ31_B":   PN = "287"  !CDS_PN = "287";
"HSA":   PN = "148"  !CDS_PN = "148";
"HSCL":   PN = "4"  !CDS_PN = "4";
"HSDA":   PN = "5"  !CDS_PN = "5";
"LBD||RSP_A_N":   PN = "86"  !CDS_PN = "86";
"LBS||RSP_B_N":   PN = "87"  !CDS_PN = "87";
"PAR_A":   PN = "74"  !CDS_PN = "74";
"PAR_B":   PN = "227"  !CDS_PN = "227";
"PWR_GOOD||FAIL_N":   PN = "147"  !CDS_PN = "147";
"RESET_N":   PN = "207"  !CDS_PN = "207";
"RFU0":   PN = "2"  !CDS_PN = "2";
"RFU1":   PN = "144"  !CDS_PN = "144";
"RFU2":   PN = "149"  !CDS_PN = "149";
"RFU3":   PN = "150"  !CDS_PN = "150";
"RFU4":   PN = "220"  !CDS_PN = "220";
"RFU5":   PN = "231"  !CDS_PN = "231";
"RFU6":   PN = "232"  !CDS_PN = "232";
"VIN_MGMT":   PN = "3"  !CDS_PN = "3";
BODY = "Q_CAP","I121": LOCATION = "C23" #&CDS_LOCATION = "C23" &SEC = "1" #&CDS_SEC = "1";
"A":   PN = "1"  !CDS_PN = "1";
"B":   PN = "2"  !CDS_PN = "2";
BODY = "Q_CAP","I125": LOCATION = "C24" #&CDS_LOCATION = "C24" &SEC = "1" #&CDS_SEC = "1";
"A":   PN = "1"  !CDS_PN = "1";
"B":   PN = "2"  !CDS_PN = "2";
BODY = "Q_CAP","I127": LOCATION = "C25" #&CDS_LOCATION = "C25" &SEC = "1" #&CDS_SEC = "1";
"A":   PN = "1"  !CDS_PN = "1";
"B":   PN = "2"  !CDS_PN = "2";
BODY = "SCONN288_ADR50017P087CC","I175": LOCATION = "J8" #&CDS_LOCATION = "J8" &SEC = "3" #&CDS_SEC = "3";
"G1":   PN = "G1"  !CDS_PN = "G1";
"G2":   PN = "G2"  !CDS_PN = "G2";
"G3":   PN = "G3"  !CDS_PN = "G3";
"VIN_BULK0":   PN = "1"  !CDS_PN = "1";
"VIN_BULK1":   PN = "145"  !CDS_PN = "145";
"VIN_BULK2":   PN = "146"  !CDS_PN = "146";
"VSS0":   PN = "6"  !CDS_PN = "6";
"VSS1":   PN = "8"  !CDS_PN = "8";
"VSS2":   PN = "10"  !CDS_PN = "10";
"VSS3":   PN = "13"  !CDS_PN = "13";
"VSS4":   PN = "15"  !CDS_PN = "15";
"VSS5":   PN = "17"  !CDS_PN = "17";
"VSS6":   PN = "19"  !CDS_PN = "19";
"VSS7":   PN = "21"  !CDS_PN = "21";
"VSS8":   PN = "24"  !CDS_PN = "24";
"VSS9":   PN = "26"  !CDS_PN = "26";
"VSS10":   PN = "28"  !CDS_PN = "28";
"VSS11":   PN = "30"  !CDS_PN = "30";
"VSS12":   PN = "32"  !CDS_PN = "32";
"VSS13":   PN = "35"  !CDS_PN = "35";
"VSS14":   PN = "37"  !CDS_PN = "37";
"VSS15":   PN = "39"  !CDS_PN = "39";
"VSS16":   PN = "41"  !CDS_PN = "41";
"VSS17":   PN = "43"  !CDS_PN = "43";
"VSS18":   PN = "46"  !CDS_PN = "46";
"VSS19":   PN = "48"  !CDS_PN = "48";
"VSS20":   PN = "50"  !CDS_PN = "50";
"VSS21":   PN = "52"  !CDS_PN = "52";
"VSS22":   PN = "54"  !CDS_PN = "54";
"VSS23":   PN = "57"  !CDS_PN = "57";
"VSS24":   PN = "59"  !CDS_PN = "59";
"VSS25":   PN = "61"  !CDS_PN = "61";
"VSS26":   PN = "63"  !CDS_PN = "63";
"VSS27":   PN = "65"  !CDS_PN = "65";
"VSS28":   PN = "67"  !CDS_PN = "67";
"VSS29":   PN = "69"  !CDS_PN = "69";
"VSS30":   PN = "71"  !CDS_PN = "71";
"VSS31":   PN = "73"  !CDS_PN = "73";
"VSS32":   PN = "75"  !CDS_PN = "75";
"VSS33":   PN = "77"  !CDS_PN = "77";
"VSS34":   PN = "79"  !CDS_PN = "79";
"VSS35":   PN = "81"  !CDS_PN = "81";
"VSS36":   PN = "83"  !CDS_PN = "83";
"VSS37":   PN = "85"  !CDS_PN = "85";
"VSS38":   PN = "88"  !CDS_PN = "88";
"VSS39":   PN = "90"  !CDS_PN = "90";
"VSS40":   PN = "92"  !CDS_PN = "92";
"VSS41":   PN = "95"  !CDS_PN = "95";
"VSS42":   PN = "97"  !CDS_PN = "97";
"VSS43":   PN = "99"  !CDS_PN = "99";
"VSS44":   PN = "101"  !CDS_PN = "101";
"VSS45":   PN = "103"  !CDS_PN = "103";
"VSS46":   PN = "106"  !CDS_PN = "106";
"VSS47":   PN = "108"  !CDS_PN = "108";
"VSS48":   PN = "110"  !CDS_PN = "110";
"VSS49":   PN = "112"  !CDS_PN = "112";
"VSS50":   PN = "114"  !CDS_PN = "114";
"VSS51":   PN = "117"  !CDS_PN = "117";
"VSS52":   PN = "119"  !CDS_PN = "119";
"VSS53":   PN = "121"  !CDS_PN = "121";
"VSS54":   PN = "123"  !CDS_PN = "123";
"VSS55":   PN = "125"  !CDS_PN = "125";
"VSS56":   PN = "128"  !CDS_PN = "128";
"VSS57":   PN = "130"  !CDS_PN = "130";
"VSS58":   PN = "132"  !CDS_PN = "132";
"VSS59":   PN = "134"  !CDS_PN = "134";
"VSS60":   PN = "136"  !CDS_PN = "136";
"VSS61":   PN = "139"  !CDS_PN = "139";
"VSS62":   PN = "141"  !CDS_PN = "141";
"VSS63":   PN = "143"  !CDS_PN = "143";
"VSS64":   PN = "151"  !CDS_PN = "151";
"VSS65":   PN = "153"  !CDS_PN = "153";
"VSS66":   PN = "155"  !CDS_PN = "155";
"VSS67":   PN = "158"  !CDS_PN = "158";
"VSS68":   PN = "160"  !CDS_PN = "160";
"VSS69":   PN = "162"  !CDS_PN = "162";
"VSS70":   PN = "164"  !CDS_PN = "164";
"VSS71":   PN = "166"  !CDS_PN = "166";
"VSS72":   PN = "169"  !CDS_PN = "169";
"VSS73":   PN = "171"  !CDS_PN = "171";
"VSS74":   PN = "173"  !CDS_PN = "173";
"VSS75":   PN = "175"  !CDS_PN = "175";
"VSS76":   PN = "177"  !CDS_PN = "177";
"VSS77":   PN = "180"  !CDS_PN = "180";
"VSS78":   PN = "182"  !CDS_PN = "182";
"VSS79":   PN = "184"  !CDS_PN = "184";
"VSS80":   PN = "186"  !CDS_PN = "186";
"VSS81":   PN = "188"  !CDS_PN = "188";
"VSS82":   PN = "191"  !CDS_PN = "191";
"VSS83":   PN = "193"  !CDS_PN = "193";
"VSS84":   PN = "195"  !CDS_PN = "195";
"VSS85":   PN = "197"  !CDS_PN = "197";
"VSS86":   PN = "199"  !CDS_PN = "199";
"VSS87":   PN = "202"  !CDS_PN = "202";
"VSS88":   PN = "204"  !CDS_PN = "204";
"VSS89":   PN = "206"  !CDS_PN = "206";
"VSS90":   PN = "208"  !CDS_PN = "208";
"VSS91":   PN = "210"  !CDS_PN = "210";
"VSS92":   PN = "212"  !CDS_PN = "212";
"VSS93":   PN = "214"  !CDS_PN = "214";
"VSS94":   PN = "216"  !CDS_PN = "216";
"VSS95":   PN = "219"  !CDS_PN = "219";
"VSS96":   PN = "222"  !CDS_PN = "222";
"VSS97":   PN = "224"  !CDS_PN = "224";
"VSS98":   PN = "226"  !CDS_PN = "226";
"VSS99":   PN = "228"  !CDS_PN = "228";
"VSS100":   PN = "230"  !CDS_PN = "230";
"VSS101":   PN = "233"  !CDS_PN = "233";
"VSS102":   PN = "235"  !CDS_PN = "235";
"VSS103":   PN = "237"  !CDS_PN = "237";
"VSS104":   PN = "240"  !CDS_PN = "240";
"VSS105":   PN = "242"  !CDS_PN = "242";
"VSS106":   PN = "244"  !CDS_PN = "244";
"VSS107":   PN = "246"  !CDS_PN = "246";
"VSS108":   PN = "248"  !CDS_PN = "248";
"VSS109":   PN = "251"  !CDS_PN = "251";
"VSS110":   PN = "253"  !CDS_PN = "253";
"VSS111":   PN = "255"  !CDS_PN = "255";
"VSS112":   PN = "257"  !CDS_PN = "257";
"VSS113":   PN = "259"  !CDS_PN = "259";
"VSS114":   PN = "262"  !CDS_PN = "262";
"VSS115":   PN = "264"  !CDS_PN = "264";
"VSS116":   PN = "266"  !CDS_PN = "266";
"VSS117":   PN = "268"  !CDS_PN = "268";
"VSS118":   PN = "270"  !CDS_PN = "270";
"VSS119":   PN = "273"  !CDS_PN = "273";
"VSS120":   PN = "275"  !CDS_PN = "275";
"VSS121":   PN = "277"  !CDS_PN = "277";
"VSS122":   PN = "279"  !CDS_PN = "279";
"VSS123":   PN = "281"  !CDS_PN = "281";
"VSS124":   PN = "284"  !CDS_PN = "284";
"VSS125":   PN = "286"  !CDS_PN = "286";
"VSS126":   PN = "288"  !CDS_PN = "288";
BODY = "SCONN288_ADR50017P087CC","I178": #LOCATION = "J8" !CDS_LOCATION = "J8" &SEC = "2" #&CDS_SEC = "2";
"DQS0_A_C":   PN = "12"  !CDS_PN = "12";
"DQS0_A_T":   PN = "11"  !CDS_PN = "11";
"DQS0_B_C":   PN = "105"  !CDS_PN = "105";
"DQS0_B_T":   PN = "104"  !CDS_PN = "104";
"DQS1_A_C":   PN = "23"  !CDS_PN = "23";
"DQS1_A_T":   PN = "22"  !CDS_PN = "22";
"DQS1_B_C":   PN = "116"  !CDS_PN = "116";
"DQS1_B_T":   PN = "115"  !CDS_PN = "115";
"DQS2_A_C":   PN = "34"  !CDS_PN = "34";
"DQS2_A_T":   PN = "33"  !CDS_PN = "33";
"DQS2_B_C":   PN = "127"  !CDS_PN = "127";
"DQS2_B_T":   PN = "126"  !CDS_PN = "126";
"DQS3_A_C":   PN = "45"  !CDS_PN = "45";
"DQS3_A_T":   PN = "44"  !CDS_PN = "44";
"DQS3_B_C":   PN = "138"  !CDS_PN = "138";
"DQS3_B_T":   PN = "137"  !CDS_PN = "137";
"DQS4_A_C":   PN = "56"  !CDS_PN = "56";
"DQS4_A_T":   PN = "55"  !CDS_PN = "55";
"DQS4_B_C":   PN = "238"  !CDS_PN = "238";
"DQS4_B_T":   PN = "239"  !CDS_PN = "239";
"DQS5_A_C||TDQS5_A_C||DQS5_A_T||TDQS5_A_T":   PN = "156"  !CDS_PN = "156";
"DQS5_A_T||TDQS5_A_T":   PN = "157"  !CDS_PN = "157";
"DQS5_B_C||TDQS5_B_C":   PN = "249"  !CDS_PN = "249";
"DQS5_B_T||TDQS5_B_T":   PN = "250"  !CDS_PN = "250";
"DQS6_A_C||TDQS6_A_C||DQS6_A_T||TDQS6_A_T":   PN = "167"  !CDS_PN = "167";
"DQS6_A_T||TDQS6_A_T":   PN = "168"  !CDS_PN = "168";
"DQS6_B_C||TDQS6_B_C":   PN = "260"  !CDS_PN = "260";
"DQS6_B_T||TDQS6_B_T":   PN = "261"  !CDS_PN = "261";
"DQS7_A_C||TDQS7_A_C":   PN = "178"  !CDS_PN = "178";
"DQS7_A_T||TDQS7_A_T":   PN = "179"  !CDS_PN = "179";
"DQS7_B_C||TDQS7_B_C":   PN = "271"  !CDS_PN = "271";
"DQS7_B_T||TDQS7_B_T":   PN = "272"  !CDS_PN = "272";
"DQS8_A_C||TDQS8_A_C":   PN = "189"  !CDS_PN = "189";
"DQS8_A_T||TDQS8_A_T":   PN = "190"  !CDS_PN = "190";
"DQS8_B_C||TDQS8_B_C":   PN = "282"  !CDS_PN = "282";
"DQS8_B_T||TDQS8_B_T":   PN = "283"  !CDS_PN = "283";
"DQS9_A_C||TDQS9_A_C":   PN = "200"  !CDS_PN = "200";
"DQS9_A_T||TDQS9_A_T":   PN = "201"  !CDS_PN = "201";
"DQS9_B_C||TDQS9_B_C":   PN = "94"  !CDS_PN = "94";
"DQS9_B_T||TDQS9_B_T||DBI4_B_N":   PN = "93"  !CDS_PN = "93";
BODY = "Q_RES","I180": LOCATION = "R3882" #&CDS_LOCATION = "R3882" &SEC = "1" #&CDS_SEC = "1";
"A":   PN = "1"  !CDS_PN = "1";
"B":   PN = "2"  !CDS_PN = "2";
DRAWING = "@s9s_mb_2u_lib.s9s_mb_2u(sch_1):page90";
BODY = "Q_RES","I11": LOCATION = "R34" #&CDS_LOCATION = "R34" &SEC = "1" #&CDS_SEC = "1";
"A":   PN = "1"  !CDS_PN = "1";
"B":   PN = "2"  !CDS_PN = "2";
BODY = "SCONN288_ADR50017P130CC","I12": LOCATION = "J9" #&CDS_LOCATION = "J9" &SEC = "1" #&CDS_SEC = "1";
"ALERT_N":   PN = "62"  !CDS_PN = "62";
"CA0_A":   PN = "66"  !CDS_PN = "66";
"CA0_B":   PN = "76"  !CDS_PN = "76";
"CA1_A":   PN = "211"  !CDS_PN = "211";
"CA1_B":   PN = "221"  !CDS_PN = "221";
"CA2_A":   PN = "68"  !CDS_PN = "68";
"CA2_B":   PN = "78"  !CDS_PN = "78";
"CA3_A":   PN = "213"  !CDS_PN = "213";
"CA3_B":   PN = "223"  !CDS_PN = "223";
"CA4_A":   PN = "70"  !CDS_PN = "70";
"CA4_B":   PN = "80"  !CDS_PN = "80";
"CA5_A":   PN = "215"  !CDS_PN = "215";
"CA5_B":   PN = "225"  !CDS_PN = "225";
"CA6_A":   PN = "72"  !CDS_PN = "72";
"CA6_B":   PN = "82"  !CDS_PN = "82";
"CB0_A":   PN = "51"  !CDS_PN = "51";
"CB0_B":   PN = "96"  !CDS_PN = "96";
"CB1_A":   PN = "53"  !CDS_PN = "53";
"CB1_B":   PN = "98"  !CDS_PN = "98";
"CB2_A":   PN = "196"  !CDS_PN = "196";
"CB2_B":   PN = "241"  !CDS_PN = "241";
"CB3_A":   PN = "198"  !CDS_PN = "198";
"CB3_B":   PN = "243"  !CDS_PN = "243";
"CB4_A":   PN = "58"  !CDS_PN = "58";
"CB4_B":   PN = "89"  !CDS_PN = "89";
"CB5_A":   PN = "60"  !CDS_PN = "60";
"CB5_B":   PN = "91"  !CDS_PN = "91";
"CB6_A":   PN = "203"  !CDS_PN = "203";
"CB6_B":   PN = "234"  !CDS_PN = "234";
"CB7_A":   PN = "205"  !CDS_PN = "205";
"CB7_B":   PN = "236"  !CDS_PN = "236";
"CK_C":   PN = "218"  !CDS_PN = "218";
"CK_T":   PN = "217"  !CDS_PN = "217";
"CS0_A_N":   PN = "64"  !CDS_PN = "64";
"CS0_B_N":   PN = "84"  !CDS_PN = "84";
"CS1_A_N":   PN = "209"  !CDS_PN = "209";
"CS1_B_N":   PN = "229"  !CDS_PN = "229";
"DQ0_A":   PN = "7"  !CDS_PN = "7";
"DQ0_B":   PN = "100"  !CDS_PN = "100";
"DQ1_A":   PN = "9"  !CDS_PN = "9";
"DQ1_B":   PN = "102"  !CDS_PN = "102";
"DQ2_A":   PN = "152"  !CDS_PN = "152";
"DQ2_B":   PN = "245"  !CDS_PN = "245";
"DQ3_A":   PN = "154"  !CDS_PN = "154";
"DQ3_B":   PN = "247"  !CDS_PN = "247";
"DQ4_A":   PN = "14"  !CDS_PN = "14";
"DQ4_B":   PN = "107"  !CDS_PN = "107";
"DQ5_A":   PN = "16"  !CDS_PN = "16";
"DQ5_B":   PN = "109"  !CDS_PN = "109";
"DQ6_A":   PN = "159"  !CDS_PN = "159";
"DQ6_B":   PN = "252"  !CDS_PN = "252";
"DQ7_A":   PN = "161"  !CDS_PN = "161";
"DQ7_B":   PN = "254"  !CDS_PN = "254";
"DQ8_A":   PN = "18"  !CDS_PN = "18";
"DQ8_B":   PN = "111"  !CDS_PN = "111";
"DQ9_A":   PN = "20"  !CDS_PN = "20";
"DQ9_B":   PN = "113"  !CDS_PN = "113";
"DQ10_A":   PN = "163"  !CDS_PN = "163";
"DQ10_B":   PN = "256"  !CDS_PN = "256";
"DQ11_A":   PN = "165"  !CDS_PN = "165";
"DQ11_B":   PN = "258"  !CDS_PN = "258";
"DQ12_A":   PN = "25"  !CDS_PN = "25";
"DQ12_B":   PN = "118"  !CDS_PN = "118";
"DQ13_A":   PN = "27"  !CDS_PN = "27";
"DQ13_B":   PN = "120"  !CDS_PN = "120";
"DQ14_A":   PN = "170"  !CDS_PN = "170";
"DQ14_B":   PN = "263"  !CDS_PN = "263";
"DQ15_A":   PN = "172"  !CDS_PN = "172";
"DQ15_B":   PN = "265"  !CDS_PN = "265";
"DQ16_A":   PN = "29"  !CDS_PN = "29";
"DQ16_B":   PN = "122"  !CDS_PN = "122";
"DQ17_A":   PN = "31"  !CDS_PN = "31";
"DQ17_B":   PN = "124"  !CDS_PN = "124";
"DQ18_A":   PN = "174"  !CDS_PN = "174";
"DQ18_B":   PN = "267"  !CDS_PN = "267";
"DQ19_A":   PN = "176"  !CDS_PN = "176";
"DQ19_B":   PN = "269"  !CDS_PN = "269";
"DQ20_A":   PN = "36"  !CDS_PN = "36";
"DQ20_B":   PN = "129"  !CDS_PN = "129";
"DQ21_A":   PN = "38"  !CDS_PN = "38";
"DQ21_B":   PN = "131"  !CDS_PN = "131";
"DQ22_A":   PN = "181"  !CDS_PN = "181";
"DQ22_B":   PN = "274"  !CDS_PN = "274";
"DQ23_A":   PN = "183"  !CDS_PN = "183";
"DQ23_B":   PN = "276"  !CDS_PN = "276";
"DQ24_A":   PN = "40"  !CDS_PN = "40";
"DQ24_B":   PN = "133"  !CDS_PN = "133";
"DQ25_A":   PN = "42"  !CDS_PN = "42";
"DQ25_B":   PN = "135"  !CDS_PN = "135";
"DQ26_A":   PN = "185"  !CDS_PN = "185";
"DQ26_B":   PN = "278"  !CDS_PN = "278";
"DQ27_A":   PN = "187"  !CDS_PN = "187";
"DQ27_B":   PN = "280"  !CDS_PN = "280";
"DQ28_A":   PN = "47"  !CDS_PN = "47";
"DQ28_B":   PN = "140"  !CDS_PN = "140";
"DQ29_A":   PN = "49"  !CDS_PN = "49";
"DQ29_B":   PN = "142"  !CDS_PN = "142";
"DQ30_A":   PN = "192"  !CDS_PN = "192";
"DQ30_B":   PN = "285"  !CDS_PN = "285";
"DQ31_A":   PN = "194"  !CDS_PN = "194";
"DQ31_B":   PN = "287"  !CDS_PN = "287";
"HSA":   PN = "148"  !CDS_PN = "148";
"HSCL":   PN = "4"  !CDS_PN = "4";
"HSDA":   PN = "5"  !CDS_PN = "5";
"LBD||RSP_A_N":   PN = "86"  !CDS_PN = "86";
"LBS||RSP_B_N":   PN = "87"  !CDS_PN = "87";
"PAR_A":   PN = "74"  !CDS_PN = "74";
"PAR_B":   PN = "227"  !CDS_PN = "227";
"PWR_GOOD||FAIL_N":   PN = "147"  !CDS_PN = "147";
"RESET_N":   PN = "207"  !CDS_PN = "207";
"RFU0":   PN = "2"  !CDS_PN = "2";
"RFU1":   PN = "144"  !CDS_PN = "144";
"RFU2":   PN = "149"  !CDS_PN = "149";
"RFU3":   PN = "150"  !CDS_PN = "150";
"RFU4":   PN = "220"  !CDS_PN = "220";
"RFU5":   PN = "231"  !CDS_PN = "231";
"RFU6":   PN = "232"  !CDS_PN = "232";
"VIN_MGMT":   PN = "3"  !CDS_PN = "3";
BODY = "Q_CAP","I122": LOCATION = "C26" #&CDS_LOCATION = "C26" &SEC = "1" #&CDS_SEC = "1";
"A":   PN = "1"  !CDS_PN = "1";
"B":   PN = "2"  !CDS_PN = "2";
BODY = "Q_CAP","I123": LOCATION = "C27" #&CDS_LOCATION = "C27" &SEC = "1" #&CDS_SEC = "1";
"A":   PN = "1"  !CDS_PN = "1";
"B":   PN = "2"  !CDS_PN = "2";
BODY = "Q_CAP","I145": LOCATION = "C28" #&CDS_LOCATION = "C28" &SEC = "1" #&CDS_SEC = "1";
"A":   PN = "1"  !CDS_PN = "1";
"B":   PN = "2"  !CDS_PN = "2";
BODY = "SCONN288_ADR50017P130CC","I147": LOCATION = "J9" #&CDS_LOCATION = "J9" &SEC = "3" #&CDS_SEC = "3";
"G1":   PN = "G1"  !CDS_PN = "G1";
"G2":   PN = "G2"  !CDS_PN = "G2";
"G3":   PN = "G3"  !CDS_PN = "G3";
"VIN_BULK0":   PN = "1"  !CDS_PN = "1";
"VIN_BULK1":   PN = "145"  !CDS_PN = "145";
"VIN_BULK2":   PN = "146"  !CDS_PN = "146";
"VSS0":   PN = "6"  !CDS_PN = "6";
"VSS1":   PN = "8"  !CDS_PN = "8";
"VSS2":   PN = "10"  !CDS_PN = "10";
"VSS3":   PN = "13"  !CDS_PN = "13";
"VSS4":   PN = "15"  !CDS_PN = "15";
"VSS5":   PN = "17"  !CDS_PN = "17";
"VSS6":   PN = "19"  !CDS_PN = "19";
"VSS7":   PN = "21"  !CDS_PN = "21";
"VSS8":   PN = "24"  !CDS_PN = "24";
"VSS9":   PN = "26"  !CDS_PN = "26";
"VSS10":   PN = "28"  !CDS_PN = "28";
"VSS11":   PN = "30"  !CDS_PN = "30";
"VSS12":   PN = "32"  !CDS_PN = "32";
"VSS13":   PN = "35"  !CDS_PN = "35";
"VSS14":   PN = "37"  !CDS_PN = "37";
"VSS15":   PN = "39"  !CDS_PN = "39";
"VSS16":   PN = "41"  !CDS_PN = "41";
"VSS17":   PN = "43"  !CDS_PN = "43";
"VSS18":   PN = "46"  !CDS_PN = "46";
"VSS19":   PN = "48"  !CDS_PN = "48";
"VSS20":   PN = "50"  !CDS_PN = "50";
"VSS21":   PN = "52"  !CDS_PN = "52";
"VSS22":   PN = "54"  !CDS_PN = "54";
"VSS23":   PN = "57"  !CDS_PN = "57";
"VSS24":   PN = "59"  !CDS_PN = "59";
"VSS25":   PN = "61"  !CDS_PN = "61";
"VSS26":   PN = "63"  !CDS_PN = "63";
"VSS27":   PN = "65"  !CDS_PN = "65";
"VSS28":   PN = "67"  !CDS_PN = "67";
"VSS29":   PN = "69"  !CDS_PN = "69";
"VSS30":   PN = "71"  !CDS_PN = "71";
"VSS31":   PN = "73"  !CDS_PN = "73";
"VSS32":   PN = "75"  !CDS_PN = "75";
"VSS33":   PN = "77"  !CDS_PN = "77";
"VSS34":   PN = "79"  !CDS_PN = "79";
"VSS35":   PN = "81"  !CDS_PN = "81";
"VSS36":   PN = "83"  !CDS_PN = "83";
"VSS37":   PN = "85"  !CDS_PN = "85";
"VSS38":   PN = "88"  !CDS_PN = "88";
"VSS39":   PN = "90"  !CDS_PN = "90";
"VSS40":   PN = "92"  !CDS_PN = "92";
"VSS41":   PN = "95"  !CDS_PN = "95";
"VSS42":   PN = "97"  !CDS_PN = "97";
"VSS43":   PN = "99"  !CDS_PN = "99";
"VSS44":   PN = "101"  !CDS_PN = "101";
"VSS45":   PN = "103"  !CDS_PN = "103";
"VSS46":   PN = "106"  !CDS_PN = "106";
"VSS47":   PN = "108"  !CDS_PN = "108";
"VSS48":   PN = "110"  !CDS_PN = "110";
"VSS49":   PN = "112"  !CDS_PN = "112";
"VSS50":   PN = "114"  !CDS_PN = "114";
"VSS51":   PN = "117"  !CDS_PN = "117";
"VSS52":   PN = "119"  !CDS_PN = "119";
"VSS53":   PN = "121"  !CDS_PN = "121";
"VSS54":   PN = "123"  !CDS_PN = "123";
"VSS55":   PN = "125"  !CDS_PN = "125";
"VSS56":   PN = "128"  !CDS_PN = "128";
"VSS57":   PN = "130"  !CDS_PN = "130";
"VSS58":   PN = "132"  !CDS_PN = "132";
"VSS59":   PN = "134"  !CDS_PN = "134";
"VSS60":   PN = "136"  !CDS_PN = "136";
"VSS61":   PN = "139"  !CDS_PN = "139";
"VSS62":   PN = "141"  !CDS_PN = "141";
"VSS63":   PN = "143"  !CDS_PN = "143";
"VSS64":   PN = "151"  !CDS_PN = "151";
"VSS65":   PN = "153"  !CDS_PN = "153";
"VSS66":   PN = "155"  !CDS_PN = "155";
"VSS67":   PN = "158"  !CDS_PN = "158";
"VSS68":   PN = "160"  !CDS_PN = "160";
"VSS69":   PN = "162"  !CDS_PN = "162";
"VSS70":   PN = "164"  !CDS_PN = "164";
"VSS71":   PN = "166"  !CDS_PN = "166";
"VSS72":   PN = "169"  !CDS_PN = "169";
"VSS73":   PN = "171"  !CDS_PN = "171";
"VSS74":   PN = "173"  !CDS_PN = "173";
"VSS75":   PN = "175"  !CDS_PN = "175";
"VSS76":   PN = "177"  !CDS_PN = "177";
"VSS77":   PN = "180"  !CDS_PN = "180";
"VSS78":   PN = "182"  !CDS_PN = "182";
"VSS79":   PN = "184"  !CDS_PN = "184";
"VSS80":   PN = "186"  !CDS_PN = "186";
"VSS81":   PN = "188"  !CDS_PN = "188";
"VSS82":   PN = "191"  !CDS_PN = "191";
"VSS83":   PN = "193"  !CDS_PN = "193";
"VSS84":   PN = "195"  !CDS_PN = "195";
"VSS85":   PN = "197"  !CDS_PN = "197";
"VSS86":   PN = "199"  !CDS_PN = "199";
"VSS87":   PN = "202"  !CDS_PN = "202";
"VSS88":   PN = "204"  !CDS_PN = "204";
"VSS89":   PN = "206"  !CDS_PN = "206";
"VSS90":   PN = "208"  !CDS_PN = "208";
"VSS91":   PN = "210"  !CDS_PN = "210";
"VSS92":   PN = "212"  !CDS_PN = "212";
"VSS93":   PN = "214"  !CDS_PN = "214";
"VSS94":   PN = "216"  !CDS_PN = "216";
"VSS95":   PN = "219"  !CDS_PN = "219";
"VSS96":   PN = "222"  !CDS_PN = "222";
"VSS97":   PN = "224"  !CDS_PN = "224";
"VSS98":   PN = "226"  !CDS_PN = "226";
"VSS99":   PN = "228"  !CDS_PN = "228";
"VSS100":   PN = "230"  !CDS_PN = "230";
"VSS101":   PN = "233"  !CDS_PN = "233";
"VSS102":   PN = "235"  !CDS_PN = "235";
"VSS103":   PN = "237"  !CDS_PN = "237";
"VSS104":   PN = "240"  !CDS_PN = "240";
"VSS105":   PN = "242"  !CDS_PN = "242";
"VSS106":   PN = "244"  !CDS_PN = "244";
"VSS107":   PN = "246"  !CDS_PN = "246";
"VSS108":   PN = "248"  !CDS_PN = "248";
"VSS109":   PN = "251"  !CDS_PN = "251";
"VSS110":   PN = "253"  !CDS_PN = "253";
"VSS111":   PN = "255"  !CDS_PN = "255";
"VSS112":   PN = "257"  !CDS_PN = "257";
"VSS113":   PN = "259"  !CDS_PN = "259";
"VSS114":   PN = "262"  !CDS_PN = "262";
"VSS115":   PN = "264"  !CDS_PN = "264";
"VSS116":   PN = "266"  !CDS_PN = "266";
"VSS117":   PN = "268"  !CDS_PN = "268";
"VSS118":   PN = "270"  !CDS_PN = "270";
"VSS119":   PN = "273"  !CDS_PN = "273";
"VSS120":   PN = "275"  !CDS_PN = "275";
"VSS121":   PN = "277"  !CDS_PN = "277";
"VSS122":   PN = "279"  !CDS_PN = "279";
"VSS123":   PN = "281"  !CDS_PN = "281";
"VSS124":   PN = "284"  !CDS_PN = "284";
"VSS125":   PN = "286"  !CDS_PN = "286";
"VSS126":   PN = "288"  !CDS_PN = "288";
BODY = "SCONN288_ADR50017P130CC","I178": #LOCATION = "J9" !CDS_LOCATION = "J9" &SEC = "2" #&CDS_SEC = "2";
"DQS0_A_C":   PN = "12"  !CDS_PN = "12";
"DQS0_A_T":   PN = "11"  !CDS_PN = "11";
"DQS0_B_C":   PN = "105"  !CDS_PN = "105";
"DQS0_B_T":   PN = "104"  !CDS_PN = "104";
"DQS1_A_C":   PN = "23"  !CDS_PN = "23";
"DQS1_A_T":   PN = "22"  !CDS_PN = "22";
"DQS1_B_C":   PN = "116"  !CDS_PN = "116";
"DQS1_B_T":   PN = "115"  !CDS_PN = "115";
"DQS2_A_C":   PN = "34"  !CDS_PN = "34";
"DQS2_A_T":   PN = "33"  !CDS_PN = "33";
"DQS2_B_C":   PN = "127"  !CDS_PN = "127";
"DQS2_B_T":   PN = "126"  !CDS_PN = "126";
"DQS3_A_C":   PN = "45"  !CDS_PN = "45";
"DQS3_A_T":   PN = "44"  !CDS_PN = "44";
"DQS3_B_C":   PN = "138"  !CDS_PN = "138";
"DQS3_B_T":   PN = "137"  !CDS_PN = "137";
"DQS4_A_C":   PN = "56"  !CDS_PN = "56";
"DQS4_A_T":   PN = "55"  !CDS_PN = "55";
"DQS4_B_C":   PN = "238"  !CDS_PN = "238";
"DQS4_B_T":   PN = "239"  !CDS_PN = "239";
"DQS5_A_C||TDQS5_A_C||DQS5_A_T||TDQS5_A_T":   PN = "156"  !CDS_PN = "156";
"DQS5_A_T||TDQS5_A_T":   PN = "157"  !CDS_PN = "157";
"DQS5_B_C||TDQS5_B_C":   PN = "249"  !CDS_PN = "249";
"DQS5_B_T||TDQS5_B_T":   PN = "250"  !CDS_PN = "250";
"DQS6_A_C||TDQS6_A_C||DQS6_A_T||TDQS6_A_T":   PN = "167"  !CDS_PN = "167";
"DQS6_A_T||TDQS6_A_T":   PN = "168"  !CDS_PN = "168";
"DQS6_B_C||TDQS6_B_C":   PN = "260"  !CDS_PN = "260";
"DQS6_B_T||TDQS6_B_T":   PN = "261"  !CDS_PN = "261";
"DQS7_A_C||TDQS7_A_C":   PN = "178"  !CDS_PN = "178";
"DQS7_A_T||TDQS7_A_T":   PN = "179"  !CDS_PN = "179";
"DQS7_B_C||TDQS7_B_C":   PN = "271"  !CDS_PN = "271";
"DQS7_B_T||TDQS7_B_T":   PN = "272"  !CDS_PN = "272";
"DQS8_A_C||TDQS8_A_C":   PN = "189"  !CDS_PN = "189";
"DQS8_A_T||TDQS8_A_T":   PN = "190"  !CDS_PN = "190";
"DQS8_B_C||TDQS8_B_C":   PN = "282"  !CDS_PN = "282";
"DQS8_B_T||TDQS8_B_T":   PN = "283"  !CDS_PN = "283";
"DQS9_A_C||TDQS9_A_C":   PN = "200"  !CDS_PN = "200";
"DQS9_A_T||TDQS9_A_T":   PN = "201"  !CDS_PN = "201";
"DQS9_B_C||TDQS9_B_C":   PN = "94"  !CDS_PN = "94";
"DQS9_B_T||TDQS9_B_T||DBI4_B_N":   PN = "93"  !CDS_PN = "93";
BODY = "Q_RES","I179": LOCATION = "R3883" #&CDS_LOCATION = "R3883" &SEC = "1" #&CDS_SEC = "1";
"A":   PN = "1"  !CDS_PN = "1";
"B":   PN = "2"  !CDS_PN = "2";
DRAWING = "@s9s_mb_2u_lib.s9s_mb_2u(sch_1):page91";
BODY = "Q_RES","I2": LOCATION = "R35" #&CDS_LOCATION = "R35" &SEC = "1" #&CDS_SEC = "1";
"A":   PN = "1"  !CDS_PN = "1";
"B":   PN = "2"  !CDS_PN = "2";
BODY = "SCONN288_ADR50017P087CC","I13": LOCATION = "J10" #&CDS_LOCATION = "J10" &SEC = "1" #&CDS_SEC = "1";
"ALERT_N":   PN = "62"  !CDS_PN = "62";
"CA0_A":   PN = "66"  !CDS_PN = "66";
"CA0_B":   PN = "76"  !CDS_PN = "76";
"CA1_A":   PN = "211"  !CDS_PN = "211";
"CA1_B":   PN = "221"  !CDS_PN = "221";
"CA2_A":   PN = "68"  !CDS_PN = "68";
"CA2_B":   PN = "78"  !CDS_PN = "78";
"CA3_A":   PN = "213"  !CDS_PN = "213";
"CA3_B":   PN = "223"  !CDS_PN = "223";
"CA4_A":   PN = "70"  !CDS_PN = "70";
"CA4_B":   PN = "80"  !CDS_PN = "80";
"CA5_A":   PN = "215"  !CDS_PN = "215";
"CA5_B":   PN = "225"  !CDS_PN = "225";
"CA6_A":   PN = "72"  !CDS_PN = "72";
"CA6_B":   PN = "82"  !CDS_PN = "82";
"CB0_A":   PN = "51"  !CDS_PN = "51";
"CB0_B":   PN = "96"  !CDS_PN = "96";
"CB1_A":   PN = "53"  !CDS_PN = "53";
"CB1_B":   PN = "98"  !CDS_PN = "98";
"CB2_A":   PN = "196"  !CDS_PN = "196";
"CB2_B":   PN = "241"  !CDS_PN = "241";
"CB3_A":   PN = "198"  !CDS_PN = "198";
"CB3_B":   PN = "243"  !CDS_PN = "243";
"CB4_A":   PN = "58"  !CDS_PN = "58";
"CB4_B":   PN = "89"  !CDS_PN = "89";
"CB5_A":   PN = "60"  !CDS_PN = "60";
"CB5_B":   PN = "91"  !CDS_PN = "91";
"CB6_A":   PN = "203"  !CDS_PN = "203";
"CB6_B":   PN = "234"  !CDS_PN = "234";
"CB7_A":   PN = "205"  !CDS_PN = "205";
"CB7_B":   PN = "236"  !CDS_PN = "236";
"CK_C":   PN = "218"  !CDS_PN = "218";
"CK_T":   PN = "217"  !CDS_PN = "217";
"CS0_A_N":   PN = "64"  !CDS_PN = "64";
"CS0_B_N":   PN = "84"  !CDS_PN = "84";
"CS1_A_N":   PN = "209"  !CDS_PN = "209";
"CS1_B_N":   PN = "229"  !CDS_PN = "229";
"DQ0_A":   PN = "7"  !CDS_PN = "7";
"DQ0_B":   PN = "100"  !CDS_PN = "100";
"DQ1_A":   PN = "9"  !CDS_PN = "9";
"DQ1_B":   PN = "102"  !CDS_PN = "102";
"DQ2_A":   PN = "152"  !CDS_PN = "152";
"DQ2_B":   PN = "245"  !CDS_PN = "245";
"DQ3_A":   PN = "154"  !CDS_PN = "154";
"DQ3_B":   PN = "247"  !CDS_PN = "247";
"DQ4_A":   PN = "14"  !CDS_PN = "14";
"DQ4_B":   PN = "107"  !CDS_PN = "107";
"DQ5_A":   PN = "16"  !CDS_PN = "16";
"DQ5_B":   PN = "109"  !CDS_PN = "109";
"DQ6_A":   PN = "159"  !CDS_PN = "159";
"DQ6_B":   PN = "252"  !CDS_PN = "252";
"DQ7_A":   PN = "161"  !CDS_PN = "161";
"DQ7_B":   PN = "254"  !CDS_PN = "254";
"DQ8_A":   PN = "18"  !CDS_PN = "18";
"DQ8_B":   PN = "111"  !CDS_PN = "111";
"DQ9_A":   PN = "20"  !CDS_PN = "20";
"DQ9_B":   PN = "113"  !CDS_PN = "113";
"DQ10_A":   PN = "163"  !CDS_PN = "163";
"DQ10_B":   PN = "256"  !CDS_PN = "256";
"DQ11_A":   PN = "165"  !CDS_PN = "165";
"DQ11_B":   PN = "258"  !CDS_PN = "258";
"DQ12_A":   PN = "25"  !CDS_PN = "25";
"DQ12_B":   PN = "118"  !CDS_PN = "118";
"DQ13_A":   PN = "27"  !CDS_PN = "27";
"DQ13_B":   PN = "120"  !CDS_PN = "120";
"DQ14_A":   PN = "170"  !CDS_PN = "170";
"DQ14_B":   PN = "263"  !CDS_PN = "263";
"DQ15_A":   PN = "172"  !CDS_PN = "172";
"DQ15_B":   PN = "265"  !CDS_PN = "265";
"DQ16_A":   PN = "29"  !CDS_PN = "29";
"DQ16_B":   PN = "122"  !CDS_PN = "122";
"DQ17_A":   PN = "31"  !CDS_PN = "31";
"DQ17_B":   PN = "124"  !CDS_PN = "124";
"DQ18_A":   PN = "174"  !CDS_PN = "174";
"DQ18_B":   PN = "267"  !CDS_PN = "267";
"DQ19_A":   PN = "176"  !CDS_PN = "176";
"DQ19_B":   PN = "269"  !CDS_PN = "269";
"DQ20_A":   PN = "36"  !CDS_PN = "36";
"DQ20_B":   PN = "129"  !CDS_PN = "129";
"DQ21_A":   PN = "38"  !CDS_PN = "38";
"DQ21_B":   PN = "131"  !CDS_PN = "131";
"DQ22_A":   PN = "181"  !CDS_PN = "181";
"DQ22_B":   PN = "274"  !CDS_PN = "274";
"DQ23_A":   PN = "183"  !CDS_PN = "183";
"DQ23_B":   PN = "276"  !CDS_PN = "276";
"DQ24_A":   PN = "40"  !CDS_PN = "40";
"DQ24_B":   PN = "133"  !CDS_PN = "133";
"DQ25_A":   PN = "42"  !CDS_PN = "42";
"DQ25_B":   PN = "135"  !CDS_PN = "135";
"DQ26_A":   PN = "185"  !CDS_PN = "185";
"DQ26_B":   PN = "278"  !CDS_PN = "278";
"DQ27_A":   PN = "187"  !CDS_PN = "187";
"DQ27_B":   PN = "280"  !CDS_PN = "280";
"DQ28_A":   PN = "47"  !CDS_PN = "47";
"DQ28_B":   PN = "140"  !CDS_PN = "140";
"DQ29_A":   PN = "49"  !CDS_PN = "49";
"DQ29_B":   PN = "142"  !CDS_PN = "142";
"DQ30_A":   PN = "192"  !CDS_PN = "192";
"DQ30_B":   PN = "285"  !CDS_PN = "285";
"DQ31_A":   PN = "194"  !CDS_PN = "194";
"DQ31_B":   PN = "287"  !CDS_PN = "287";
"HSA":   PN = "148"  !CDS_PN = "148";
"HSCL":   PN = "4"  !CDS_PN = "4";
"HSDA":   PN = "5"  !CDS_PN = "5";
"LBD||RSP_A_N":   PN = "86"  !CDS_PN = "86";
"LBS||RSP_B_N":   PN = "87"  !CDS_PN = "87";
"PAR_A":   PN = "74"  !CDS_PN = "74";
"PAR_B":   PN = "227"  !CDS_PN = "227";
"PWR_GOOD||FAIL_N":   PN = "147"  !CDS_PN = "147";
"RESET_N":   PN = "207"  !CDS_PN = "207";
"RFU0":   PN = "2"  !CDS_PN = "2";
"RFU1":   PN = "144"  !CDS_PN = "144";
"RFU2":   PN = "149"  !CDS_PN = "149";
"RFU3":   PN = "150"  !CDS_PN = "150";
"RFU4":   PN = "220"  !CDS_PN = "220";
"RFU5":   PN = "231"  !CDS_PN = "231";
"RFU6":   PN = "232"  !CDS_PN = "232";
"VIN_MGMT":   PN = "3"  !CDS_PN = "3";
BODY = "Q_CAP","I123": LOCATION = "C29" #&CDS_LOCATION = "C29" &SEC = "1" #&CDS_SEC = "1";
"A":   PN = "1"  !CDS_PN = "1";
"B":   PN = "2"  !CDS_PN = "2";
BODY = "Q_CAP","I124": LOCATION = "C30" #&CDS_LOCATION = "C30" &SEC = "1" #&CDS_SEC = "1";
"A":   PN = "1"  !CDS_PN = "1";
"B":   PN = "2"  !CDS_PN = "2";
BODY = "Q_CAP","I146": LOCATION = "C31" #&CDS_LOCATION = "C31" &SEC = "1" #&CDS_SEC = "1";
"A":   PN = "1"  !CDS_PN = "1";
"B":   PN = "2"  !CDS_PN = "2";
BODY = "SCONN288_ADR50017P087CC","I148": LOCATION = "J10" #&CDS_LOCATION = "J10" &SEC = "3" #&CDS_SEC = "3";
"G1":   PN = "G1"  !CDS_PN = "G1";
"G2":   PN = "G2"  !CDS_PN = "G2";
"G3":   PN = "G3"  !CDS_PN = "G3";
"VIN_BULK0":   PN = "1"  !CDS_PN = "1";
"VIN_BULK1":   PN = "145"  !CDS_PN = "145";
"VIN_BULK2":   PN = "146"  !CDS_PN = "146";
"VSS0":   PN = "6"  !CDS_PN = "6";
"VSS1":   PN = "8"  !CDS_PN = "8";
"VSS2":   PN = "10"  !CDS_PN = "10";
"VSS3":   PN = "13"  !CDS_PN = "13";
"VSS4":   PN = "15"  !CDS_PN = "15";
"VSS5":   PN = "17"  !CDS_PN = "17";
"VSS6":   PN = "19"  !CDS_PN = "19";
"VSS7":   PN = "21"  !CDS_PN = "21";
"VSS8":   PN = "24"  !CDS_PN = "24";
"VSS9":   PN = "26"  !CDS_PN = "26";
"VSS10":   PN = "28"  !CDS_PN = "28";
"VSS11":   PN = "30"  !CDS_PN = "30";
"VSS12":   PN = "32"  !CDS_PN = "32";
"VSS13":   PN = "35"  !CDS_PN = "35";
"VSS14":   PN = "37"  !CDS_PN = "37";
"VSS15":   PN = "39"  !CDS_PN = "39";
"VSS16":   PN = "41"  !CDS_PN = "41";
"VSS17":   PN = "43"  !CDS_PN = "43";
"VSS18":   PN = "46"  !CDS_PN = "46";
"VSS19":   PN = "48"  !CDS_PN = "48";
"VSS20":   PN = "50"  !CDS_PN = "50";
"VSS21":   PN = "52"  !CDS_PN = "52";
"VSS22":   PN = "54"  !CDS_PN = "54";
"VSS23":   PN = "57"  !CDS_PN = "57";
"VSS24":   PN = "59"  !CDS_PN = "59";
"VSS25":   PN = "61"  !CDS_PN = "61";
"VSS26":   PN = "63"  !CDS_PN = "63";
"VSS27":   PN = "65"  !CDS_PN = "65";
"VSS28":   PN = "67"  !CDS_PN = "67";
"VSS29":   PN = "69"  !CDS_PN = "69";
"VSS30":   PN = "71"  !CDS_PN = "71";
"VSS31":   PN = "73"  !CDS_PN = "73";
"VSS32":   PN = "75"  !CDS_PN = "75";
"VSS33":   PN = "77"  !CDS_PN = "77";
"VSS34":   PN = "79"  !CDS_PN = "79";
"VSS35":   PN = "81"  !CDS_PN = "81";
"VSS36":   PN = "83"  !CDS_PN = "83";
"VSS37":   PN = "85"  !CDS_PN = "85";
"VSS38":   PN = "88"  !CDS_PN = "88";
"VSS39":   PN = "90"  !CDS_PN = "90";
"VSS40":   PN = "92"  !CDS_PN = "92";
"VSS41":   PN = "95"  !CDS_PN = "95";
"VSS42":   PN = "97"  !CDS_PN = "97";
"VSS43":   PN = "99"  !CDS_PN = "99";
"VSS44":   PN = "101"  !CDS_PN = "101";
"VSS45":   PN = "103"  !CDS_PN = "103";
"VSS46":   PN = "106"  !CDS_PN = "106";
"VSS47":   PN = "108"  !CDS_PN = "108";
"VSS48":   PN = "110"  !CDS_PN = "110";
"VSS49":   PN = "112"  !CDS_PN = "112";
"VSS50":   PN = "114"  !CDS_PN = "114";
"VSS51":   PN = "117"  !CDS_PN = "117";
"VSS52":   PN = "119"  !CDS_PN = "119";
"VSS53":   PN = "121"  !CDS_PN = "121";
"VSS54":   PN = "123"  !CDS_PN = "123";
"VSS55":   PN = "125"  !CDS_PN = "125";
"VSS56":   PN = "128"  !CDS_PN = "128";
"VSS57":   PN = "130"  !CDS_PN = "130";
"VSS58":   PN = "132"  !CDS_PN = "132";
"VSS59":   PN = "134"  !CDS_PN = "134";
"VSS60":   PN = "136"  !CDS_PN = "136";
"VSS61":   PN = "139"  !CDS_PN = "139";
"VSS62":   PN = "141"  !CDS_PN = "141";
"VSS63":   PN = "143"  !CDS_PN = "143";
"VSS64":   PN = "151"  !CDS_PN = "151";
"VSS65":   PN = "153"  !CDS_PN = "153";
"VSS66":   PN = "155"  !CDS_PN = "155";
"VSS67":   PN = "158"  !CDS_PN = "158";
"VSS68":   PN = "160"  !CDS_PN = "160";
"VSS69":   PN = "162"  !CDS_PN = "162";
"VSS70":   PN = "164"  !CDS_PN = "164";
"VSS71":   PN = "166"  !CDS_PN = "166";
"VSS72":   PN = "169"  !CDS_PN = "169";
"VSS73":   PN = "171"  !CDS_PN = "171";
"VSS74":   PN = "173"  !CDS_PN = "173";
"VSS75":   PN = "175"  !CDS_PN = "175";
"VSS76":   PN = "177"  !CDS_PN = "177";
"VSS77":   PN = "180"  !CDS_PN = "180";
"VSS78":   PN = "182"  !CDS_PN = "182";
"VSS79":   PN = "184"  !CDS_PN = "184";
"VSS80":   PN = "186"  !CDS_PN = "186";
"VSS81":   PN = "188"  !CDS_PN = "188";
"VSS82":   PN = "191"  !CDS_PN = "191";
"VSS83":   PN = "193"  !CDS_PN = "193";
"VSS84":   PN = "195"  !CDS_PN = "195";
"VSS85":   PN = "197"  !CDS_PN = "197";
"VSS86":   PN = "199"  !CDS_PN = "199";
"VSS87":   PN = "202"  !CDS_PN = "202";
"VSS88":   PN = "204"  !CDS_PN = "204";
"VSS89":   PN = "206"  !CDS_PN = "206";
"VSS90":   PN = "208"  !CDS_PN = "208";
"VSS91":   PN = "210"  !CDS_PN = "210";
"VSS92":   PN = "212"  !CDS_PN = "212";
"VSS93":   PN = "214"  !CDS_PN = "214";
"VSS94":   PN = "216"  !CDS_PN = "216";
"VSS95":   PN = "219"  !CDS_PN = "219";
"VSS96":   PN = "222"  !CDS_PN = "222";
"VSS97":   PN = "224"  !CDS_PN = "224";
"VSS98":   PN = "226"  !CDS_PN = "226";
"VSS99":   PN = "228"  !CDS_PN = "228";
"VSS100":   PN = "230"  !CDS_PN = "230";
"VSS101":   PN = "233"  !CDS_PN = "233";
"VSS102":   PN = "235"  !CDS_PN = "235";
"VSS103":   PN = "237"  !CDS_PN = "237";
"VSS104":   PN = "240"  !CDS_PN = "240";
"VSS105":   PN = "242"  !CDS_PN = "242";
"VSS106":   PN = "244"  !CDS_PN = "244";
"VSS107":   PN = "246"  !CDS_PN = "246";
"VSS108":   PN = "248"  !CDS_PN = "248";
"VSS109":   PN = "251"  !CDS_PN = "251";
"VSS110":   PN = "253"  !CDS_PN = "253";
"VSS111":   PN = "255"  !CDS_PN = "255";
"VSS112":   PN = "257"  !CDS_PN = "257";
"VSS113":   PN = "259"  !CDS_PN = "259";
"VSS114":   PN = "262"  !CDS_PN = "262";
"VSS115":   PN = "264"  !CDS_PN = "264";
"VSS116":   PN = "266"  !CDS_PN = "266";
"VSS117":   PN = "268"  !CDS_PN = "268";
"VSS118":   PN = "270"  !CDS_PN = "270";
"VSS119":   PN = "273"  !CDS_PN = "273";
"VSS120":   PN = "275"  !CDS_PN = "275";
"VSS121":   PN = "277"  !CDS_PN = "277";
"VSS122":   PN = "279"  !CDS_PN = "279";
"VSS123":   PN = "281"  !CDS_PN = "281";
"VSS124":   PN = "284"  !CDS_PN = "284";
"VSS125":   PN = "286"  !CDS_PN = "286";
"VSS126":   PN = "288"  !CDS_PN = "288";
BODY = "SCONN288_ADR50017P087CC","I178": #LOCATION = "J10" !CDS_LOCATION = "J10" &SEC = "2" #&CDS_SEC = "2";
"DQS0_A_C":   PN = "12"  !CDS_PN = "12";
"DQS0_A_T":   PN = "11"  !CDS_PN = "11";
"DQS0_B_C":   PN = "105"  !CDS_PN = "105";
"DQS0_B_T":   PN = "104"  !CDS_PN = "104";
"DQS1_A_C":   PN = "23"  !CDS_PN = "23";
"DQS1_A_T":   PN = "22"  !CDS_PN = "22";
"DQS1_B_C":   PN = "116"  !CDS_PN = "116";
"DQS1_B_T":   PN = "115"  !CDS_PN = "115";
"DQS2_A_C":   PN = "34"  !CDS_PN = "34";
"DQS2_A_T":   PN = "33"  !CDS_PN = "33";
"DQS2_B_C":   PN = "127"  !CDS_PN = "127";
"DQS2_B_T":   PN = "126"  !CDS_PN = "126";
"DQS3_A_C":   PN = "45"  !CDS_PN = "45";
"DQS3_A_T":   PN = "44"  !CDS_PN = "44";
"DQS3_B_C":   PN = "138"  !CDS_PN = "138";
"DQS3_B_T":   PN = "137"  !CDS_PN = "137";
"DQS4_A_C":   PN = "56"  !CDS_PN = "56";
"DQS4_A_T":   PN = "55"  !CDS_PN = "55";
"DQS4_B_C":   PN = "238"  !CDS_PN = "238";
"DQS4_B_T":   PN = "239"  !CDS_PN = "239";
"DQS5_A_C||TDQS5_A_C||DQS5_A_T||TDQS5_A_T":   PN = "156"  !CDS_PN = "156";
"DQS5_A_T||TDQS5_A_T":   PN = "157"  !CDS_PN = "157";
"DQS5_B_C||TDQS5_B_C":   PN = "249"  !CDS_PN = "249";
"DQS5_B_T||TDQS5_B_T":   PN = "250"  !CDS_PN = "250";
"DQS6_A_C||TDQS6_A_C||DQS6_A_T||TDQS6_A_T":   PN = "167"  !CDS_PN = "167";
"DQS6_A_T||TDQS6_A_T":   PN = "168"  !CDS_PN = "168";
"DQS6_B_C||TDQS6_B_C":   PN = "260"  !CDS_PN = "260";
"DQS6_B_T||TDQS6_B_T":   PN = "261"  !CDS_PN = "261";
"DQS7_A_C||TDQS7_A_C":   PN = "178"  !CDS_PN = "178";
"DQS7_A_T||TDQS7_A_T":   PN = "179"  !CDS_PN = "179";
"DQS7_B_C||TDQS7_B_C":   PN = "271"  !CDS_PN = "271";
"DQS7_B_T||TDQS7_B_T":   PN = "272"  !CDS_PN = "272";
"DQS8_A_C||TDQS8_A_C":   PN = "189"  !CDS_PN = "189";
"DQS8_A_T||TDQS8_A_T":   PN = "190"  !CDS_PN = "190";
"DQS8_B_C||TDQS8_B_C":   PN = "282"  !CDS_PN = "282";
"DQS8_B_T||TDQS8_B_T":   PN = "283"  !CDS_PN = "283";
"DQS9_A_C||TDQS9_A_C":   PN = "200"  !CDS_PN = "200";
"DQS9_A_T||TDQS9_A_T":   PN = "201"  !CDS_PN = "201";
"DQS9_B_C||TDQS9_B_C":   PN = "94"  !CDS_PN = "94";
"DQS9_B_T||TDQS9_B_T||DBI4_B_N":   PN = "93"  !CDS_PN = "93";
BODY = "Q_RES","I179": LOCATION = "R3884" #&CDS_LOCATION = "R3884" &SEC = "1" #&CDS_SEC = "1";
"A":   PN = "1"  !CDS_PN = "1";
"B":   PN = "2"  !CDS_PN = "2";
DRAWING = "@s9s_mb_2u_lib.s9s_mb_2u(sch_1):page92";
BODY = "Q_RES","I2": LOCATION = "R36" #&CDS_LOCATION = "R36" &SEC = "1" #&CDS_SEC = "1";
"A":   PN = "1"  !CDS_PN = "1";
"B":   PN = "2"  !CDS_PN = "2";
BODY = "SCONN288_ADR50017P130CC","I25": LOCATION = "J11" #&CDS_LOCATION = "J11" &SEC = "1" #&CDS_SEC = "1";
"ALERT_N":   PN = "62"  !CDS_PN = "62";
"CA0_A":   PN = "66"  !CDS_PN = "66";
"CA0_B":   PN = "76"  !CDS_PN = "76";
"CA1_A":   PN = "211"  !CDS_PN = "211";
"CA1_B":   PN = "221"  !CDS_PN = "221";
"CA2_A":   PN = "68"  !CDS_PN = "68";
"CA2_B":   PN = "78"  !CDS_PN = "78";
"CA3_A":   PN = "213"  !CDS_PN = "213";
"CA3_B":   PN = "223"  !CDS_PN = "223";
"CA4_A":   PN = "70"  !CDS_PN = "70";
"CA4_B":   PN = "80"  !CDS_PN = "80";
"CA5_A":   PN = "215"  !CDS_PN = "215";
"CA5_B":   PN = "225"  !CDS_PN = "225";
"CA6_A":   PN = "72"  !CDS_PN = "72";
"CA6_B":   PN = "82"  !CDS_PN = "82";
"CB0_A":   PN = "51"  !CDS_PN = "51";
"CB0_B":   PN = "96"  !CDS_PN = "96";
"CB1_A":   PN = "53"  !CDS_PN = "53";
"CB1_B":   PN = "98"  !CDS_PN = "98";
"CB2_A":   PN = "196"  !CDS_PN = "196";
"CB2_B":   PN = "241"  !CDS_PN = "241";
"CB3_A":   PN = "198"  !CDS_PN = "198";
"CB3_B":   PN = "243"  !CDS_PN = "243";
"CB4_A":   PN = "58"  !CDS_PN = "58";
"CB4_B":   PN = "89"  !CDS_PN = "89";
"CB5_A":   PN = "60"  !CDS_PN = "60";
"CB5_B":   PN = "91"  !CDS_PN = "91";
"CB6_A":   PN = "203"  !CDS_PN = "203";
"CB6_B":   PN = "234"  !CDS_PN = "234";
"CB7_A":   PN = "205"  !CDS_PN = "205";
"CB7_B":   PN = "236"  !CDS_PN = "236";
"CK_C":   PN = "218"  !CDS_PN = "218";
"CK_T":   PN = "217"  !CDS_PN = "217";
"CS0_A_N":   PN = "64"  !CDS_PN = "64";
"CS0_B_N":   PN = "84"  !CDS_PN = "84";
"CS1_A_N":   PN = "209"  !CDS_PN = "209";
"CS1_B_N":   PN = "229"  !CDS_PN = "229";
"DQ0_A":   PN = "7"  !CDS_PN = "7";
"DQ0_B":   PN = "100"  !CDS_PN = "100";
"DQ1_A":   PN = "9"  !CDS_PN = "9";
"DQ1_B":   PN = "102"  !CDS_PN = "102";
"DQ2_A":   PN = "152"  !CDS_PN = "152";
"DQ2_B":   PN = "245"  !CDS_PN = "245";
"DQ3_A":   PN = "154"  !CDS_PN = "154";
"DQ3_B":   PN = "247"  !CDS_PN = "247";
"DQ4_A":   PN = "14"  !CDS_PN = "14";
"DQ4_B":   PN = "107"  !CDS_PN = "107";
"DQ5_A":   PN = "16"  !CDS_PN = "16";
"DQ5_B":   PN = "109"  !CDS_PN = "109";
"DQ6_A":   PN = "159"  !CDS_PN = "159";
"DQ6_B":   PN = "252"  !CDS_PN = "252";
"DQ7_A":   PN = "161"  !CDS_PN = "161";
"DQ7_B":   PN = "254"  !CDS_PN = "254";
"DQ8_A":   PN = "18"  !CDS_PN = "18";
"DQ8_B":   PN = "111"  !CDS_PN = "111";
"DQ9_A":   PN = "20"  !CDS_PN = "20";
"DQ9_B":   PN = "113"  !CDS_PN = "113";
"DQ10_A":   PN = "163"  !CDS_PN = "163";
"DQ10_B":   PN = "256"  !CDS_PN = "256";
"DQ11_A":   PN = "165"  !CDS_PN = "165";
"DQ11_B":   PN = "258"  !CDS_PN = "258";
"DQ12_A":   PN = "25"  !CDS_PN = "25";
"DQ12_B":   PN = "118"  !CDS_PN = "118";
"DQ13_A":   PN = "27"  !CDS_PN = "27";
"DQ13_B":   PN = "120"  !CDS_PN = "120";
"DQ14_A":   PN = "170"  !CDS_PN = "170";
"DQ14_B":   PN = "263"  !CDS_PN = "263";
"DQ15_A":   PN = "172"  !CDS_PN = "172";
"DQ15_B":   PN = "265"  !CDS_PN = "265";
"DQ16_A":   PN = "29"  !CDS_PN = "29";
"DQ16_B":   PN = "122"  !CDS_PN = "122";
"DQ17_A":   PN = "31"  !CDS_PN = "31";
"DQ17_B":   PN = "124"  !CDS_PN = "124";
"DQ18_A":   PN = "174"  !CDS_PN = "174";
"DQ18_B":   PN = "267"  !CDS_PN = "267";
"DQ19_A":   PN = "176"  !CDS_PN = "176";
"DQ19_B":   PN = "269"  !CDS_PN = "269";
"DQ20_A":   PN = "36"  !CDS_PN = "36";
"DQ20_B":   PN = "129"  !CDS_PN = "129";
"DQ21_A":   PN = "38"  !CDS_PN = "38";
"DQ21_B":   PN = "131"  !CDS_PN = "131";
"DQ22_A":   PN = "181"  !CDS_PN = "181";
"DQ22_B":   PN = "274"  !CDS_PN = "274";
"DQ23_A":   PN = "183"  !CDS_PN = "183";
"DQ23_B":   PN = "276"  !CDS_PN = "276";
"DQ24_A":   PN = "40"  !CDS_PN = "40";
"DQ24_B":   PN = "133"  !CDS_PN = "133";
"DQ25_A":   PN = "42"  !CDS_PN = "42";
"DQ25_B":   PN = "135"  !CDS_PN = "135";
"DQ26_A":   PN = "185"  !CDS_PN = "185";
"DQ26_B":   PN = "278"  !CDS_PN = "278";
"DQ27_A":   PN = "187"  !CDS_PN = "187";
"DQ27_B":   PN = "280"  !CDS_PN = "280";
"DQ28_A":   PN = "47"  !CDS_PN = "47";
"DQ28_B":   PN = "140"  !CDS_PN = "140";
"DQ29_A":   PN = "49"  !CDS_PN = "49";
"DQ29_B":   PN = "142"  !CDS_PN = "142";
"DQ30_A":   PN = "192"  !CDS_PN = "192";
"DQ30_B":   PN = "285"  !CDS_PN = "285";
"DQ31_A":   PN = "194"  !CDS_PN = "194";
"DQ31_B":   PN = "287"  !CDS_PN = "287";
"HSA":   PN = "148"  !CDS_PN = "148";
"HSCL":   PN = "4"  !CDS_PN = "4";
"HSDA":   PN = "5"  !CDS_PN = "5";
"LBD||RSP_A_N":   PN = "86"  !CDS_PN = "86";
"LBS||RSP_B_N":   PN = "87"  !CDS_PN = "87";
"PAR_A":   PN = "74"  !CDS_PN = "74";
"PAR_B":   PN = "227"  !CDS_PN = "227";
"PWR_GOOD||FAIL_N":   PN = "147"  !CDS_PN = "147";
"RESET_N":   PN = "207"  !CDS_PN = "207";
"RFU0":   PN = "2"  !CDS_PN = "2";
"RFU1":   PN = "144"  !CDS_PN = "144";
"RFU2":   PN = "149"  !CDS_PN = "149";
"RFU3":   PN = "150"  !CDS_PN = "150";
"RFU4":   PN = "220"  !CDS_PN = "220";
"RFU5":   PN = "231"  !CDS_PN = "231";
"RFU6":   PN = "232"  !CDS_PN = "232";
"VIN_MGMT":   PN = "3"  !CDS_PN = "3";
BODY = "Q_CAP","I122": LOCATION = "C32" #&CDS_LOCATION = "C32" &SEC = "1" #&CDS_SEC = "1";
"A":   PN = "1"  !CDS_PN = "1";
"B":   PN = "2"  !CDS_PN = "2";
BODY = "Q_CAP","I127": LOCATION = "C33" #&CDS_LOCATION = "C33" &SEC = "1" #&CDS_SEC = "1";
"A":   PN = "1"  !CDS_PN = "1";
"B":   PN = "2"  !CDS_PN = "2";
BODY = "Q_CAP","I130": LOCATION = "C34" #&CDS_LOCATION = "C34" &SEC = "1" #&CDS_SEC = "1";
"A":   PN = "1"  !CDS_PN = "1";
"B":   PN = "2"  !CDS_PN = "2";
BODY = "SCONN288_ADR50017P130CC","I175": LOCATION = "J11" #&CDS_LOCATION = "J11" &SEC = "3" #&CDS_SEC = "3";
"G1":   PN = "G1"  !CDS_PN = "G1";
"G2":   PN = "G2"  !CDS_PN = "G2";
"G3":   PN = "G3"  !CDS_PN = "G3";
"VIN_BULK0":   PN = "1"  !CDS_PN = "1";
"VIN_BULK1":   PN = "145"  !CDS_PN = "145";
"VIN_BULK2":   PN = "146"  !CDS_PN = "146";
"VSS0":   PN = "6"  !CDS_PN = "6";
"VSS1":   PN = "8"  !CDS_PN = "8";
"VSS2":   PN = "10"  !CDS_PN = "10";
"VSS3":   PN = "13"  !CDS_PN = "13";
"VSS4":   PN = "15"  !CDS_PN = "15";
"VSS5":   PN = "17"  !CDS_PN = "17";
"VSS6":   PN = "19"  !CDS_PN = "19";
"VSS7":   PN = "21"  !CDS_PN = "21";
"VSS8":   PN = "24"  !CDS_PN = "24";
"VSS9":   PN = "26"  !CDS_PN = "26";
"VSS10":   PN = "28"  !CDS_PN = "28";
"VSS11":   PN = "30"  !CDS_PN = "30";
"VSS12":   PN = "32"  !CDS_PN = "32";
"VSS13":   PN = "35"  !CDS_PN = "35";
"VSS14":   PN = "37"  !CDS_PN = "37";
"VSS15":   PN = "39"  !CDS_PN = "39";
"VSS16":   PN = "41"  !CDS_PN = "41";
"VSS17":   PN = "43"  !CDS_PN = "43";
"VSS18":   PN = "46"  !CDS_PN = "46";
"VSS19":   PN = "48"  !CDS_PN = "48";
"VSS20":   PN = "50"  !CDS_PN = "50";
"VSS21":   PN = "52"  !CDS_PN = "52";
"VSS22":   PN = "54"  !CDS_PN = "54";
"VSS23":   PN = "57"  !CDS_PN = "57";
"VSS24":   PN = "59"  !CDS_PN = "59";
"VSS25":   PN = "61"  !CDS_PN = "61";
"VSS26":   PN = "63"  !CDS_PN = "63";
"VSS27":   PN = "65"  !CDS_PN = "65";
"VSS28":   PN = "67"  !CDS_PN = "67";
"VSS29":   PN = "69"  !CDS_PN = "69";
"VSS30":   PN = "71"  !CDS_PN = "71";
"VSS31":   PN = "73"  !CDS_PN = "73";
"VSS32":   PN = "75"  !CDS_PN = "75";
"VSS33":   PN = "77"  !CDS_PN = "77";
"VSS34":   PN = "79"  !CDS_PN = "79";
"VSS35":   PN = "81"  !CDS_PN = "81";
"VSS36":   PN = "83"  !CDS_PN = "83";
"VSS37":   PN = "85"  !CDS_PN = "85";
"VSS38":   PN = "88"  !CDS_PN = "88";
"VSS39":   PN = "90"  !CDS_PN = "90";
"VSS40":   PN = "92"  !CDS_PN = "92";
"VSS41":   PN = "95"  !CDS_PN = "95";
"VSS42":   PN = "97"  !CDS_PN = "97";
"VSS43":   PN = "99"  !CDS_PN = "99";
"VSS44":   PN = "101"  !CDS_PN = "101";
"VSS45":   PN = "103"  !CDS_PN = "103";
"VSS46":   PN = "106"  !CDS_PN = "106";
"VSS47":   PN = "108"  !CDS_PN = "108";
"VSS48":   PN = "110"  !CDS_PN = "110";
"VSS49":   PN = "112"  !CDS_PN = "112";
"VSS50":   PN = "114"  !CDS_PN = "114";
"VSS51":   PN = "117"  !CDS_PN = "117";
"VSS52":   PN = "119"  !CDS_PN = "119";
"VSS53":   PN = "121"  !CDS_PN = "121";
"VSS54":   PN = "123"  !CDS_PN = "123";
"VSS55":   PN = "125"  !CDS_PN = "125";
"VSS56":   PN = "128"  !CDS_PN = "128";
"VSS57":   PN = "130"  !CDS_PN = "130";
"VSS58":   PN = "132"  !CDS_PN = "132";
"VSS59":   PN = "134"  !CDS_PN = "134";
"VSS60":   PN = "136"  !CDS_PN = "136";
"VSS61":   PN = "139"  !CDS_PN = "139";
"VSS62":   PN = "141"  !CDS_PN = "141";
"VSS63":   PN = "143"  !CDS_PN = "143";
"VSS64":   PN = "151"  !CDS_PN = "151";
"VSS65":   PN = "153"  !CDS_PN = "153";
"VSS66":   PN = "155"  !CDS_PN = "155";
"VSS67":   PN = "158"  !CDS_PN = "158";
"VSS68":   PN = "160"  !CDS_PN = "160";
"VSS69":   PN = "162"  !CDS_PN = "162";
"VSS70":   PN = "164"  !CDS_PN = "164";
"VSS71":   PN = "166"  !CDS_PN = "166";
"VSS72":   PN = "169"  !CDS_PN = "169";
"VSS73":   PN = "171"  !CDS_PN = "171";
"VSS74":   PN = "173"  !CDS_PN = "173";
"VSS75":   PN = "175"  !CDS_PN = "175";
"VSS76":   PN = "177"  !CDS_PN = "177";
"VSS77":   PN = "180"  !CDS_PN = "180";
"VSS78":   PN = "182"  !CDS_PN = "182";
"VSS79":   PN = "184"  !CDS_PN = "184";
"VSS80":   PN = "186"  !CDS_PN = "186";
"VSS81":   PN = "188"  !CDS_PN = "188";
"VSS82":   PN = "191"  !CDS_PN = "191";
"VSS83":   PN = "193"  !CDS_PN = "193";
"VSS84":   PN = "195"  !CDS_PN = "195";
"VSS85":   PN = "197"  !CDS_PN = "197";
"VSS86":   PN = "199"  !CDS_PN = "199";
"VSS87":   PN = "202"  !CDS_PN = "202";
"VSS88":   PN = "204"  !CDS_PN = "204";
"VSS89":   PN = "206"  !CDS_PN = "206";
"VSS90":   PN = "208"  !CDS_PN = "208";
"VSS91":   PN = "210"  !CDS_PN = "210";
"VSS92":   PN = "212"  !CDS_PN = "212";
"VSS93":   PN = "214"  !CDS_PN = "214";
"VSS94":   PN = "216"  !CDS_PN = "216";
"VSS95":   PN = "219"  !CDS_PN = "219";
"VSS96":   PN = "222"  !CDS_PN = "222";
"VSS97":   PN = "224"  !CDS_PN = "224";
"VSS98":   PN = "226"  !CDS_PN = "226";
"VSS99":   PN = "228"  !CDS_PN = "228";
"VSS100":   PN = "230"  !CDS_PN = "230";
"VSS101":   PN = "233"  !CDS_PN = "233";
"VSS102":   PN = "235"  !CDS_PN = "235";
"VSS103":   PN = "237"  !CDS_PN = "237";
"VSS104":   PN = "240"  !CDS_PN = "240";
"VSS105":   PN = "242"  !CDS_PN = "242";
"VSS106":   PN = "244"  !CDS_PN = "244";
"VSS107":   PN = "246"  !CDS_PN = "246";
"VSS108":   PN = "248"  !CDS_PN = "248";
"VSS109":   PN = "251"  !CDS_PN = "251";
"VSS110":   PN = "253"  !CDS_PN = "253";
"VSS111":   PN = "255"  !CDS_PN = "255";
"VSS112":   PN = "257"  !CDS_PN = "257";
"VSS113":   PN = "259"  !CDS_PN = "259";
"VSS114":   PN = "262"  !CDS_PN = "262";
"VSS115":   PN = "264"  !CDS_PN = "264";
"VSS116":   PN = "266"  !CDS_PN = "266";
"VSS117":   PN = "268"  !CDS_PN = "268";
"VSS118":   PN = "270"  !CDS_PN = "270";
"VSS119":   PN = "273"  !CDS_PN = "273";
"VSS120":   PN = "275"  !CDS_PN = "275";
"VSS121":   PN = "277"  !CDS_PN = "277";
"VSS122":   PN = "279"  !CDS_PN = "279";
"VSS123":   PN = "281"  !CDS_PN = "281";
"VSS124":   PN = "284"  !CDS_PN = "284";
"VSS125":   PN = "286"  !CDS_PN = "286";
"VSS126":   PN = "288"  !CDS_PN = "288";
BODY = "SCONN288_ADR50017P130CC","I178": #LOCATION = "J11" !CDS_LOCATION = "J11" &SEC = "2" #&CDS_SEC = "2";
"DQS0_A_C":   PN = "12"  !CDS_PN = "12";
"DQS0_A_T":   PN = "11"  !CDS_PN = "11";
"DQS0_B_C":   PN = "105"  !CDS_PN = "105";
"DQS0_B_T":   PN = "104"  !CDS_PN = "104";
"DQS1_A_C":   PN = "23"  !CDS_PN = "23";
"DQS1_A_T":   PN = "22"  !CDS_PN = "22";
"DQS1_B_C":   PN = "116"  !CDS_PN = "116";
"DQS1_B_T":   PN = "115"  !CDS_PN = "115";
"DQS2_A_C":   PN = "34"  !CDS_PN = "34";
"DQS2_A_T":   PN = "33"  !CDS_PN = "33";
"DQS2_B_C":   PN = "127"  !CDS_PN = "127";
"DQS2_B_T":   PN = "126"  !CDS_PN = "126";
"DQS3_A_C":   PN = "45"  !CDS_PN = "45";
"DQS3_A_T":   PN = "44"  !CDS_PN = "44";
"DQS3_B_C":   PN = "138"  !CDS_PN = "138";
"DQS3_B_T":   PN = "137"  !CDS_PN = "137";
"DQS4_A_C":   PN = "56"  !CDS_PN = "56";
"DQS4_A_T":   PN = "55"  !CDS_PN = "55";
"DQS4_B_C":   PN = "238"  !CDS_PN = "238";
"DQS4_B_T":   PN = "239"  !CDS_PN = "239";
"DQS5_A_C||TDQS5_A_C||DQS5_A_T||TDQS5_A_T":   PN = "156"  !CDS_PN = "156";
"DQS5_A_T||TDQS5_A_T":   PN = "157"  !CDS_PN = "157";
"DQS5_B_C||TDQS5_B_C":   PN = "249"  !CDS_PN = "249";
"DQS5_B_T||TDQS5_B_T":   PN = "250"  !CDS_PN = "250";
"DQS6_A_C||TDQS6_A_C||DQS6_A_T||TDQS6_A_T":   PN = "167"  !CDS_PN = "167";
"DQS6_A_T||TDQS6_A_T":   PN = "168"  !CDS_PN = "168";
"DQS6_B_C||TDQS6_B_C":   PN = "260"  !CDS_PN = "260";
"DQS6_B_T||TDQS6_B_T":   PN = "261"  !CDS_PN = "261";
"DQS7_A_C||TDQS7_A_C":   PN = "178"  !CDS_PN = "178";
"DQS7_A_T||TDQS7_A_T":   PN = "179"  !CDS_PN = "179";
"DQS7_B_C||TDQS7_B_C":   PN = "271"  !CDS_PN = "271";
"DQS7_B_T||TDQS7_B_T":   PN = "272"  !CDS_PN = "272";
"DQS8_A_C||TDQS8_A_C":   PN = "189"  !CDS_PN = "189";
"DQS8_A_T||TDQS8_A_T":   PN = "190"  !CDS_PN = "190";
"DQS8_B_C||TDQS8_B_C":   PN = "282"  !CDS_PN = "282";
"DQS8_B_T||TDQS8_B_T":   PN = "283"  !CDS_PN = "283";
"DQS9_A_C||TDQS9_A_C":   PN = "200"  !CDS_PN = "200";
"DQS9_A_T||TDQS9_A_T":   PN = "201"  !CDS_PN = "201";
"DQS9_B_C||TDQS9_B_C":   PN = "94"  !CDS_PN = "94";
"DQS9_B_T||TDQS9_B_T||DBI4_B_N":   PN = "93"  !CDS_PN = "93";
BODY = "Q_RES","I179": LOCATION = "R3885" #&CDS_LOCATION = "R3885" &SEC = "1" #&CDS_SEC = "1";
"A":   PN = "1"  !CDS_PN = "1";
"B":   PN = "2"  !CDS_PN = "2";
DRAWING = "@s9s_mb_2u_lib.s9s_mb_2u(sch_1):page93";
BODY = "Q_RES","I2": LOCATION = "R37" #&CDS_LOCATION = "R37" &SEC = "1" #&CDS_SEC = "1";
"A":   PN = "1"  !CDS_PN = "1";
"B":   PN = "2"  !CDS_PN = "2";
BODY = "SCONN288_ADR50017P087CC","I24": LOCATION = "J12" #&CDS_LOCATION = "J12" &SEC = "1" #&CDS_SEC = "1";
"ALERT_N":   PN = "62"  !CDS_PN = "62";
"CA0_A":   PN = "66"  !CDS_PN = "66";
"CA0_B":   PN = "76"  !CDS_PN = "76";
"CA1_A":   PN = "211"  !CDS_PN = "211";
"CA1_B":   PN = "221"  !CDS_PN = "221";
"CA2_A":   PN = "68"  !CDS_PN = "68";
"CA2_B":   PN = "78"  !CDS_PN = "78";
"CA3_A":   PN = "213"  !CDS_PN = "213";
"CA3_B":   PN = "223"  !CDS_PN = "223";
"CA4_A":   PN = "70"  !CDS_PN = "70";
"CA4_B":   PN = "80"  !CDS_PN = "80";
"CA5_A":   PN = "215"  !CDS_PN = "215";
"CA5_B":   PN = "225"  !CDS_PN = "225";
"CA6_A":   PN = "72"  !CDS_PN = "72";
"CA6_B":   PN = "82"  !CDS_PN = "82";
"CB0_A":   PN = "51"  !CDS_PN = "51";
"CB0_B":   PN = "96"  !CDS_PN = "96";
"CB1_A":   PN = "53"  !CDS_PN = "53";
"CB1_B":   PN = "98"  !CDS_PN = "98";
"CB2_A":   PN = "196"  !CDS_PN = "196";
"CB2_B":   PN = "241"  !CDS_PN = "241";
"CB3_A":   PN = "198"  !CDS_PN = "198";
"CB3_B":   PN = "243"  !CDS_PN = "243";
"CB4_A":   PN = "58"  !CDS_PN = "58";
"CB4_B":   PN = "89"  !CDS_PN = "89";
"CB5_A":   PN = "60"  !CDS_PN = "60";
"CB5_B":   PN = "91"  !CDS_PN = "91";
"CB6_A":   PN = "203"  !CDS_PN = "203";
"CB6_B":   PN = "234"  !CDS_PN = "234";
"CB7_A":   PN = "205"  !CDS_PN = "205";
"CB7_B":   PN = "236"  !CDS_PN = "236";
"CK_C":   PN = "218"  !CDS_PN = "218";
"CK_T":   PN = "217"  !CDS_PN = "217";
"CS0_A_N":   PN = "64"  !CDS_PN = "64";
"CS0_B_N":   PN = "84"  !CDS_PN = "84";
"CS1_A_N":   PN = "209"  !CDS_PN = "209";
"CS1_B_N":   PN = "229"  !CDS_PN = "229";
"DQ0_A":   PN = "7"  !CDS_PN = "7";
"DQ0_B":   PN = "100"  !CDS_PN = "100";
"DQ1_A":   PN = "9"  !CDS_PN = "9";
"DQ1_B":   PN = "102"  !CDS_PN = "102";
"DQ2_A":   PN = "152"  !CDS_PN = "152";
"DQ2_B":   PN = "245"  !CDS_PN = "245";
"DQ3_A":   PN = "154"  !CDS_PN = "154";
"DQ3_B":   PN = "247"  !CDS_PN = "247";
"DQ4_A":   PN = "14"  !CDS_PN = "14";
"DQ4_B":   PN = "107"  !CDS_PN = "107";
"DQ5_A":   PN = "16"  !CDS_PN = "16";
"DQ5_B":   PN = "109"  !CDS_PN = "109";
"DQ6_A":   PN = "159"  !CDS_PN = "159";
"DQ6_B":   PN = "252"  !CDS_PN = "252";
"DQ7_A":   PN = "161"  !CDS_PN = "161";
"DQ7_B":   PN = "254"  !CDS_PN = "254";
"DQ8_A":   PN = "18"  !CDS_PN = "18";
"DQ8_B":   PN = "111"  !CDS_PN = "111";
"DQ9_A":   PN = "20"  !CDS_PN = "20";
"DQ9_B":   PN = "113"  !CDS_PN = "113";
"DQ10_A":   PN = "163"  !CDS_PN = "163";
"DQ10_B":   PN = "256"  !CDS_PN = "256";
"DQ11_A":   PN = "165"  !CDS_PN = "165";
"DQ11_B":   PN = "258"  !CDS_PN = "258";
"DQ12_A":   PN = "25"  !CDS_PN = "25";
"DQ12_B":   PN = "118"  !CDS_PN = "118";
"DQ13_A":   PN = "27"  !CDS_PN = "27";
"DQ13_B":   PN = "120"  !CDS_PN = "120";
"DQ14_A":   PN = "170"  !CDS_PN = "170";
"DQ14_B":   PN = "263"  !CDS_PN = "263";
"DQ15_A":   PN = "172"  !CDS_PN = "172";
"DQ15_B":   PN = "265"  !CDS_PN = "265";
"DQ16_A":   PN = "29"  !CDS_PN = "29";
"DQ16_B":   PN = "122"  !CDS_PN = "122";
"DQ17_A":   PN = "31"  !CDS_PN = "31";
"DQ17_B":   PN = "124"  !CDS_PN = "124";
"DQ18_A":   PN = "174"  !CDS_PN = "174";
"DQ18_B":   PN = "267"  !CDS_PN = "267";
"DQ19_A":   PN = "176"  !CDS_PN = "176";
"DQ19_B":   PN = "269"  !CDS_PN = "269";
"DQ20_A":   PN = "36"  !CDS_PN = "36";
"DQ20_B":   PN = "129"  !CDS_PN = "129";
"DQ21_A":   PN = "38"  !CDS_PN = "38";
"DQ21_B":   PN = "131"  !CDS_PN = "131";
"DQ22_A":   PN = "181"  !CDS_PN = "181";
"DQ22_B":   PN = "274"  !CDS_PN = "274";
"DQ23_A":   PN = "183"  !CDS_PN = "183";
"DQ23_B":   PN = "276"  !CDS_PN = "276";
"DQ24_A":   PN = "40"  !CDS_PN = "40";
"DQ24_B":   PN = "133"  !CDS_PN = "133";
"DQ25_A":   PN = "42"  !CDS_PN = "42";
"DQ25_B":   PN = "135"  !CDS_PN = "135";
"DQ26_A":   PN = "185"  !CDS_PN = "185";
"DQ26_B":   PN = "278"  !CDS_PN = "278";
"DQ27_A":   PN = "187"  !CDS_PN = "187";
"DQ27_B":   PN = "280"  !CDS_PN = "280";
"DQ28_A":   PN = "47"  !CDS_PN = "47";
"DQ28_B":   PN = "140"  !CDS_PN = "140";
"DQ29_A":   PN = "49"  !CDS_PN = "49";
"DQ29_B":   PN = "142"  !CDS_PN = "142";
"DQ30_A":   PN = "192"  !CDS_PN = "192";
"DQ30_B":   PN = "285"  !CDS_PN = "285";
"DQ31_A":   PN = "194"  !CDS_PN = "194";
"DQ31_B":   PN = "287"  !CDS_PN = "287";
"HSA":   PN = "148"  !CDS_PN = "148";
"HSCL":   PN = "4"  !CDS_PN = "4";
"HSDA":   PN = "5"  !CDS_PN = "5";
"LBD||RSP_A_N":   PN = "86"  !CDS_PN = "86";
"LBS||RSP_B_N":   PN = "87"  !CDS_PN = "87";
"PAR_A":   PN = "74"  !CDS_PN = "74";
"PAR_B":   PN = "227"  !CDS_PN = "227";
"PWR_GOOD||FAIL_N":   PN = "147"  !CDS_PN = "147";
"RESET_N":   PN = "207"  !CDS_PN = "207";
"RFU0":   PN = "2"  !CDS_PN = "2";
"RFU1":   PN = "144"  !CDS_PN = "144";
"RFU2":   PN = "149"  !CDS_PN = "149";
"RFU3":   PN = "150"  !CDS_PN = "150";
"RFU4":   PN = "220"  !CDS_PN = "220";
"RFU5":   PN = "231"  !CDS_PN = "231";
"RFU6":   PN = "232"  !CDS_PN = "232";
"VIN_MGMT":   PN = "3"  !CDS_PN = "3";
BODY = "Q_CAP","I122": LOCATION = "C35" #&CDS_LOCATION = "C35" &SEC = "1" #&CDS_SEC = "1";
"A":   PN = "1"  !CDS_PN = "1";
"B":   PN = "2"  !CDS_PN = "2";
BODY = "Q_CAP","I126": LOCATION = "C36" #&CDS_LOCATION = "C36" &SEC = "1" #&CDS_SEC = "1";
"A":   PN = "1"  !CDS_PN = "1";
"B":   PN = "2"  !CDS_PN = "2";
BODY = "Q_CAP","I128": LOCATION = "C37" #&CDS_LOCATION = "C37" &SEC = "1" #&CDS_SEC = "1";
"A":   PN = "1"  !CDS_PN = "1";
"B":   PN = "2"  !CDS_PN = "2";
BODY = "SCONN288_ADR50017P087CC","I175": LOCATION = "J12" #&CDS_LOCATION = "J12" &SEC = "3" #&CDS_SEC = "3";
"G1":   PN = "G1"  !CDS_PN = "G1";
"G2":   PN = "G2"  !CDS_PN = "G2";
"G3":   PN = "G3"  !CDS_PN = "G3";
"VIN_BULK0":   PN = "1"  !CDS_PN = "1";
"VIN_BULK1":   PN = "145"  !CDS_PN = "145";
"VIN_BULK2":   PN = "146"  !CDS_PN = "146";
"VSS0":   PN = "6"  !CDS_PN = "6";
"VSS1":   PN = "8"  !CDS_PN = "8";
"VSS2":   PN = "10"  !CDS_PN = "10";
"VSS3":   PN = "13"  !CDS_PN = "13";
"VSS4":   PN = "15"  !CDS_PN = "15";
"VSS5":   PN = "17"  !CDS_PN = "17";
"VSS6":   PN = "19"  !CDS_PN = "19";
"VSS7":   PN = "21"  !CDS_PN = "21";
"VSS8":   PN = "24"  !CDS_PN = "24";
"VSS9":   PN = "26"  !CDS_PN = "26";
"VSS10":   PN = "28"  !CDS_PN = "28";
"VSS11":   PN = "30"  !CDS_PN = "30";
"VSS12":   PN = "32"  !CDS_PN = "32";
"VSS13":   PN = "35"  !CDS_PN = "35";
"VSS14":   PN = "37"  !CDS_PN = "37";
"VSS15":   PN = "39"  !CDS_PN = "39";
"VSS16":   PN = "41"  !CDS_PN = "41";
"VSS17":   PN = "43"  !CDS_PN = "43";
"VSS18":   PN = "46"  !CDS_PN = "46";
"VSS19":   PN = "48"  !CDS_PN = "48";
"VSS20":   PN = "50"  !CDS_PN = "50";
"VSS21":   PN = "52"  !CDS_PN = "52";
"VSS22":   PN = "54"  !CDS_PN = "54";
"VSS23":   PN = "57"  !CDS_PN = "57";
"VSS24":   PN = "59"  !CDS_PN = "59";
"VSS25":   PN = "61"  !CDS_PN = "61";
"VSS26":   PN = "63"  !CDS_PN = "63";
"VSS27":   PN = "65"  !CDS_PN = "65";
"VSS28":   PN = "67"  !CDS_PN = "67";
"VSS29":   PN = "69"  !CDS_PN = "69";
"VSS30":   PN = "71"  !CDS_PN = "71";
"VSS31":   PN = "73"  !CDS_PN = "73";
"VSS32":   PN = "75"  !CDS_PN = "75";
"VSS33":   PN = "77"  !CDS_PN = "77";
"VSS34":   PN = "79"  !CDS_PN = "79";
"VSS35":   PN = "81"  !CDS_PN = "81";
"VSS36":   PN = "83"  !CDS_PN = "83";
"VSS37":   PN = "85"  !CDS_PN = "85";
"VSS38":   PN = "88"  !CDS_PN = "88";
"VSS39":   PN = "90"  !CDS_PN = "90";
"VSS40":   PN = "92"  !CDS_PN = "92";
"VSS41":   PN = "95"  !CDS_PN = "95";
"VSS42":   PN = "97"  !CDS_PN = "97";
"VSS43":   PN = "99"  !CDS_PN = "99";
"VSS44":   PN = "101"  !CDS_PN = "101";
"VSS45":   PN = "103"  !CDS_PN = "103";
"VSS46":   PN = "106"  !CDS_PN = "106";
"VSS47":   PN = "108"  !CDS_PN = "108";
"VSS48":   PN = "110"  !CDS_PN = "110";
"VSS49":   PN = "112"  !CDS_PN = "112";
"VSS50":   PN = "114"  !CDS_PN = "114";
"VSS51":   PN = "117"  !CDS_PN = "117";
"VSS52":   PN = "119"  !CDS_PN = "119";
"VSS53":   PN = "121"  !CDS_PN = "121";
"VSS54":   PN = "123"  !CDS_PN = "123";
"VSS55":   PN = "125"  !CDS_PN = "125";
"VSS56":   PN = "128"  !CDS_PN = "128";
"VSS57":   PN = "130"  !CDS_PN = "130";
"VSS58":   PN = "132"  !CDS_PN = "132";
"VSS59":   PN = "134"  !CDS_PN = "134";
"VSS60":   PN = "136"  !CDS_PN = "136";
"VSS61":   PN = "139"  !CDS_PN = "139";
"VSS62":   PN = "141"  !CDS_PN = "141";
"VSS63":   PN = "143"  !CDS_PN = "143";
"VSS64":   PN = "151"  !CDS_PN = "151";
"VSS65":   PN = "153"  !CDS_PN = "153";
"VSS66":   PN = "155"  !CDS_PN = "155";
"VSS67":   PN = "158"  !CDS_PN = "158";
"VSS68":   PN = "160"  !CDS_PN = "160";
"VSS69":   PN = "162"  !CDS_PN = "162";
"VSS70":   PN = "164"  !CDS_PN = "164";
"VSS71":   PN = "166"  !CDS_PN = "166";
"VSS72":   PN = "169"  !CDS_PN = "169";
"VSS73":   PN = "171"  !CDS_PN = "171";
"VSS74":   PN = "173"  !CDS_PN = "173";
"VSS75":   PN = "175"  !CDS_PN = "175";
"VSS76":   PN = "177"  !CDS_PN = "177";
"VSS77":   PN = "180"  !CDS_PN = "180";
"VSS78":   PN = "182"  !CDS_PN = "182";
"VSS79":   PN = "184"  !CDS_PN = "184";
"VSS80":   PN = "186"  !CDS_PN = "186";
"VSS81":   PN = "188"  !CDS_PN = "188";
"VSS82":   PN = "191"  !CDS_PN = "191";
"VSS83":   PN = "193"  !CDS_PN = "193";
"VSS84":   PN = "195"  !CDS_PN = "195";
"VSS85":   PN = "197"  !CDS_PN = "197";
"VSS86":   PN = "199"  !CDS_PN = "199";
"VSS87":   PN = "202"  !CDS_PN = "202";
"VSS88":   PN = "204"  !CDS_PN = "204";
"VSS89":   PN = "206"  !CDS_PN = "206";
"VSS90":   PN = "208"  !CDS_PN = "208";
"VSS91":   PN = "210"  !CDS_PN = "210";
"VSS92":   PN = "212"  !CDS_PN = "212";
"VSS93":   PN = "214"  !CDS_PN = "214";
"VSS94":   PN = "216"  !CDS_PN = "216";
"VSS95":   PN = "219"  !CDS_PN = "219";
"VSS96":   PN = "222"  !CDS_PN = "222";
"VSS97":   PN = "224"  !CDS_PN = "224";
"VSS98":   PN = "226"  !CDS_PN = "226";
"VSS99":   PN = "228"  !CDS_PN = "228";
"VSS100":   PN = "230"  !CDS_PN = "230";
"VSS101":   PN = "233"  !CDS_PN = "233";
"VSS102":   PN = "235"  !CDS_PN = "235";
"VSS103":   PN = "237"  !CDS_PN = "237";
"VSS104":   PN = "240"  !CDS_PN = "240";
"VSS105":   PN = "242"  !CDS_PN = "242";
"VSS106":   PN = "244"  !CDS_PN = "244";
"VSS107":   PN = "246"  !CDS_PN = "246";
"VSS108":   PN = "248"  !CDS_PN = "248";
"VSS109":   PN = "251"  !CDS_PN = "251";
"VSS110":   PN = "253"  !CDS_PN = "253";
"VSS111":   PN = "255"  !CDS_PN = "255";
"VSS112":   PN = "257"  !CDS_PN = "257";
"VSS113":   PN = "259"  !CDS_PN = "259";
"VSS114":   PN = "262"  !CDS_PN = "262";
"VSS115":   PN = "264"  !CDS_PN = "264";
"VSS116":   PN = "266"  !CDS_PN = "266";
"VSS117":   PN = "268"  !CDS_PN = "268";
"VSS118":   PN = "270"  !CDS_PN = "270";
"VSS119":   PN = "273"  !CDS_PN = "273";
"VSS120":   PN = "275"  !CDS_PN = "275";
"VSS121":   PN = "277"  !CDS_PN = "277";
"VSS122":   PN = "279"  !CDS_PN = "279";
"VSS123":   PN = "281"  !CDS_PN = "281";
"VSS124":   PN = "284"  !CDS_PN = "284";
"VSS125":   PN = "286"  !CDS_PN = "286";
"VSS126":   PN = "288"  !CDS_PN = "288";
BODY = "SCONN288_ADR50017P087CC","I178": #LOCATION = "J12" !CDS_LOCATION = "J12" &SEC = "2" #&CDS_SEC = "2";
"DQS0_A_C":   PN = "12"  !CDS_PN = "12";
"DQS0_A_T":   PN = "11"  !CDS_PN = "11";
"DQS0_B_C":   PN = "105"  !CDS_PN = "105";
"DQS0_B_T":   PN = "104"  !CDS_PN = "104";
"DQS1_A_C":   PN = "23"  !CDS_PN = "23";
"DQS1_A_T":   PN = "22"  !CDS_PN = "22";
"DQS1_B_C":   PN = "116"  !CDS_PN = "116";
"DQS1_B_T":   PN = "115"  !CDS_PN = "115";
"DQS2_A_C":   PN = "34"  !CDS_PN = "34";
"DQS2_A_T":   PN = "33"  !CDS_PN = "33";
"DQS2_B_C":   PN = "127"  !CDS_PN = "127";
"DQS2_B_T":   PN = "126"  !CDS_PN = "126";
"DQS3_A_C":   PN = "45"  !CDS_PN = "45";
"DQS3_A_T":   PN = "44"  !CDS_PN = "44";
"DQS3_B_C":   PN = "138"  !CDS_PN = "138";
"DQS3_B_T":   PN = "137"  !CDS_PN = "137";
"DQS4_A_C":   PN = "56"  !CDS_PN = "56";
"DQS4_A_T":   PN = "55"  !CDS_PN = "55";
"DQS4_B_C":   PN = "238"  !CDS_PN = "238";
"DQS4_B_T":   PN = "239"  !CDS_PN = "239";
"DQS5_A_C||TDQS5_A_C||DQS5_A_T||TDQS5_A_T":   PN = "156"  !CDS_PN = "156";
"DQS5_A_T||TDQS5_A_T":   PN = "157"  !CDS_PN = "157";
"DQS5_B_C||TDQS5_B_C":   PN = "249"  !CDS_PN = "249";
"DQS5_B_T||TDQS5_B_T":   PN = "250"  !CDS_PN = "250";
"DQS6_A_C||TDQS6_A_C||DQS6_A_T||TDQS6_A_T":   PN = "167"  !CDS_PN = "167";
"DQS6_A_T||TDQS6_A_T":   PN = "168"  !CDS_PN = "168";
"DQS6_B_C||TDQS6_B_C":   PN = "260"  !CDS_PN = "260";
"DQS6_B_T||TDQS6_B_T":   PN = "261"  !CDS_PN = "261";
"DQS7_A_C||TDQS7_A_C":   PN = "178"  !CDS_PN = "178";
"DQS7_A_T||TDQS7_A_T":   PN = "179"  !CDS_PN = "179";
"DQS7_B_C||TDQS7_B_C":   PN = "271"  !CDS_PN = "271";
"DQS7_B_T||TDQS7_B_T":   PN = "272"  !CDS_PN = "272";
"DQS8_A_C||TDQS8_A_C":   PN = "189"  !CDS_PN = "189";
"DQS8_A_T||TDQS8_A_T":   PN = "190"  !CDS_PN = "190";
"DQS8_B_C||TDQS8_B_C":   PN = "282"  !CDS_PN = "282";
"DQS8_B_T||TDQS8_B_T":   PN = "283"  !CDS_PN = "283";
"DQS9_A_C||TDQS9_A_C":   PN = "200"  !CDS_PN = "200";
"DQS9_A_T||TDQS9_A_T":   PN = "201"  !CDS_PN = "201";
"DQS9_B_C||TDQS9_B_C":   PN = "94"  !CDS_PN = "94";
"DQS9_B_T||TDQS9_B_T||DBI4_B_N":   PN = "93"  !CDS_PN = "93";
BODY = "Q_RES","I179": LOCATION = "R3886" #&CDS_LOCATION = "R3886" &SEC = "1" #&CDS_SEC = "1";
"A":   PN = "1"  !CDS_PN = "1";
"B":   PN = "2"  !CDS_PN = "2";
DRAWING = "@s9s_mb_2u_lib.s9s_mb_2u(sch_1):page94";
BODY = "Q_RES","I10": LOCATION = "R38" #&CDS_LOCATION = "R38" &SEC = "1" #&CDS_SEC = "1";
"A":   PN = "1"  !CDS_PN = "1";
"B":   PN = "2"  !CDS_PN = "2";
BODY = "SCONN288_ADR50017P130CC","I11": LOCATION = "J13" #&CDS_LOCATION = "J13" &SEC = "1" #&CDS_SEC = "1";
"ALERT_N":   PN = "62"  !CDS_PN = "62";
"CA0_A":   PN = "66"  !CDS_PN = "66";
"CA0_B":   PN = "76"  !CDS_PN = "76";
"CA1_A":   PN = "211"  !CDS_PN = "211";
"CA1_B":   PN = "221"  !CDS_PN = "221";
"CA2_A":   PN = "68"  !CDS_PN = "68";
"CA2_B":   PN = "78"  !CDS_PN = "78";
"CA3_A":   PN = "213"  !CDS_PN = "213";
"CA3_B":   PN = "223"  !CDS_PN = "223";
"CA4_A":   PN = "70"  !CDS_PN = "70";
"CA4_B":   PN = "80"  !CDS_PN = "80";
"CA5_A":   PN = "215"  !CDS_PN = "215";
"CA5_B":   PN = "225"  !CDS_PN = "225";
"CA6_A":   PN = "72"  !CDS_PN = "72";
"CA6_B":   PN = "82"  !CDS_PN = "82";
"CB0_A":   PN = "51"  !CDS_PN = "51";
"CB0_B":   PN = "96"  !CDS_PN = "96";
"CB1_A":   PN = "53"  !CDS_PN = "53";
"CB1_B":   PN = "98"  !CDS_PN = "98";
"CB2_A":   PN = "196"  !CDS_PN = "196";
"CB2_B":   PN = "241"  !CDS_PN = "241";
"CB3_A":   PN = "198"  !CDS_PN = "198";
"CB3_B":   PN = "243"  !CDS_PN = "243";
"CB4_A":   PN = "58"  !CDS_PN = "58";
"CB4_B":   PN = "89"  !CDS_PN = "89";
"CB5_A":   PN = "60"  !CDS_PN = "60";
"CB5_B":   PN = "91"  !CDS_PN = "91";
"CB6_A":   PN = "203"  !CDS_PN = "203";
"CB6_B":   PN = "234"  !CDS_PN = "234";
"CB7_A":   PN = "205"  !CDS_PN = "205";
"CB7_B":   PN = "236"  !CDS_PN = "236";
"CK_C":   PN = "218"  !CDS_PN = "218";
"CK_T":   PN = "217"  !CDS_PN = "217";
"CS0_A_N":   PN = "64"  !CDS_PN = "64";
"CS0_B_N":   PN = "84"  !CDS_PN = "84";
"CS1_A_N":   PN = "209"  !CDS_PN = "209";
"CS1_B_N":   PN = "229"  !CDS_PN = "229";
"DQ0_A":   PN = "7"  !CDS_PN = "7";
"DQ0_B":   PN = "100"  !CDS_PN = "100";
"DQ1_A":   PN = "9"  !CDS_PN = "9";
"DQ1_B":   PN = "102"  !CDS_PN = "102";
"DQ2_A":   PN = "152"  !CDS_PN = "152";
"DQ2_B":   PN = "245"  !CDS_PN = "245";
"DQ3_A":   PN = "154"  !CDS_PN = "154";
"DQ3_B":   PN = "247"  !CDS_PN = "247";
"DQ4_A":   PN = "14"  !CDS_PN = "14";
"DQ4_B":   PN = "107"  !CDS_PN = "107";
"DQ5_A":   PN = "16"  !CDS_PN = "16";
"DQ5_B":   PN = "109"  !CDS_PN = "109";
"DQ6_A":   PN = "159"  !CDS_PN = "159";
"DQ6_B":   PN = "252"  !CDS_PN = "252";
"DQ7_A":   PN = "161"  !CDS_PN = "161";
"DQ7_B":   PN = "254"  !CDS_PN = "254";
"DQ8_A":   PN = "18"  !CDS_PN = "18";
"DQ8_B":   PN = "111"  !CDS_PN = "111";
"DQ9_A":   PN = "20"  !CDS_PN = "20";
"DQ9_B":   PN = "113"  !CDS_PN = "113";
"DQ10_A":   PN = "163"  !CDS_PN = "163";
"DQ10_B":   PN = "256"  !CDS_PN = "256";
"DQ11_A":   PN = "165"  !CDS_PN = "165";
"DQ11_B":   PN = "258"  !CDS_PN = "258";
"DQ12_A":   PN = "25"  !CDS_PN = "25";
"DQ12_B":   PN = "118"  !CDS_PN = "118";
"DQ13_A":   PN = "27"  !CDS_PN = "27";
"DQ13_B":   PN = "120"  !CDS_PN = "120";
"DQ14_A":   PN = "170"  !CDS_PN = "170";
"DQ14_B":   PN = "263"  !CDS_PN = "263";
"DQ15_A":   PN = "172"  !CDS_PN = "172";
"DQ15_B":   PN = "265"  !CDS_PN = "265";
"DQ16_A":   PN = "29"  !CDS_PN = "29";
"DQ16_B":   PN = "122"  !CDS_PN = "122";
"DQ17_A":   PN = "31"  !CDS_PN = "31";
"DQ17_B":   PN = "124"  !CDS_PN = "124";
"DQ18_A":   PN = "174"  !CDS_PN = "174";
"DQ18_B":   PN = "267"  !CDS_PN = "267";
"DQ19_A":   PN = "176"  !CDS_PN = "176";
"DQ19_B":   PN = "269"  !CDS_PN = "269";
"DQ20_A":   PN = "36"  !CDS_PN = "36";
"DQ20_B":   PN = "129"  !CDS_PN = "129";
"DQ21_A":   PN = "38"  !CDS_PN = "38";
"DQ21_B":   PN = "131"  !CDS_PN = "131";
"DQ22_A":   PN = "181"  !CDS_PN = "181";
"DQ22_B":   PN = "274"  !CDS_PN = "274";
"DQ23_A":   PN = "183"  !CDS_PN = "183";
"DQ23_B":   PN = "276"  !CDS_PN = "276";
"DQ24_A":   PN = "40"  !CDS_PN = "40";
"DQ24_B":   PN = "133"  !CDS_PN = "133";
"DQ25_A":   PN = "42"  !CDS_PN = "42";
"DQ25_B":   PN = "135"  !CDS_PN = "135";
"DQ26_A":   PN = "185"  !CDS_PN = "185";
"DQ26_B":   PN = "278"  !CDS_PN = "278";
"DQ27_A":   PN = "187"  !CDS_PN = "187";
"DQ27_B":   PN = "280"  !CDS_PN = "280";
"DQ28_A":   PN = "47"  !CDS_PN = "47";
"DQ28_B":   PN = "140"  !CDS_PN = "140";
"DQ29_A":   PN = "49"  !CDS_PN = "49";
"DQ29_B":   PN = "142"  !CDS_PN = "142";
"DQ30_A":   PN = "192"  !CDS_PN = "192";
"DQ30_B":   PN = "285"  !CDS_PN = "285";
"DQ31_A":   PN = "194"  !CDS_PN = "194";
"DQ31_B":   PN = "287"  !CDS_PN = "287";
"HSA":   PN = "148"  !CDS_PN = "148";
"HSCL":   PN = "4"  !CDS_PN = "4";
"HSDA":   PN = "5"  !CDS_PN = "5";
"LBD||RSP_A_N":   PN = "86"  !CDS_PN = "86";
"LBS||RSP_B_N":   PN = "87"  !CDS_PN = "87";
"PAR_A":   PN = "74"  !CDS_PN = "74";
"PAR_B":   PN = "227"  !CDS_PN = "227";
"PWR_GOOD||FAIL_N":   PN = "147"  !CDS_PN = "147";
"RESET_N":   PN = "207"  !CDS_PN = "207";
"RFU0":   PN = "2"  !CDS_PN = "2";
"RFU1":   PN = "144"  !CDS_PN = "144";
"RFU2":   PN = "149"  !CDS_PN = "149";
"RFU3":   PN = "150"  !CDS_PN = "150";
"RFU4":   PN = "220"  !CDS_PN = "220";
"RFU5":   PN = "231"  !CDS_PN = "231";
"RFU6":   PN = "232"  !CDS_PN = "232";
"VIN_MGMT":   PN = "3"  !CDS_PN = "3";
BODY = "Q_CAP","I123": LOCATION = "C38" #&CDS_LOCATION = "C38" &SEC = "1" #&CDS_SEC = "1";
"A":   PN = "1"  !CDS_PN = "1";
"B":   PN = "2"  !CDS_PN = "2";
BODY = "Q_CAP","I125": LOCATION = "C39" #&CDS_LOCATION = "C39" &SEC = "1" #&CDS_SEC = "1";
"A":   PN = "1"  !CDS_PN = "1";
"B":   PN = "2"  !CDS_PN = "2";
BODY = "Q_CAP","I162": LOCATION = "C40" #&CDS_LOCATION = "C40" &SEC = "1" #&CDS_SEC = "1";
"A":   PN = "1"  !CDS_PN = "1";
"B":   PN = "2"  !CDS_PN = "2";
BODY = "SCONN288_ADR50017P130CC","I164": LOCATION = "J13" #&CDS_LOCATION = "J13" &SEC = "3" #&CDS_SEC = "3";
"G1":   PN = "G1"  !CDS_PN = "G1";
"G2":   PN = "G2"  !CDS_PN = "G2";
"G3":   PN = "G3"  !CDS_PN = "G3";
"VIN_BULK0":   PN = "1"  !CDS_PN = "1";
"VIN_BULK1":   PN = "145"  !CDS_PN = "145";
"VIN_BULK2":   PN = "146"  !CDS_PN = "146";
"VSS0":   PN = "6"  !CDS_PN = "6";
"VSS1":   PN = "8"  !CDS_PN = "8";
"VSS2":   PN = "10"  !CDS_PN = "10";
"VSS3":   PN = "13"  !CDS_PN = "13";
"VSS4":   PN = "15"  !CDS_PN = "15";
"VSS5":   PN = "17"  !CDS_PN = "17";
"VSS6":   PN = "19"  !CDS_PN = "19";
"VSS7":   PN = "21"  !CDS_PN = "21";
"VSS8":   PN = "24"  !CDS_PN = "24";
"VSS9":   PN = "26"  !CDS_PN = "26";
"VSS10":   PN = "28"  !CDS_PN = "28";
"VSS11":   PN = "30"  !CDS_PN = "30";
"VSS12":   PN = "32"  !CDS_PN = "32";
"VSS13":   PN = "35"  !CDS_PN = "35";
"VSS14":   PN = "37"  !CDS_PN = "37";
"VSS15":   PN = "39"  !CDS_PN = "39";
"VSS16":   PN = "41"  !CDS_PN = "41";
"VSS17":   PN = "43"  !CDS_PN = "43";
"VSS18":   PN = "46"  !CDS_PN = "46";
"VSS19":   PN = "48"  !CDS_PN = "48";
"VSS20":   PN = "50"  !CDS_PN = "50";
"VSS21":   PN = "52"  !CDS_PN = "52";
"VSS22":   PN = "54"  !CDS_PN = "54";
"VSS23":   PN = "57"  !CDS_PN = "57";
"VSS24":   PN = "59"  !CDS_PN = "59";
"VSS25":   PN = "61"  !CDS_PN = "61";
"VSS26":   PN = "63"  !CDS_PN = "63";
"VSS27":   PN = "65"  !CDS_PN = "65";
"VSS28":   PN = "67"  !CDS_PN = "67";
"VSS29":   PN = "69"  !CDS_PN = "69";
"VSS30":   PN = "71"  !CDS_PN = "71";
"VSS31":   PN = "73"  !CDS_PN = "73";
"VSS32":   PN = "75"  !CDS_PN = "75";
"VSS33":   PN = "77"  !CDS_PN = "77";
"VSS34":   PN = "79"  !CDS_PN = "79";
"VSS35":   PN = "81"  !CDS_PN = "81";
"VSS36":   PN = "83"  !CDS_PN = "83";
"VSS37":   PN = "85"  !CDS_PN = "85";
"VSS38":   PN = "88"  !CDS_PN = "88";
"VSS39":   PN = "90"  !CDS_PN = "90";
"VSS40":   PN = "92"  !CDS_PN = "92";
"VSS41":   PN = "95"  !CDS_PN = "95";
"VSS42":   PN = "97"  !CDS_PN = "97";
"VSS43":   PN = "99"  !CDS_PN = "99";
"VSS44":   PN = "101"  !CDS_PN = "101";
"VSS45":   PN = "103"  !CDS_PN = "103";
"VSS46":   PN = "106"  !CDS_PN = "106";
"VSS47":   PN = "108"  !CDS_PN = "108";
"VSS48":   PN = "110"  !CDS_PN = "110";
"VSS49":   PN = "112"  !CDS_PN = "112";
"VSS50":   PN = "114"  !CDS_PN = "114";
"VSS51":   PN = "117"  !CDS_PN = "117";
"VSS52":   PN = "119"  !CDS_PN = "119";
"VSS53":   PN = "121"  !CDS_PN = "121";
"VSS54":   PN = "123"  !CDS_PN = "123";
"VSS55":   PN = "125"  !CDS_PN = "125";
"VSS56":   PN = "128"  !CDS_PN = "128";
"VSS57":   PN = "130"  !CDS_PN = "130";
"VSS58":   PN = "132"  !CDS_PN = "132";
"VSS59":   PN = "134"  !CDS_PN = "134";
"VSS60":   PN = "136"  !CDS_PN = "136";
"VSS61":   PN = "139"  !CDS_PN = "139";
"VSS62":   PN = "141"  !CDS_PN = "141";
"VSS63":   PN = "143"  !CDS_PN = "143";
"VSS64":   PN = "151"  !CDS_PN = "151";
"VSS65":   PN = "153"  !CDS_PN = "153";
"VSS66":   PN = "155"  !CDS_PN = "155";
"VSS67":   PN = "158"  !CDS_PN = "158";
"VSS68":   PN = "160"  !CDS_PN = "160";
"VSS69":   PN = "162"  !CDS_PN = "162";
"VSS70":   PN = "164"  !CDS_PN = "164";
"VSS71":   PN = "166"  !CDS_PN = "166";
"VSS72":   PN = "169"  !CDS_PN = "169";
"VSS73":   PN = "171"  !CDS_PN = "171";
"VSS74":   PN = "173"  !CDS_PN = "173";
"VSS75":   PN = "175"  !CDS_PN = "175";
"VSS76":   PN = "177"  !CDS_PN = "177";
"VSS77":   PN = "180"  !CDS_PN = "180";
"VSS78":   PN = "182"  !CDS_PN = "182";
"VSS79":   PN = "184"  !CDS_PN = "184";
"VSS80":   PN = "186"  !CDS_PN = "186";
"VSS81":   PN = "188"  !CDS_PN = "188";
"VSS82":   PN = "191"  !CDS_PN = "191";
"VSS83":   PN = "193"  !CDS_PN = "193";
"VSS84":   PN = "195"  !CDS_PN = "195";
"VSS85":   PN = "197"  !CDS_PN = "197";
"VSS86":   PN = "199"  !CDS_PN = "199";
"VSS87":   PN = "202"  !CDS_PN = "202";
"VSS88":   PN = "204"  !CDS_PN = "204";
"VSS89":   PN = "206"  !CDS_PN = "206";
"VSS90":   PN = "208"  !CDS_PN = "208";
"VSS91":   PN = "210"  !CDS_PN = "210";
"VSS92":   PN = "212"  !CDS_PN = "212";
"VSS93":   PN = "214"  !CDS_PN = "214";
"VSS94":   PN = "216"  !CDS_PN = "216";
"VSS95":   PN = "219"  !CDS_PN = "219";
"VSS96":   PN = "222"  !CDS_PN = "222";
"VSS97":   PN = "224"  !CDS_PN = "224";
"VSS98":   PN = "226"  !CDS_PN = "226";
"VSS99":   PN = "228"  !CDS_PN = "228";
"VSS100":   PN = "230"  !CDS_PN = "230";
"VSS101":   PN = "233"  !CDS_PN = "233";
"VSS102":   PN = "235"  !CDS_PN = "235";
"VSS103":   PN = "237"  !CDS_PN = "237";
"VSS104":   PN = "240"  !CDS_PN = "240";
"VSS105":   PN = "242"  !CDS_PN = "242";
"VSS106":   PN = "244"  !CDS_PN = "244";
"VSS107":   PN = "246"  !CDS_PN = "246";
"VSS108":   PN = "248"  !CDS_PN = "248";
"VSS109":   PN = "251"  !CDS_PN = "251";
"VSS110":   PN = "253"  !CDS_PN = "253";
"VSS111":   PN = "255"  !CDS_PN = "255";
"VSS112":   PN = "257"  !CDS_PN = "257";
"VSS113":   PN = "259"  !CDS_PN = "259";
"VSS114":   PN = "262"  !CDS_PN = "262";
"VSS115":   PN = "264"  !CDS_PN = "264";
"VSS116":   PN = "266"  !CDS_PN = "266";
"VSS117":   PN = "268"  !CDS_PN = "268";
"VSS118":   PN = "270"  !CDS_PN = "270";
"VSS119":   PN = "273"  !CDS_PN = "273";
"VSS120":   PN = "275"  !CDS_PN = "275";
"VSS121":   PN = "277"  !CDS_PN = "277";
"VSS122":   PN = "279"  !CDS_PN = "279";
"VSS123":   PN = "281"  !CDS_PN = "281";
"VSS124":   PN = "284"  !CDS_PN = "284";
"VSS125":   PN = "286"  !CDS_PN = "286";
"VSS126":   PN = "288"  !CDS_PN = "288";
BODY = "SCONN288_ADR50017P130CC","I178": #LOCATION = "J13" !CDS_LOCATION = "J13" &SEC = "2" #&CDS_SEC = "2";
"DQS0_A_C":   PN = "12"  !CDS_PN = "12";
"DQS0_A_T":   PN = "11"  !CDS_PN = "11";
"DQS0_B_C":   PN = "105"  !CDS_PN = "105";
"DQS0_B_T":   PN = "104"  !CDS_PN = "104";
"DQS1_A_C":   PN = "23"  !CDS_PN = "23";
"DQS1_A_T":   PN = "22"  !CDS_PN = "22";
"DQS1_B_C":   PN = "116"  !CDS_PN = "116";
"DQS1_B_T":   PN = "115"  !CDS_PN = "115";
"DQS2_A_C":   PN = "34"  !CDS_PN = "34";
"DQS2_A_T":   PN = "33"  !CDS_PN = "33";
"DQS2_B_C":   PN = "127"  !CDS_PN = "127";
"DQS2_B_T":   PN = "126"  !CDS_PN = "126";
"DQS3_A_C":   PN = "45"  !CDS_PN = "45";
"DQS3_A_T":   PN = "44"  !CDS_PN = "44";
"DQS3_B_C":   PN = "138"  !CDS_PN = "138";
"DQS3_B_T":   PN = "137"  !CDS_PN = "137";
"DQS4_A_C":   PN = "56"  !CDS_PN = "56";
"DQS4_A_T":   PN = "55"  !CDS_PN = "55";
"DQS4_B_C":   PN = "238"  !CDS_PN = "238";
"DQS4_B_T":   PN = "239"  !CDS_PN = "239";
"DQS5_A_C||TDQS5_A_C||DQS5_A_T||TDQS5_A_T":   PN = "156"  !CDS_PN = "156";
"DQS5_A_T||TDQS5_A_T":   PN = "157"  !CDS_PN = "157";
"DQS5_B_C||TDQS5_B_C":   PN = "249"  !CDS_PN = "249";
"DQS5_B_T||TDQS5_B_T":   PN = "250"  !CDS_PN = "250";
"DQS6_A_C||TDQS6_A_C||DQS6_A_T||TDQS6_A_T":   PN = "167"  !CDS_PN = "167";
"DQS6_A_T||TDQS6_A_T":   PN = "168"  !CDS_PN = "168";
"DQS6_B_C||TDQS6_B_C":   PN = "260"  !CDS_PN = "260";
"DQS6_B_T||TDQS6_B_T":   PN = "261"  !CDS_PN = "261";
"DQS7_A_C||TDQS7_A_C":   PN = "178"  !CDS_PN = "178";
"DQS7_A_T||TDQS7_A_T":   PN = "179"  !CDS_PN = "179";
"DQS7_B_C||TDQS7_B_C":   PN = "271"  !CDS_PN = "271";
"DQS7_B_T||TDQS7_B_T":   PN = "272"  !CDS_PN = "272";
"DQS8_A_C||TDQS8_A_C":   PN = "189"  !CDS_PN = "189";
"DQS8_A_T||TDQS8_A_T":   PN = "190"  !CDS_PN = "190";
"DQS8_B_C||TDQS8_B_C":   PN = "282"  !CDS_PN = "282";
"DQS8_B_T||TDQS8_B_T":   PN = "283"  !CDS_PN = "283";
"DQS9_A_C||TDQS9_A_C":   PN = "200"  !CDS_PN = "200";
"DQS9_A_T||TDQS9_A_T":   PN = "201"  !CDS_PN = "201";
"DQS9_B_C||TDQS9_B_C":   PN = "94"  !CDS_PN = "94";
"DQS9_B_T||TDQS9_B_T||DBI4_B_N":   PN = "93"  !CDS_PN = "93";
BODY = "Q_RES","I179": LOCATION = "R3887" #&CDS_LOCATION = "R3887" &SEC = "1" #&CDS_SEC = "1";
"A":   PN = "1"  !CDS_PN = "1";
"B":   PN = "2"  !CDS_PN = "2";
DRAWING = "@s9s_mb_2u_lib.s9s_mb_2u(sch_1):page95";
BODY = "Q_RES","I46": LOCATION = "R39" #&CDS_LOCATION = "R39" &SEC = "1" #&CDS_SEC = "1";
"A":   PN = "1"  !CDS_PN = "1";
"B":   PN = "2"  !CDS_PN = "2";
BODY = "SCONN288_ADR50017P087CC","I47": LOCATION = "J14" #&CDS_LOCATION = "J14" &SEC = "1" #&CDS_SEC = "1";
"ALERT_N":   PN = "62"  !CDS_PN = "62";
"CA0_A":   PN = "66"  !CDS_PN = "66";
"CA0_B":   PN = "76"  !CDS_PN = "76";
"CA1_A":   PN = "211"  !CDS_PN = "211";
"CA1_B":   PN = "221"  !CDS_PN = "221";
"CA2_A":   PN = "68"  !CDS_PN = "68";
"CA2_B":   PN = "78"  !CDS_PN = "78";
"CA3_A":   PN = "213"  !CDS_PN = "213";
"CA3_B":   PN = "223"  !CDS_PN = "223";
"CA4_A":   PN = "70"  !CDS_PN = "70";
"CA4_B":   PN = "80"  !CDS_PN = "80";
"CA5_A":   PN = "215"  !CDS_PN = "215";
"CA5_B":   PN = "225"  !CDS_PN = "225";
"CA6_A":   PN = "72"  !CDS_PN = "72";
"CA6_B":   PN = "82"  !CDS_PN = "82";
"CB0_A":   PN = "51"  !CDS_PN = "51";
"CB0_B":   PN = "96"  !CDS_PN = "96";
"CB1_A":   PN = "53"  !CDS_PN = "53";
"CB1_B":   PN = "98"  !CDS_PN = "98";
"CB2_A":   PN = "196"  !CDS_PN = "196";
"CB2_B":   PN = "241"  !CDS_PN = "241";
"CB3_A":   PN = "198"  !CDS_PN = "198";
"CB3_B":   PN = "243"  !CDS_PN = "243";
"CB4_A":   PN = "58"  !CDS_PN = "58";
"CB4_B":   PN = "89"  !CDS_PN = "89";
"CB5_A":   PN = "60"  !CDS_PN = "60";
"CB5_B":   PN = "91"  !CDS_PN = "91";
"CB6_A":   PN = "203"  !CDS_PN = "203";
"CB6_B":   PN = "234"  !CDS_PN = "234";
"CB7_A":   PN = "205"  !CDS_PN = "205";
"CB7_B":   PN = "236"  !CDS_PN = "236";
"CK_C":   PN = "218"  !CDS_PN = "218";
"CK_T":   PN = "217"  !CDS_PN = "217";
"CS0_A_N":   PN = "64"  !CDS_PN = "64";
"CS0_B_N":   PN = "84"  !CDS_PN = "84";
"CS1_A_N":   PN = "209"  !CDS_PN = "209";
"CS1_B_N":   PN = "229"  !CDS_PN = "229";
"DQ0_A":   PN = "7"  !CDS_PN = "7";
"DQ0_B":   PN = "100"  !CDS_PN = "100";
"DQ1_A":   PN = "9"  !CDS_PN = "9";
"DQ1_B":   PN = "102"  !CDS_PN = "102";
"DQ2_A":   PN = "152"  !CDS_PN = "152";
"DQ2_B":   PN = "245"  !CDS_PN = "245";
"DQ3_A":   PN = "154"  !CDS_PN = "154";
"DQ3_B":   PN = "247"  !CDS_PN = "247";
"DQ4_A":   PN = "14"  !CDS_PN = "14";
"DQ4_B":   PN = "107"  !CDS_PN = "107";
"DQ5_A":   PN = "16"  !CDS_PN = "16";
"DQ5_B":   PN = "109"  !CDS_PN = "109";
"DQ6_A":   PN = "159"  !CDS_PN = "159";
"DQ6_B":   PN = "252"  !CDS_PN = "252";
"DQ7_A":   PN = "161"  !CDS_PN = "161";
"DQ7_B":   PN = "254"  !CDS_PN = "254";
"DQ8_A":   PN = "18"  !CDS_PN = "18";
"DQ8_B":   PN = "111"  !CDS_PN = "111";
"DQ9_A":   PN = "20"  !CDS_PN = "20";
"DQ9_B":   PN = "113"  !CDS_PN = "113";
"DQ10_A":   PN = "163"  !CDS_PN = "163";
"DQ10_B":   PN = "256"  !CDS_PN = "256";
"DQ11_A":   PN = "165"  !CDS_PN = "165";
"DQ11_B":   PN = "258"  !CDS_PN = "258";
"DQ12_A":   PN = "25"  !CDS_PN = "25";
"DQ12_B":   PN = "118"  !CDS_PN = "118";
"DQ13_A":   PN = "27"  !CDS_PN = "27";
"DQ13_B":   PN = "120"  !CDS_PN = "120";
"DQ14_A":   PN = "170"  !CDS_PN = "170";
"DQ14_B":   PN = "263"  !CDS_PN = "263";
"DQ15_A":   PN = "172"  !CDS_PN = "172";
"DQ15_B":   PN = "265"  !CDS_PN = "265";
"DQ16_A":   PN = "29"  !CDS_PN = "29";
"DQ16_B":   PN = "122"  !CDS_PN = "122";
"DQ17_A":   PN = "31"  !CDS_PN = "31";
"DQ17_B":   PN = "124"  !CDS_PN = "124";
"DQ18_A":   PN = "174"  !CDS_PN = "174";
"DQ18_B":   PN = "267"  !CDS_PN = "267";
"DQ19_A":   PN = "176"  !CDS_PN = "176";
"DQ19_B":   PN = "269"  !CDS_PN = "269";
"DQ20_A":   PN = "36"  !CDS_PN = "36";
"DQ20_B":   PN = "129"  !CDS_PN = "129";
"DQ21_A":   PN = "38"  !CDS_PN = "38";
"DQ21_B":   PN = "131"  !CDS_PN = "131";
"DQ22_A":   PN = "181"  !CDS_PN = "181";
"DQ22_B":   PN = "274"  !CDS_PN = "274";
"DQ23_A":   PN = "183"  !CDS_PN = "183";
"DQ23_B":   PN = "276"  !CDS_PN = "276";
"DQ24_A":   PN = "40"  !CDS_PN = "40";
"DQ24_B":   PN = "133"  !CDS_PN = "133";
"DQ25_A":   PN = "42"  !CDS_PN = "42";
"DQ25_B":   PN = "135"  !CDS_PN = "135";
"DQ26_A":   PN = "185"  !CDS_PN = "185";
"DQ26_B":   PN = "278"  !CDS_PN = "278";
"DQ27_A":   PN = "187"  !CDS_PN = "187";
"DQ27_B":   PN = "280"  !CDS_PN = "280";
"DQ28_A":   PN = "47"  !CDS_PN = "47";
"DQ28_B":   PN = "140"  !CDS_PN = "140";
"DQ29_A":   PN = "49"  !CDS_PN = "49";
"DQ29_B":   PN = "142"  !CDS_PN = "142";
"DQ30_A":   PN = "192"  !CDS_PN = "192";
"DQ30_B":   PN = "285"  !CDS_PN = "285";
"DQ31_A":   PN = "194"  !CDS_PN = "194";
"DQ31_B":   PN = "287"  !CDS_PN = "287";
"HSA":   PN = "148"  !CDS_PN = "148";
"HSCL":   PN = "4"  !CDS_PN = "4";
"HSDA":   PN = "5"  !CDS_PN = "5";
"LBD||RSP_A_N":   PN = "86"  !CDS_PN = "86";
"LBS||RSP_B_N":   PN = "87"  !CDS_PN = "87";
"PAR_A":   PN = "74"  !CDS_PN = "74";
"PAR_B":   PN = "227"  !CDS_PN = "227";
"PWR_GOOD||FAIL_N":   PN = "147"  !CDS_PN = "147";
"RESET_N":   PN = "207"  !CDS_PN = "207";
"RFU0":   PN = "2"  !CDS_PN = "2";
"RFU1":   PN = "144"  !CDS_PN = "144";
"RFU2":   PN = "149"  !CDS_PN = "149";
"RFU3":   PN = "150"  !CDS_PN = "150";
"RFU4":   PN = "220"  !CDS_PN = "220";
"RFU5":   PN = "231"  !CDS_PN = "231";
"RFU6":   PN = "232"  !CDS_PN = "232";
"VIN_MGMT":   PN = "3"  !CDS_PN = "3";
BODY = "Q_CAP","I121": LOCATION = "C41" #&CDS_LOCATION = "C41" &SEC = "1" #&CDS_SEC = "1";
"A":   PN = "1"  !CDS_PN = "1";
"B":   PN = "2"  !CDS_PN = "2";
BODY = "Q_CAP","I125": LOCATION = "C42" #&CDS_LOCATION = "C42" &SEC = "1" #&CDS_SEC = "1";
"A":   PN = "1"  !CDS_PN = "1";
"B":   PN = "2"  !CDS_PN = "2";
BODY = "Q_CAP","I128": LOCATION = "C43" #&CDS_LOCATION = "C43" &SEC = "1" #&CDS_SEC = "1";
"A":   PN = "1"  !CDS_PN = "1";
"B":   PN = "2"  !CDS_PN = "2";
BODY = "SCONN288_ADR50017P087CC","I176": LOCATION = "J14" #&CDS_LOCATION = "J14" &SEC = "3" #&CDS_SEC = "3";
"G1":   PN = "G1"  !CDS_PN = "G1";
"G2":   PN = "G2"  !CDS_PN = "G2";
"G3":   PN = "G3"  !CDS_PN = "G3";
"VIN_BULK0":   PN = "1"  !CDS_PN = "1";
"VIN_BULK1":   PN = "145"  !CDS_PN = "145";
"VIN_BULK2":   PN = "146"  !CDS_PN = "146";
"VSS0":   PN = "6"  !CDS_PN = "6";
"VSS1":   PN = "8"  !CDS_PN = "8";
"VSS2":   PN = "10"  !CDS_PN = "10";
"VSS3":   PN = "13"  !CDS_PN = "13";
"VSS4":   PN = "15"  !CDS_PN = "15";
"VSS5":   PN = "17"  !CDS_PN = "17";
"VSS6":   PN = "19"  !CDS_PN = "19";
"VSS7":   PN = "21"  !CDS_PN = "21";
"VSS8":   PN = "24"  !CDS_PN = "24";
"VSS9":   PN = "26"  !CDS_PN = "26";
"VSS10":   PN = "28"  !CDS_PN = "28";
"VSS11":   PN = "30"  !CDS_PN = "30";
"VSS12":   PN = "32"  !CDS_PN = "32";
"VSS13":   PN = "35"  !CDS_PN = "35";
"VSS14":   PN = "37"  !CDS_PN = "37";
"VSS15":   PN = "39"  !CDS_PN = "39";
"VSS16":   PN = "41"  !CDS_PN = "41";
"VSS17":   PN = "43"  !CDS_PN = "43";
"VSS18":   PN = "46"  !CDS_PN = "46";
"VSS19":   PN = "48"  !CDS_PN = "48";
"VSS20":   PN = "50"  !CDS_PN = "50";
"VSS21":   PN = "52"  !CDS_PN = "52";
"VSS22":   PN = "54"  !CDS_PN = "54";
"VSS23":   PN = "57"  !CDS_PN = "57";
"VSS24":   PN = "59"  !CDS_PN = "59";
"VSS25":   PN = "61"  !CDS_PN = "61";
"VSS26":   PN = "63"  !CDS_PN = "63";
"VSS27":   PN = "65"  !CDS_PN = "65";
"VSS28":   PN = "67"  !CDS_PN = "67";
"VSS29":   PN = "69"  !CDS_PN = "69";
"VSS30":   PN = "71"  !CDS_PN = "71";
"VSS31":   PN = "73"  !CDS_PN = "73";
"VSS32":   PN = "75"  !CDS_PN = "75";
"VSS33":   PN = "77"  !CDS_PN = "77";
"VSS34":   PN = "79"  !CDS_PN = "79";
"VSS35":   PN = "81"  !CDS_PN = "81";
"VSS36":   PN = "83"  !CDS_PN = "83";
"VSS37":   PN = "85"  !CDS_PN = "85";
"VSS38":   PN = "88"  !CDS_PN = "88";
"VSS39":   PN = "90"  !CDS_PN = "90";
"VSS40":   PN = "92"  !CDS_PN = "92";
"VSS41":   PN = "95"  !CDS_PN = "95";
"VSS42":   PN = "97"  !CDS_PN = "97";
"VSS43":   PN = "99"  !CDS_PN = "99";
"VSS44":   PN = "101"  !CDS_PN = "101";
"VSS45":   PN = "103"  !CDS_PN = "103";
"VSS46":   PN = "106"  !CDS_PN = "106";
"VSS47":   PN = "108"  !CDS_PN = "108";
"VSS48":   PN = "110"  !CDS_PN = "110";
"VSS49":   PN = "112"  !CDS_PN = "112";
"VSS50":   PN = "114"  !CDS_PN = "114";
"VSS51":   PN = "117"  !CDS_PN = "117";
"VSS52":   PN = "119"  !CDS_PN = "119";
"VSS53":   PN = "121"  !CDS_PN = "121";
"VSS54":   PN = "123"  !CDS_PN = "123";
"VSS55":   PN = "125"  !CDS_PN = "125";
"VSS56":   PN = "128"  !CDS_PN = "128";
"VSS57":   PN = "130"  !CDS_PN = "130";
"VSS58":   PN = "132"  !CDS_PN = "132";
"VSS59":   PN = "134"  !CDS_PN = "134";
"VSS60":   PN = "136"  !CDS_PN = "136";
"VSS61":   PN = "139"  !CDS_PN = "139";
"VSS62":   PN = "141"  !CDS_PN = "141";
"VSS63":   PN = "143"  !CDS_PN = "143";
"VSS64":   PN = "151"  !CDS_PN = "151";
"VSS65":   PN = "153"  !CDS_PN = "153";
"VSS66":   PN = "155"  !CDS_PN = "155";
"VSS67":   PN = "158"  !CDS_PN = "158";
"VSS68":   PN = "160"  !CDS_PN = "160";
"VSS69":   PN = "162"  !CDS_PN = "162";
"VSS70":   PN = "164"  !CDS_PN = "164";
"VSS71":   PN = "166"  !CDS_PN = "166";
"VSS72":   PN = "169"  !CDS_PN = "169";
"VSS73":   PN = "171"  !CDS_PN = "171";
"VSS74":   PN = "173"  !CDS_PN = "173";
"VSS75":   PN = "175"  !CDS_PN = "175";
"VSS76":   PN = "177"  !CDS_PN = "177";
"VSS77":   PN = "180"  !CDS_PN = "180";
"VSS78":   PN = "182"  !CDS_PN = "182";
"VSS79":   PN = "184"  !CDS_PN = "184";
"VSS80":   PN = "186"  !CDS_PN = "186";
"VSS81":   PN = "188"  !CDS_PN = "188";
"VSS82":   PN = "191"  !CDS_PN = "191";
"VSS83":   PN = "193"  !CDS_PN = "193";
"VSS84":   PN = "195"  !CDS_PN = "195";
"VSS85":   PN = "197"  !CDS_PN = "197";
"VSS86":   PN = "199"  !CDS_PN = "199";
"VSS87":   PN = "202"  !CDS_PN = "202";
"VSS88":   PN = "204"  !CDS_PN = "204";
"VSS89":   PN = "206"  !CDS_PN = "206";
"VSS90":   PN = "208"  !CDS_PN = "208";
"VSS91":   PN = "210"  !CDS_PN = "210";
"VSS92":   PN = "212"  !CDS_PN = "212";
"VSS93":   PN = "214"  !CDS_PN = "214";
"VSS94":   PN = "216"  !CDS_PN = "216";
"VSS95":   PN = "219"  !CDS_PN = "219";
"VSS96":   PN = "222"  !CDS_PN = "222";
"VSS97":   PN = "224"  !CDS_PN = "224";
"VSS98":   PN = "226"  !CDS_PN = "226";
"VSS99":   PN = "228"  !CDS_PN = "228";
"VSS100":   PN = "230"  !CDS_PN = "230";
"VSS101":   PN = "233"  !CDS_PN = "233";
"VSS102":   PN = "235"  !CDS_PN = "235";
"VSS103":   PN = "237"  !CDS_PN = "237";
"VSS104":   PN = "240"  !CDS_PN = "240";
"VSS105":   PN = "242"  !CDS_PN = "242";
"VSS106":   PN = "244"  !CDS_PN = "244";
"VSS107":   PN = "246"  !CDS_PN = "246";
"VSS108":   PN = "248"  !CDS_PN = "248";
"VSS109":   PN = "251"  !CDS_PN = "251";
"VSS110":   PN = "253"  !CDS_PN = "253";
"VSS111":   PN = "255"  !CDS_PN = "255";
"VSS112":   PN = "257"  !CDS_PN = "257";
"VSS113":   PN = "259"  !CDS_PN = "259";
"VSS114":   PN = "262"  !CDS_PN = "262";
"VSS115":   PN = "264"  !CDS_PN = "264";
"VSS116":   PN = "266"  !CDS_PN = "266";
"VSS117":   PN = "268"  !CDS_PN = "268";
"VSS118":   PN = "270"  !CDS_PN = "270";
"VSS119":   PN = "273"  !CDS_PN = "273";
"VSS120":   PN = "275"  !CDS_PN = "275";
"VSS121":   PN = "277"  !CDS_PN = "277";
"VSS122":   PN = "279"  !CDS_PN = "279";
"VSS123":   PN = "281"  !CDS_PN = "281";
"VSS124":   PN = "284"  !CDS_PN = "284";
"VSS125":   PN = "286"  !CDS_PN = "286";
"VSS126":   PN = "288"  !CDS_PN = "288";
BODY = "SCONN288_ADR50017P087CC","I178": #LOCATION = "J14" !CDS_LOCATION = "J14" &SEC = "2" #&CDS_SEC = "2";
"DQS0_A_C":   PN = "12"  !CDS_PN = "12";
"DQS0_A_T":   PN = "11"  !CDS_PN = "11";
"DQS0_B_C":   PN = "105"  !CDS_PN = "105";
"DQS0_B_T":   PN = "104"  !CDS_PN = "104";
"DQS1_A_C":   PN = "23"  !CDS_PN = "23";
"DQS1_A_T":   PN = "22"  !CDS_PN = "22";
"DQS1_B_C":   PN = "116"  !CDS_PN = "116";
"DQS1_B_T":   PN = "115"  !CDS_PN = "115";
"DQS2_A_C":   PN = "34"  !CDS_PN = "34";
"DQS2_A_T":   PN = "33"  !CDS_PN = "33";
"DQS2_B_C":   PN = "127"  !CDS_PN = "127";
"DQS2_B_T":   PN = "126"  !CDS_PN = "126";
"DQS3_A_C":   PN = "45"  !CDS_PN = "45";
"DQS3_A_T":   PN = "44"  !CDS_PN = "44";
"DQS3_B_C":   PN = "138"  !CDS_PN = "138";
"DQS3_B_T":   PN = "137"  !CDS_PN = "137";
"DQS4_A_C":   PN = "56"  !CDS_PN = "56";
"DQS4_A_T":   PN = "55"  !CDS_PN = "55";
"DQS4_B_C":   PN = "238"  !CDS_PN = "238";
"DQS4_B_T":   PN = "239"  !CDS_PN = "239";
"DQS5_A_C||TDQS5_A_C||DQS5_A_T||TDQS5_A_T":   PN = "156"  !CDS_PN = "156";
"DQS5_A_T||TDQS5_A_T":   PN = "157"  !CDS_PN = "157";
"DQS5_B_C||TDQS5_B_C":   PN = "249"  !CDS_PN = "249";
"DQS5_B_T||TDQS5_B_T":   PN = "250"  !CDS_PN = "250";
"DQS6_A_C||TDQS6_A_C||DQS6_A_T||TDQS6_A_T":   PN = "167"  !CDS_PN = "167";
"DQS6_A_T||TDQS6_A_T":   PN = "168"  !CDS_PN = "168";
"DQS6_B_C||TDQS6_B_C":   PN = "260"  !CDS_PN = "260";
"DQS6_B_T||TDQS6_B_T":   PN = "261"  !CDS_PN = "261";
"DQS7_A_C||TDQS7_A_C":   PN = "178"  !CDS_PN = "178";
"DQS7_A_T||TDQS7_A_T":   PN = "179"  !CDS_PN = "179";
"DQS7_B_C||TDQS7_B_C":   PN = "271"  !CDS_PN = "271";
"DQS7_B_T||TDQS7_B_T":   PN = "272"  !CDS_PN = "272";
"DQS8_A_C||TDQS8_A_C":   PN = "189"  !CDS_PN = "189";
"DQS8_A_T||TDQS8_A_T":   PN = "190"  !CDS_PN = "190";
"DQS8_B_C||TDQS8_B_C":   PN = "282"  !CDS_PN = "282";
"DQS8_B_T||TDQS8_B_T":   PN = "283"  !CDS_PN = "283";
"DQS9_A_C||TDQS9_A_C":   PN = "200"  !CDS_PN = "200";
"DQS9_A_T||TDQS9_A_T":   PN = "201"  !CDS_PN = "201";
"DQS9_B_C||TDQS9_B_C":   PN = "94"  !CDS_PN = "94";
"DQS9_B_T||TDQS9_B_T||DBI4_B_N":   PN = "93"  !CDS_PN = "93";
BODY = "Q_RES","I179": LOCATION = "R3888" #&CDS_LOCATION = "R3888" &SEC = "1" #&CDS_SEC = "1";
"A":   PN = "1"  !CDS_PN = "1";
"B":   PN = "2"  !CDS_PN = "2";
DRAWING = "@s9s_mb_2u_lib.s9s_mb_2u(sch_1):page96";
BODY = "Q_RES","I47": LOCATION = "R40" #&CDS_LOCATION = "R40" &SEC = "1" #&CDS_SEC = "1";
"A":   PN = "1"  !CDS_PN = "1";
"B":   PN = "2"  !CDS_PN = "2";
BODY = "SCONN288_ADR50017P130CC","I48": LOCATION = "J15" #&CDS_LOCATION = "J15" &SEC = "1" #&CDS_SEC = "1";
"ALERT_N":   PN = "62"  !CDS_PN = "62";
"CA0_A":   PN = "66"  !CDS_PN = "66";
"CA0_B":   PN = "76"  !CDS_PN = "76";
"CA1_A":   PN = "211"  !CDS_PN = "211";
"CA1_B":   PN = "221"  !CDS_PN = "221";
"CA2_A":   PN = "68"  !CDS_PN = "68";
"CA2_B":   PN = "78"  !CDS_PN = "78";
"CA3_A":   PN = "213"  !CDS_PN = "213";
"CA3_B":   PN = "223"  !CDS_PN = "223";
"CA4_A":   PN = "70"  !CDS_PN = "70";
"CA4_B":   PN = "80"  !CDS_PN = "80";
"CA5_A":   PN = "215"  !CDS_PN = "215";
"CA5_B":   PN = "225"  !CDS_PN = "225";
"CA6_A":   PN = "72"  !CDS_PN = "72";
"CA6_B":   PN = "82"  !CDS_PN = "82";
"CB0_A":   PN = "51"  !CDS_PN = "51";
"CB0_B":   PN = "96"  !CDS_PN = "96";
"CB1_A":   PN = "53"  !CDS_PN = "53";
"CB1_B":   PN = "98"  !CDS_PN = "98";
"CB2_A":   PN = "196"  !CDS_PN = "196";
"CB2_B":   PN = "241"  !CDS_PN = "241";
"CB3_A":   PN = "198"  !CDS_PN = "198";
"CB3_B":   PN = "243"  !CDS_PN = "243";
"CB4_A":   PN = "58"  !CDS_PN = "58";
"CB4_B":   PN = "89"  !CDS_PN = "89";
"CB5_A":   PN = "60"  !CDS_PN = "60";
"CB5_B":   PN = "91"  !CDS_PN = "91";
"CB6_A":   PN = "203"  !CDS_PN = "203";
"CB6_B":   PN = "234"  !CDS_PN = "234";
"CB7_A":   PN = "205"  !CDS_PN = "205";
"CB7_B":   PN = "236"  !CDS_PN = "236";
"CK_C":   PN = "218"  !CDS_PN = "218";
"CK_T":   PN = "217"  !CDS_PN = "217";
"CS0_A_N":   PN = "64"  !CDS_PN = "64";
"CS0_B_N":   PN = "84"  !CDS_PN = "84";
"CS1_A_N":   PN = "209"  !CDS_PN = "209";
"CS1_B_N":   PN = "229"  !CDS_PN = "229";
"DQ0_A":   PN = "7"  !CDS_PN = "7";
"DQ0_B":   PN = "100"  !CDS_PN = "100";
"DQ1_A":   PN = "9"  !CDS_PN = "9";
"DQ1_B":   PN = "102"  !CDS_PN = "102";
"DQ2_A":   PN = "152"  !CDS_PN = "152";
"DQ2_B":   PN = "245"  !CDS_PN = "245";
"DQ3_A":   PN = "154"  !CDS_PN = "154";
"DQ3_B":   PN = "247"  !CDS_PN = "247";
"DQ4_A":   PN = "14"  !CDS_PN = "14";
"DQ4_B":   PN = "107"  !CDS_PN = "107";
"DQ5_A":   PN = "16"  !CDS_PN = "16";
"DQ5_B":   PN = "109"  !CDS_PN = "109";
"DQ6_A":   PN = "159"  !CDS_PN = "159";
"DQ6_B":   PN = "252"  !CDS_PN = "252";
"DQ7_A":   PN = "161"  !CDS_PN = "161";
"DQ7_B":   PN = "254"  !CDS_PN = "254";
"DQ8_A":   PN = "18"  !CDS_PN = "18";
"DQ8_B":   PN = "111"  !CDS_PN = "111";
"DQ9_A":   PN = "20"  !CDS_PN = "20";
"DQ9_B":   PN = "113"  !CDS_PN = "113";
"DQ10_A":   PN = "163"  !CDS_PN = "163";
"DQ10_B":   PN = "256"  !CDS_PN = "256";
"DQ11_A":   PN = "165"  !CDS_PN = "165";
"DQ11_B":   PN = "258"  !CDS_PN = "258";
"DQ12_A":   PN = "25"  !CDS_PN = "25";
"DQ12_B":   PN = "118"  !CDS_PN = "118";
"DQ13_A":   PN = "27"  !CDS_PN = "27";
"DQ13_B":   PN = "120"  !CDS_PN = "120";
"DQ14_A":   PN = "170"  !CDS_PN = "170";
"DQ14_B":   PN = "263"  !CDS_PN = "263";
"DQ15_A":   PN = "172"  !CDS_PN = "172";
"DQ15_B":   PN = "265"  !CDS_PN = "265";
"DQ16_A":   PN = "29"  !CDS_PN = "29";
"DQ16_B":   PN = "122"  !CDS_PN = "122";
"DQ17_A":   PN = "31"  !CDS_PN = "31";
"DQ17_B":   PN = "124"  !CDS_PN = "124";
"DQ18_A":   PN = "174"  !CDS_PN = "174";
"DQ18_B":   PN = "267"  !CDS_PN = "267";
"DQ19_A":   PN = "176"  !CDS_PN = "176";
"DQ19_B":   PN = "269"  !CDS_PN = "269";
"DQ20_A":   PN = "36"  !CDS_PN = "36";
"DQ20_B":   PN = "129"  !CDS_PN = "129";
"DQ21_A":   PN = "38"  !CDS_PN = "38";
"DQ21_B":   PN = "131"  !CDS_PN = "131";
"DQ22_A":   PN = "181"  !CDS_PN = "181";
"DQ22_B":   PN = "274"  !CDS_PN = "274";
"DQ23_A":   PN = "183"  !CDS_PN = "183";
"DQ23_B":   PN = "276"  !CDS_PN = "276";
"DQ24_A":   PN = "40"  !CDS_PN = "40";
"DQ24_B":   PN = "133"  !CDS_PN = "133";
"DQ25_A":   PN = "42"  !CDS_PN = "42";
"DQ25_B":   PN = "135"  !CDS_PN = "135";
"DQ26_A":   PN = "185"  !CDS_PN = "185";
"DQ26_B":   PN = "278"  !CDS_PN = "278";
"DQ27_A":   PN = "187"  !CDS_PN = "187";
"DQ27_B":   PN = "280"  !CDS_PN = "280";
"DQ28_A":   PN = "47"  !CDS_PN = "47";
"DQ28_B":   PN = "140"  !CDS_PN = "140";
"DQ29_A":   PN = "49"  !CDS_PN = "49";
"DQ29_B":   PN = "142"  !CDS_PN = "142";
"DQ30_A":   PN = "192"  !CDS_PN = "192";
"DQ30_B":   PN = "285"  !CDS_PN = "285";
"DQ31_A":   PN = "194"  !CDS_PN = "194";
"DQ31_B":   PN = "287"  !CDS_PN = "287";
"HSA":   PN = "148"  !CDS_PN = "148";
"HSCL":   PN = "4"  !CDS_PN = "4";
"HSDA":   PN = "5"  !CDS_PN = "5";
"LBD||RSP_A_N":   PN = "86"  !CDS_PN = "86";
"LBS||RSP_B_N":   PN = "87"  !CDS_PN = "87";
"PAR_A":   PN = "74"  !CDS_PN = "74";
"PAR_B":   PN = "227"  !CDS_PN = "227";
"PWR_GOOD||FAIL_N":   PN = "147"  !CDS_PN = "147";
"RESET_N":   PN = "207"  !CDS_PN = "207";
"RFU0":   PN = "2"  !CDS_PN = "2";
"RFU1":   PN = "144"  !CDS_PN = "144";
"RFU2":   PN = "149"  !CDS_PN = "149";
"RFU3":   PN = "150"  !CDS_PN = "150";
"RFU4":   PN = "220"  !CDS_PN = "220";
"RFU5":   PN = "231"  !CDS_PN = "231";
"RFU6":   PN = "232"  !CDS_PN = "232";
"VIN_MGMT":   PN = "3"  !CDS_PN = "3";
BODY = "Q_CAP","I121": LOCATION = "C44" #&CDS_LOCATION = "C44" &SEC = "1" #&CDS_SEC = "1";
"A":   PN = "1"  !CDS_PN = "1";
"B":   PN = "2"  !CDS_PN = "2";
BODY = "Q_CAP","I125": LOCATION = "C45" #&CDS_LOCATION = "C45" &SEC = "1" #&CDS_SEC = "1";
"A":   PN = "1"  !CDS_PN = "1";
"B":   PN = "2"  !CDS_PN = "2";
BODY = "Q_CAP","I127": LOCATION = "C46" #&CDS_LOCATION = "C46" &SEC = "1" #&CDS_SEC = "1";
"A":   PN = "1"  !CDS_PN = "1";
"B":   PN = "2"  !CDS_PN = "2";
BODY = "SCONN288_ADR50017P130CC","I176": LOCATION = "J15" #&CDS_LOCATION = "J15" &SEC = "3" #&CDS_SEC = "3";
"G1":   PN = "G1"  !CDS_PN = "G1";
"G2":   PN = "G2"  !CDS_PN = "G2";
"G3":   PN = "G3"  !CDS_PN = "G3";
"VIN_BULK0":   PN = "1"  !CDS_PN = "1";
"VIN_BULK1":   PN = "145"  !CDS_PN = "145";
"VIN_BULK2":   PN = "146"  !CDS_PN = "146";
"VSS0":   PN = "6"  !CDS_PN = "6";
"VSS1":   PN = "8"  !CDS_PN = "8";
"VSS2":   PN = "10"  !CDS_PN = "10";
"VSS3":   PN = "13"  !CDS_PN = "13";
"VSS4":   PN = "15"  !CDS_PN = "15";
"VSS5":   PN = "17"  !CDS_PN = "17";
"VSS6":   PN = "19"  !CDS_PN = "19";
"VSS7":   PN = "21"  !CDS_PN = "21";
"VSS8":   PN = "24"  !CDS_PN = "24";
"VSS9":   PN = "26"  !CDS_PN = "26";
"VSS10":   PN = "28"  !CDS_PN = "28";
"VSS11":   PN = "30"  !CDS_PN = "30";
"VSS12":   PN = "32"  !CDS_PN = "32";
"VSS13":   PN = "35"  !CDS_PN = "35";
"VSS14":   PN = "37"  !CDS_PN = "37";
"VSS15":   PN = "39"  !CDS_PN = "39";
"VSS16":   PN = "41"  !CDS_PN = "41";
"VSS17":   PN = "43"  !CDS_PN = "43";
"VSS18":   PN = "46"  !CDS_PN = "46";
"VSS19":   PN = "48"  !CDS_PN = "48";
"VSS20":   PN = "50"  !CDS_PN = "50";
"VSS21":   PN = "52"  !CDS_PN = "52";
"VSS22":   PN = "54"  !CDS_PN = "54";
"VSS23":   PN = "57"  !CDS_PN = "57";
"VSS24":   PN = "59"  !CDS_PN = "59";
"VSS25":   PN = "61"  !CDS_PN = "61";
"VSS26":   PN = "63"  !CDS_PN = "63";
"VSS27":   PN = "65"  !CDS_PN = "65";
"VSS28":   PN = "67"  !CDS_PN = "67";
"VSS29":   PN = "69"  !CDS_PN = "69";
"VSS30":   PN = "71"  !CDS_PN = "71";
"VSS31":   PN = "73"  !CDS_PN = "73";
"VSS32":   PN = "75"  !CDS_PN = "75";
"VSS33":   PN = "77"  !CDS_PN = "77";
"VSS34":   PN = "79"  !CDS_PN = "79";
"VSS35":   PN = "81"  !CDS_PN = "81";
"VSS36":   PN = "83"  !CDS_PN = "83";
"VSS37":   PN = "85"  !CDS_PN = "85";
"VSS38":   PN = "88"  !CDS_PN = "88";
"VSS39":   PN = "90"  !CDS_PN = "90";
"VSS40":   PN = "92"  !CDS_PN = "92";
"VSS41":   PN = "95"  !CDS_PN = "95";
"VSS42":   PN = "97"  !CDS_PN = "97";
"VSS43":   PN = "99"  !CDS_PN = "99";
"VSS44":   PN = "101"  !CDS_PN = "101";
"VSS45":   PN = "103"  !CDS_PN = "103";
"VSS46":   PN = "106"  !CDS_PN = "106";
"VSS47":   PN = "108"  !CDS_PN = "108";
"VSS48":   PN = "110"  !CDS_PN = "110";
"VSS49":   PN = "112"  !CDS_PN = "112";
"VSS50":   PN = "114"  !CDS_PN = "114";
"VSS51":   PN = "117"  !CDS_PN = "117";
"VSS52":   PN = "119"  !CDS_PN = "119";
"VSS53":   PN = "121"  !CDS_PN = "121";
"VSS54":   PN = "123"  !CDS_PN = "123";
"VSS55":   PN = "125"  !CDS_PN = "125";
"VSS56":   PN = "128"  !CDS_PN = "128";
"VSS57":   PN = "130"  !CDS_PN = "130";
"VSS58":   PN = "132"  !CDS_PN = "132";
"VSS59":   PN = "134"  !CDS_PN = "134";
"VSS60":   PN = "136"  !CDS_PN = "136";
"VSS61":   PN = "139"  !CDS_PN = "139";
"VSS62":   PN = "141"  !CDS_PN = "141";
"VSS63":   PN = "143"  !CDS_PN = "143";
"VSS64":   PN = "151"  !CDS_PN = "151";
"VSS65":   PN = "153"  !CDS_PN = "153";
"VSS66":   PN = "155"  !CDS_PN = "155";
"VSS67":   PN = "158"  !CDS_PN = "158";
"VSS68":   PN = "160"  !CDS_PN = "160";
"VSS69":   PN = "162"  !CDS_PN = "162";
"VSS70":   PN = "164"  !CDS_PN = "164";
"VSS71":   PN = "166"  !CDS_PN = "166";
"VSS72":   PN = "169"  !CDS_PN = "169";
"VSS73":   PN = "171"  !CDS_PN = "171";
"VSS74":   PN = "173"  !CDS_PN = "173";
"VSS75":   PN = "175"  !CDS_PN = "175";
"VSS76":   PN = "177"  !CDS_PN = "177";
"VSS77":   PN = "180"  !CDS_PN = "180";
"VSS78":   PN = "182"  !CDS_PN = "182";
"VSS79":   PN = "184"  !CDS_PN = "184";
"VSS80":   PN = "186"  !CDS_PN = "186";
"VSS81":   PN = "188"  !CDS_PN = "188";
"VSS82":   PN = "191"  !CDS_PN = "191";
"VSS83":   PN = "193"  !CDS_PN = "193";
"VSS84":   PN = "195"  !CDS_PN = "195";
"VSS85":   PN = "197"  !CDS_PN = "197";
"VSS86":   PN = "199"  !CDS_PN = "199";
"VSS87":   PN = "202"  !CDS_PN = "202";
"VSS88":   PN = "204"  !CDS_PN = "204";
"VSS89":   PN = "206"  !CDS_PN = "206";
"VSS90":   PN = "208"  !CDS_PN = "208";
"VSS91":   PN = "210"  !CDS_PN = "210";
"VSS92":   PN = "212"  !CDS_PN = "212";
"VSS93":   PN = "214"  !CDS_PN = "214";
"VSS94":   PN = "216"  !CDS_PN = "216";
"VSS95":   PN = "219"  !CDS_PN = "219";
"VSS96":   PN = "222"  !CDS_PN = "222";
"VSS97":   PN = "224"  !CDS_PN = "224";
"VSS98":   PN = "226"  !CDS_PN = "226";
"VSS99":   PN = "228"  !CDS_PN = "228";
"VSS100":   PN = "230"  !CDS_PN = "230";
"VSS101":   PN = "233"  !CDS_PN = "233";
"VSS102":   PN = "235"  !CDS_PN = "235";
"VSS103":   PN = "237"  !CDS_PN = "237";
"VSS104":   PN = "240"  !CDS_PN = "240";
"VSS105":   PN = "242"  !CDS_PN = "242";
"VSS106":   PN = "244"  !CDS_PN = "244";
"VSS107":   PN = "246"  !CDS_PN = "246";
"VSS108":   PN = "248"  !CDS_PN = "248";
"VSS109":   PN = "251"  !CDS_PN = "251";
"VSS110":   PN = "253"  !CDS_PN = "253";
"VSS111":   PN = "255"  !CDS_PN = "255";
"VSS112":   PN = "257"  !CDS_PN = "257";
"VSS113":   PN = "259"  !CDS_PN = "259";
"VSS114":   PN = "262"  !CDS_PN = "262";
"VSS115":   PN = "264"  !CDS_PN = "264";
"VSS116":   PN = "266"  !CDS_PN = "266";
"VSS117":   PN = "268"  !CDS_PN = "268";
"VSS118":   PN = "270"  !CDS_PN = "270";
"VSS119":   PN = "273"  !CDS_PN = "273";
"VSS120":   PN = "275"  !CDS_PN = "275";
"VSS121":   PN = "277"  !CDS_PN = "277";
"VSS122":   PN = "279"  !CDS_PN = "279";
"VSS123":   PN = "281"  !CDS_PN = "281";
"VSS124":   PN = "284"  !CDS_PN = "284";
"VSS125":   PN = "286"  !CDS_PN = "286";
"VSS126":   PN = "288"  !CDS_PN = "288";
BODY = "SCONN288_ADR50017P130CC","I178": #LOCATION = "J15" !CDS_LOCATION = "J15" &SEC = "2" #&CDS_SEC = "2";
"DQS0_A_C":   PN = "12"  !CDS_PN = "12";
"DQS0_A_T":   PN = "11"  !CDS_PN = "11";
"DQS0_B_C":   PN = "105"  !CDS_PN = "105";
"DQS0_B_T":   PN = "104"  !CDS_PN = "104";
"DQS1_A_C":   PN = "23"  !CDS_PN = "23";
"DQS1_A_T":   PN = "22"  !CDS_PN = "22";
"DQS1_B_C":   PN = "116"  !CDS_PN = "116";
"DQS1_B_T":   PN = "115"  !CDS_PN = "115";
"DQS2_A_C":   PN = "34"  !CDS_PN = "34";
"DQS2_A_T":   PN = "33"  !CDS_PN = "33";
"DQS2_B_C":   PN = "127"  !CDS_PN = "127";
"DQS2_B_T":   PN = "126"  !CDS_PN = "126";
"DQS3_A_C":   PN = "45"  !CDS_PN = "45";
"DQS3_A_T":   PN = "44"  !CDS_PN = "44";
"DQS3_B_C":   PN = "138"  !CDS_PN = "138";
"DQS3_B_T":   PN = "137"  !CDS_PN = "137";
"DQS4_A_C":   PN = "56"  !CDS_PN = "56";
"DQS4_A_T":   PN = "55"  !CDS_PN = "55";
"DQS4_B_C":   PN = "238"  !CDS_PN = "238";
"DQS4_B_T":   PN = "239"  !CDS_PN = "239";
"DQS5_A_C||TDQS5_A_C||DQS5_A_T||TDQS5_A_T":   PN = "156"  !CDS_PN = "156";
"DQS5_A_T||TDQS5_A_T":   PN = "157"  !CDS_PN = "157";
"DQS5_B_C||TDQS5_B_C":   PN = "249"  !CDS_PN = "249";
"DQS5_B_T||TDQS5_B_T":   PN = "250"  !CDS_PN = "250";
"DQS6_A_C||TDQS6_A_C||DQS6_A_T||TDQS6_A_T":   PN = "167"  !CDS_PN = "167";
"DQS6_A_T||TDQS6_A_T":   PN = "168"  !CDS_PN = "168";
"DQS6_B_C||TDQS6_B_C":   PN = "260"  !CDS_PN = "260";
"DQS6_B_T||TDQS6_B_T":   PN = "261"  !CDS_PN = "261";
"DQS7_A_C||TDQS7_A_C":   PN = "178"  !CDS_PN = "178";
"DQS7_A_T||TDQS7_A_T":   PN = "179"  !CDS_PN = "179";
"DQS7_B_C||TDQS7_B_C":   PN = "271"  !CDS_PN = "271";
"DQS7_B_T||TDQS7_B_T":   PN = "272"  !CDS_PN = "272";
"DQS8_A_C||TDQS8_A_C":   PN = "189"  !CDS_PN = "189";
"DQS8_A_T||TDQS8_A_T":   PN = "190"  !CDS_PN = "190";
"DQS8_B_C||TDQS8_B_C":   PN = "282"  !CDS_PN = "282";
"DQS8_B_T||TDQS8_B_T":   PN = "283"  !CDS_PN = "283";
"DQS9_A_C||TDQS9_A_C":   PN = "200"  !CDS_PN = "200";
"DQS9_A_T||TDQS9_A_T":   PN = "201"  !CDS_PN = "201";
"DQS9_B_C||TDQS9_B_C":   PN = "94"  !CDS_PN = "94";
"DQS9_B_T||TDQS9_B_T||DBI4_B_N":   PN = "93"  !CDS_PN = "93";
BODY = "Q_RES","I179": LOCATION = "R3889" #&CDS_LOCATION = "R3889" &SEC = "1" #&CDS_SEC = "1";
"A":   PN = "1"  !CDS_PN = "1";
"B":   PN = "2"  !CDS_PN = "2";
DRAWING = "@s9s_mb_2u_lib.s9s_mb_2u(sch_1):page97";
BODY = "Q_RES","I5": LOCATION = "R41" #&CDS_LOCATION = "R41" &SEC = "1" #&CDS_SEC = "1";
"A":   PN = "1"  !CDS_PN = "1";
"B":   PN = "2"  !CDS_PN = "2";
BODY = "SCONN288_ADR50017P087CC","I6": LOCATION = "J16" #&CDS_LOCATION = "J16" &SEC = "1" #&CDS_SEC = "1";
"ALERT_N":   PN = "62"  !CDS_PN = "62";
"CA0_A":   PN = "66"  !CDS_PN = "66";
"CA0_B":   PN = "76"  !CDS_PN = "76";
"CA1_A":   PN = "211"  !CDS_PN = "211";
"CA1_B":   PN = "221"  !CDS_PN = "221";
"CA2_A":   PN = "68"  !CDS_PN = "68";
"CA2_B":   PN = "78"  !CDS_PN = "78";
"CA3_A":   PN = "213"  !CDS_PN = "213";
"CA3_B":   PN = "223"  !CDS_PN = "223";
"CA4_A":   PN = "70"  !CDS_PN = "70";
"CA4_B":   PN = "80"  !CDS_PN = "80";
"CA5_A":   PN = "215"  !CDS_PN = "215";
"CA5_B":   PN = "225"  !CDS_PN = "225";
"CA6_A":   PN = "72"  !CDS_PN = "72";
"CA6_B":   PN = "82"  !CDS_PN = "82";
"CB0_A":   PN = "51"  !CDS_PN = "51";
"CB0_B":   PN = "96"  !CDS_PN = "96";
"CB1_A":   PN = "53"  !CDS_PN = "53";
"CB1_B":   PN = "98"  !CDS_PN = "98";
"CB2_A":   PN = "196"  !CDS_PN = "196";
"CB2_B":   PN = "241"  !CDS_PN = "241";
"CB3_A":   PN = "198"  !CDS_PN = "198";
"CB3_B":   PN = "243"  !CDS_PN = "243";
"CB4_A":   PN = "58"  !CDS_PN = "58";
"CB4_B":   PN = "89"  !CDS_PN = "89";
"CB5_A":   PN = "60"  !CDS_PN = "60";
"CB5_B":   PN = "91"  !CDS_PN = "91";
"CB6_A":   PN = "203"  !CDS_PN = "203";
"CB6_B":   PN = "234"  !CDS_PN = "234";
"CB7_A":   PN = "205"  !CDS_PN = "205";
"CB7_B":   PN = "236"  !CDS_PN = "236";
"CK_C":   PN = "218"  !CDS_PN = "218";
"CK_T":   PN = "217"  !CDS_PN = "217";
"CS0_A_N":   PN = "64"  !CDS_PN = "64";
"CS0_B_N":   PN = "84"  !CDS_PN = "84";
"CS1_A_N":   PN = "209"  !CDS_PN = "209";
"CS1_B_N":   PN = "229"  !CDS_PN = "229";
"DQ0_A":   PN = "7"  !CDS_PN = "7";
"DQ0_B":   PN = "100"  !CDS_PN = "100";
"DQ1_A":   PN = "9"  !CDS_PN = "9";
"DQ1_B":   PN = "102"  !CDS_PN = "102";
"DQ2_A":   PN = "152"  !CDS_PN = "152";
"DQ2_B":   PN = "245"  !CDS_PN = "245";
"DQ3_A":   PN = "154"  !CDS_PN = "154";
"DQ3_B":   PN = "247"  !CDS_PN = "247";
"DQ4_A":   PN = "14"  !CDS_PN = "14";
"DQ4_B":   PN = "107"  !CDS_PN = "107";
"DQ5_A":   PN = "16"  !CDS_PN = "16";
"DQ5_B":   PN = "109"  !CDS_PN = "109";
"DQ6_A":   PN = "159"  !CDS_PN = "159";
"DQ6_B":   PN = "252"  !CDS_PN = "252";
"DQ7_A":   PN = "161"  !CDS_PN = "161";
"DQ7_B":   PN = "254"  !CDS_PN = "254";
"DQ8_A":   PN = "18"  !CDS_PN = "18";
"DQ8_B":   PN = "111"  !CDS_PN = "111";
"DQ9_A":   PN = "20"  !CDS_PN = "20";
"DQ9_B":   PN = "113"  !CDS_PN = "113";
"DQ10_A":   PN = "163"  !CDS_PN = "163";
"DQ10_B":   PN = "256"  !CDS_PN = "256";
"DQ11_A":   PN = "165"  !CDS_PN = "165";
"DQ11_B":   PN = "258"  !CDS_PN = "258";
"DQ12_A":   PN = "25"  !CDS_PN = "25";
"DQ12_B":   PN = "118"  !CDS_PN = "118";
"DQ13_A":   PN = "27"  !CDS_PN = "27";
"DQ13_B":   PN = "120"  !CDS_PN = "120";
"DQ14_A":   PN = "170"  !CDS_PN = "170";
"DQ14_B":   PN = "263"  !CDS_PN = "263";
"DQ15_A":   PN = "172"  !CDS_PN = "172";
"DQ15_B":   PN = "265"  !CDS_PN = "265";
"DQ16_A":   PN = "29"  !CDS_PN = "29";
"DQ16_B":   PN = "122"  !CDS_PN = "122";
"DQ17_A":   PN = "31"  !CDS_PN = "31";
"DQ17_B":   PN = "124"  !CDS_PN = "124";
"DQ18_A":   PN = "174"  !CDS_PN = "174";
"DQ18_B":   PN = "267"  !CDS_PN = "267";
"DQ19_A":   PN = "176"  !CDS_PN = "176";
"DQ19_B":   PN = "269"  !CDS_PN = "269";
"DQ20_A":   PN = "36"  !CDS_PN = "36";
"DQ20_B":   PN = "129"  !CDS_PN = "129";
"DQ21_A":   PN = "38"  !CDS_PN = "38";
"DQ21_B":   PN = "131"  !CDS_PN = "131";
"DQ22_A":   PN = "181"  !CDS_PN = "181";
"DQ22_B":   PN = "274"  !CDS_PN = "274";
"DQ23_A":   PN = "183"  !CDS_PN = "183";
"DQ23_B":   PN = "276"  !CDS_PN = "276";
"DQ24_A":   PN = "40"  !CDS_PN = "40";
"DQ24_B":   PN = "133"  !CDS_PN = "133";
"DQ25_A":   PN = "42"  !CDS_PN = "42";
"DQ25_B":   PN = "135"  !CDS_PN = "135";
"DQ26_A":   PN = "185"  !CDS_PN = "185";
"DQ26_B":   PN = "278"  !CDS_PN = "278";
"DQ27_A":   PN = "187"  !CDS_PN = "187";
"DQ27_B":   PN = "280"  !CDS_PN = "280";
"DQ28_A":   PN = "47"  !CDS_PN = "47";
"DQ28_B":   PN = "140"  !CDS_PN = "140";
"DQ29_A":   PN = "49"  !CDS_PN = "49";
"DQ29_B":   PN = "142"  !CDS_PN = "142";
"DQ30_A":   PN = "192"  !CDS_PN = "192";
"DQ30_B":   PN = "285"  !CDS_PN = "285";
"DQ31_A":   PN = "194"  !CDS_PN = "194";
"DQ31_B":   PN = "287"  !CDS_PN = "287";
"HSA":   PN = "148"  !CDS_PN = "148";
"HSCL":   PN = "4"  !CDS_PN = "4";
"HSDA":   PN = "5"  !CDS_PN = "5";
"LBD||RSP_A_N":   PN = "86"  !CDS_PN = "86";
"LBS||RSP_B_N":   PN = "87"  !CDS_PN = "87";
"PAR_A":   PN = "74"  !CDS_PN = "74";
"PAR_B":   PN = "227"  !CDS_PN = "227";
"PWR_GOOD||FAIL_N":   PN = "147"  !CDS_PN = "147";
"RESET_N":   PN = "207"  !CDS_PN = "207";
"RFU0":   PN = "2"  !CDS_PN = "2";
"RFU1":   PN = "144"  !CDS_PN = "144";
"RFU2":   PN = "149"  !CDS_PN = "149";
"RFU3":   PN = "150"  !CDS_PN = "150";
"RFU4":   PN = "220"  !CDS_PN = "220";
"RFU5":   PN = "231"  !CDS_PN = "231";
"RFU6":   PN = "232"  !CDS_PN = "232";
"VIN_MGMT":   PN = "3"  !CDS_PN = "3";
BODY = "Q_CAP","I56": LOCATION = "C47" #&CDS_LOCATION = "C47" &SEC = "1" #&CDS_SEC = "1";
"A":   PN = "1"  !CDS_PN = "1";
"B":   PN = "2"  !CDS_PN = "2";
BODY = "Q_CAP","I59": LOCATION = "C48" #&CDS_LOCATION = "C48" &SEC = "1" #&CDS_SEC = "1";
"A":   PN = "1"  !CDS_PN = "1";
"B":   PN = "2"  !CDS_PN = "2";
BODY = "Q_CAP","I62": LOCATION = "C49" #&CDS_LOCATION = "C49" &SEC = "1" #&CDS_SEC = "1";
"A":   PN = "1"  !CDS_PN = "1";
"B":   PN = "2"  !CDS_PN = "2";
BODY = "SCONN288_ADR50017P087CC","I64": LOCATION = "J16" #&CDS_LOCATION = "J16" &SEC = "3" #&CDS_SEC = "3";
"G1":   PN = "G1"  !CDS_PN = "G1";
"G2":   PN = "G2"  !CDS_PN = "G2";
"G3":   PN = "G3"  !CDS_PN = "G3";
"VIN_BULK0":   PN = "1"  !CDS_PN = "1";
"VIN_BULK1":   PN = "145"  !CDS_PN = "145";
"VIN_BULK2":   PN = "146"  !CDS_PN = "146";
"VSS0":   PN = "6"  !CDS_PN = "6";
"VSS1":   PN = "8"  !CDS_PN = "8";
"VSS2":   PN = "10"  !CDS_PN = "10";
"VSS3":   PN = "13"  !CDS_PN = "13";
"VSS4":   PN = "15"  !CDS_PN = "15";
"VSS5":   PN = "17"  !CDS_PN = "17";
"VSS6":   PN = "19"  !CDS_PN = "19";
"VSS7":   PN = "21"  !CDS_PN = "21";
"VSS8":   PN = "24"  !CDS_PN = "24";
"VSS9":   PN = "26"  !CDS_PN = "26";
"VSS10":   PN = "28"  !CDS_PN = "28";
"VSS11":   PN = "30"  !CDS_PN = "30";
"VSS12":   PN = "32"  !CDS_PN = "32";
"VSS13":   PN = "35"  !CDS_PN = "35";
"VSS14":   PN = "37"  !CDS_PN = "37";
"VSS15":   PN = "39"  !CDS_PN = "39";
"VSS16":   PN = "41"  !CDS_PN = "41";
"VSS17":   PN = "43"  !CDS_PN = "43";
"VSS18":   PN = "46"  !CDS_PN = "46";
"VSS19":   PN = "48"  !CDS_PN = "48";
"VSS20":   PN = "50"  !CDS_PN = "50";
"VSS21":   PN = "52"  !CDS_PN = "52";
"VSS22":   PN = "54"  !CDS_PN = "54";
"VSS23":   PN = "57"  !CDS_PN = "57";
"VSS24":   PN = "59"  !CDS_PN = "59";
"VSS25":   PN = "61"  !CDS_PN = "61";
"VSS26":   PN = "63"  !CDS_PN = "63";
"VSS27":   PN = "65"  !CDS_PN = "65";
"VSS28":   PN = "67"  !CDS_PN = "67";
"VSS29":   PN = "69"  !CDS_PN = "69";
"VSS30":   PN = "71"  !CDS_PN = "71";
"VSS31":   PN = "73"  !CDS_PN = "73";
"VSS32":   PN = "75"  !CDS_PN = "75";
"VSS33":   PN = "77"  !CDS_PN = "77";
"VSS34":   PN = "79"  !CDS_PN = "79";
"VSS35":   PN = "81"  !CDS_PN = "81";
"VSS36":   PN = "83"  !CDS_PN = "83";
"VSS37":   PN = "85"  !CDS_PN = "85";
"VSS38":   PN = "88"  !CDS_PN = "88";
"VSS39":   PN = "90"  !CDS_PN = "90";
"VSS40":   PN = "92"  !CDS_PN = "92";
"VSS41":   PN = "95"  !CDS_PN = "95";
"VSS42":   PN = "97"  !CDS_PN = "97";
"VSS43":   PN = "99"  !CDS_PN = "99";
"VSS44":   PN = "101"  !CDS_PN = "101";
"VSS45":   PN = "103"  !CDS_PN = "103";
"VSS46":   PN = "106"  !CDS_PN = "106";
"VSS47":   PN = "108"  !CDS_PN = "108";
"VSS48":   PN = "110"  !CDS_PN = "110";
"VSS49":   PN = "112"  !CDS_PN = "112";
"VSS50":   PN = "114"  !CDS_PN = "114";
"VSS51":   PN = "117"  !CDS_PN = "117";
"VSS52":   PN = "119"  !CDS_PN = "119";
"VSS53":   PN = "121"  !CDS_PN = "121";
"VSS54":   PN = "123"  !CDS_PN = "123";
"VSS55":   PN = "125"  !CDS_PN = "125";
"VSS56":   PN = "128"  !CDS_PN = "128";
"VSS57":   PN = "130"  !CDS_PN = "130";
"VSS58":   PN = "132"  !CDS_PN = "132";
"VSS59":   PN = "134"  !CDS_PN = "134";
"VSS60":   PN = "136"  !CDS_PN = "136";
"VSS61":   PN = "139"  !CDS_PN = "139";
"VSS62":   PN = "141"  !CDS_PN = "141";
"VSS63":   PN = "143"  !CDS_PN = "143";
"VSS64":   PN = "151"  !CDS_PN = "151";
"VSS65":   PN = "153"  !CDS_PN = "153";
"VSS66":   PN = "155"  !CDS_PN = "155";
"VSS67":   PN = "158"  !CDS_PN = "158";
"VSS68":   PN = "160"  !CDS_PN = "160";
"VSS69":   PN = "162"  !CDS_PN = "162";
"VSS70":   PN = "164"  !CDS_PN = "164";
"VSS71":   PN = "166"  !CDS_PN = "166";
"VSS72":   PN = "169"  !CDS_PN = "169";
"VSS73":   PN = "171"  !CDS_PN = "171";
"VSS74":   PN = "173"  !CDS_PN = "173";
"VSS75":   PN = "175"  !CDS_PN = "175";
"VSS76":   PN = "177"  !CDS_PN = "177";
"VSS77":   PN = "180"  !CDS_PN = "180";
"VSS78":   PN = "182"  !CDS_PN = "182";
"VSS79":   PN = "184"  !CDS_PN = "184";
"VSS80":   PN = "186"  !CDS_PN = "186";
"VSS81":   PN = "188"  !CDS_PN = "188";
"VSS82":   PN = "191"  !CDS_PN = "191";
"VSS83":   PN = "193"  !CDS_PN = "193";
"VSS84":   PN = "195"  !CDS_PN = "195";
"VSS85":   PN = "197"  !CDS_PN = "197";
"VSS86":   PN = "199"  !CDS_PN = "199";
"VSS87":   PN = "202"  !CDS_PN = "202";
"VSS88":   PN = "204"  !CDS_PN = "204";
"VSS89":   PN = "206"  !CDS_PN = "206";
"VSS90":   PN = "208"  !CDS_PN = "208";
"VSS91":   PN = "210"  !CDS_PN = "210";
"VSS92":   PN = "212"  !CDS_PN = "212";
"VSS93":   PN = "214"  !CDS_PN = "214";
"VSS94":   PN = "216"  !CDS_PN = "216";
"VSS95":   PN = "219"  !CDS_PN = "219";
"VSS96":   PN = "222"  !CDS_PN = "222";
"VSS97":   PN = "224"  !CDS_PN = "224";
"VSS98":   PN = "226"  !CDS_PN = "226";
"VSS99":   PN = "228"  !CDS_PN = "228";
"VSS100":   PN = "230"  !CDS_PN = "230";
"VSS101":   PN = "233"  !CDS_PN = "233";
"VSS102":   PN = "235"  !CDS_PN = "235";
"VSS103":   PN = "237"  !CDS_PN = "237";
"VSS104":   PN = "240"  !CDS_PN = "240";
"VSS105":   PN = "242"  !CDS_PN = "242";
"VSS106":   PN = "244"  !CDS_PN = "244";
"VSS107":   PN = "246"  !CDS_PN = "246";
"VSS108":   PN = "248"  !CDS_PN = "248";
"VSS109":   PN = "251"  !CDS_PN = "251";
"VSS110":   PN = "253"  !CDS_PN = "253";
"VSS111":   PN = "255"  !CDS_PN = "255";
"VSS112":   PN = "257"  !CDS_PN = "257";
"VSS113":   PN = "259"  !CDS_PN = "259";
"VSS114":   PN = "262"  !CDS_PN = "262";
"VSS115":   PN = "264"  !CDS_PN = "264";
"VSS116":   PN = "266"  !CDS_PN = "266";
"VSS117":   PN = "268"  !CDS_PN = "268";
"VSS118":   PN = "270"  !CDS_PN = "270";
"VSS119":   PN = "273"  !CDS_PN = "273";
"VSS120":   PN = "275"  !CDS_PN = "275";
"VSS121":   PN = "277"  !CDS_PN = "277";
"VSS122":   PN = "279"  !CDS_PN = "279";
"VSS123":   PN = "281"  !CDS_PN = "281";
"VSS124":   PN = "284"  !CDS_PN = "284";
"VSS125":   PN = "286"  !CDS_PN = "286";
"VSS126":   PN = "288"  !CDS_PN = "288";
BODY = "SCONN288_ADR50017P087CC","I178": #LOCATION = "J16" !CDS_LOCATION = "J16" &SEC = "2" #&CDS_SEC = "2";
"DQS0_A_C":   PN = "12"  !CDS_PN = "12";
"DQS0_A_T":   PN = "11"  !CDS_PN = "11";
"DQS0_B_C":   PN = "105"  !CDS_PN = "105";
"DQS0_B_T":   PN = "104"  !CDS_PN = "104";
"DQS1_A_C":   PN = "23"  !CDS_PN = "23";
"DQS1_A_T":   PN = "22"  !CDS_PN = "22";
"DQS1_B_C":   PN = "116"  !CDS_PN = "116";
"DQS1_B_T":   PN = "115"  !CDS_PN = "115";
"DQS2_A_C":   PN = "34"  !CDS_PN = "34";
"DQS2_A_T":   PN = "33"  !CDS_PN = "33";
"DQS2_B_C":   PN = "127"  !CDS_PN = "127";
"DQS2_B_T":   PN = "126"  !CDS_PN = "126";
"DQS3_A_C":   PN = "45"  !CDS_PN = "45";
"DQS3_A_T":   PN = "44"  !CDS_PN = "44";
"DQS3_B_C":   PN = "138"  !CDS_PN = "138";
"DQS3_B_T":   PN = "137"  !CDS_PN = "137";
"DQS4_A_C":   PN = "56"  !CDS_PN = "56";
"DQS4_A_T":   PN = "55"  !CDS_PN = "55";
"DQS4_B_C":   PN = "238"  !CDS_PN = "238";
"DQS4_B_T":   PN = "239"  !CDS_PN = "239";
"DQS5_A_C||TDQS5_A_C||DQS5_A_T||TDQS5_A_T":   PN = "156"  !CDS_PN = "156";
"DQS5_A_T||TDQS5_A_T":   PN = "157"  !CDS_PN = "157";
"DQS5_B_C||TDQS5_B_C":   PN = "249"  !CDS_PN = "249";
"DQS5_B_T||TDQS5_B_T":   PN = "250"  !CDS_PN = "250";
"DQS6_A_C||TDQS6_A_C||DQS6_A_T||TDQS6_A_T":   PN = "167"  !CDS_PN = "167";
"DQS6_A_T||TDQS6_A_T":   PN = "168"  !CDS_PN = "168";
"DQS6_B_C||TDQS6_B_C":   PN = "260"  !CDS_PN = "260";
"DQS6_B_T||TDQS6_B_T":   PN = "261"  !CDS_PN = "261";
"DQS7_A_C||TDQS7_A_C":   PN = "178"  !CDS_PN = "178";
"DQS7_A_T||TDQS7_A_T":   PN = "179"  !CDS_PN = "179";
"DQS7_B_C||TDQS7_B_C":   PN = "271"  !CDS_PN = "271";
"DQS7_B_T||TDQS7_B_T":   PN = "272"  !CDS_PN = "272";
"DQS8_A_C||TDQS8_A_C":   PN = "189"  !CDS_PN = "189";
"DQS8_A_T||TDQS8_A_T":   PN = "190"  !CDS_PN = "190";
"DQS8_B_C||TDQS8_B_C":   PN = "282"  !CDS_PN = "282";
"DQS8_B_T||TDQS8_B_T":   PN = "283"  !CDS_PN = "283";
"DQS9_A_C||TDQS9_A_C":   PN = "200"  !CDS_PN = "200";
"DQS9_A_T||TDQS9_A_T":   PN = "201"  !CDS_PN = "201";
"DQS9_B_C||TDQS9_B_C":   PN = "94"  !CDS_PN = "94";
"DQS9_B_T||TDQS9_B_T||DBI4_B_N":   PN = "93"  !CDS_PN = "93";
BODY = "Q_RES","I179": LOCATION = "R3890" #&CDS_LOCATION = "R3890" &SEC = "1" #&CDS_SEC = "1";
"A":   PN = "1"  !CDS_PN = "1";
"B":   PN = "2"  !CDS_PN = "2";
DRAWING = "@s9s_mb_2u_lib.s9s_mb_2u(sch_1):page98";
BODY = "Q_RES","I11": LOCATION = "R42" #&CDS_LOCATION = "R42" &SEC = "1" #&CDS_SEC = "1";
"A":   PN = "1"  !CDS_PN = "1";
"B":   PN = "2"  !CDS_PN = "2";
BODY = "SCONN288_ADR50017P130CC","I12": LOCATION = "J17" #&CDS_LOCATION = "J17" &SEC = "1" #&CDS_SEC = "1";
"ALERT_N":   PN = "62"  !CDS_PN = "62";
"CA0_A":   PN = "66"  !CDS_PN = "66";
"CA0_B":   PN = "76"  !CDS_PN = "76";
"CA1_A":   PN = "211"  !CDS_PN = "211";
"CA1_B":   PN = "221"  !CDS_PN = "221";
"CA2_A":   PN = "68"  !CDS_PN = "68";
"CA2_B":   PN = "78"  !CDS_PN = "78";
"CA3_A":   PN = "213"  !CDS_PN = "213";
"CA3_B":   PN = "223"  !CDS_PN = "223";
"CA4_A":   PN = "70"  !CDS_PN = "70";
"CA4_B":   PN = "80"  !CDS_PN = "80";
"CA5_A":   PN = "215"  !CDS_PN = "215";
"CA5_B":   PN = "225"  !CDS_PN = "225";
"CA6_A":   PN = "72"  !CDS_PN = "72";
"CA6_B":   PN = "82"  !CDS_PN = "82";
"CB0_A":   PN = "51"  !CDS_PN = "51";
"CB0_B":   PN = "96"  !CDS_PN = "96";
"CB1_A":   PN = "53"  !CDS_PN = "53";
"CB1_B":   PN = "98"  !CDS_PN = "98";
"CB2_A":   PN = "196"  !CDS_PN = "196";
"CB2_B":   PN = "241"  !CDS_PN = "241";
"CB3_A":   PN = "198"  !CDS_PN = "198";
"CB3_B":   PN = "243"  !CDS_PN = "243";
"CB4_A":   PN = "58"  !CDS_PN = "58";
"CB4_B":   PN = "89"  !CDS_PN = "89";
"CB5_A":   PN = "60"  !CDS_PN = "60";
"CB5_B":   PN = "91"  !CDS_PN = "91";
"CB6_A":   PN = "203"  !CDS_PN = "203";
"CB6_B":   PN = "234"  !CDS_PN = "234";
"CB7_A":   PN = "205"  !CDS_PN = "205";
"CB7_B":   PN = "236"  !CDS_PN = "236";
"CK_C":   PN = "218"  !CDS_PN = "218";
"CK_T":   PN = "217"  !CDS_PN = "217";
"CS0_A_N":   PN = "64"  !CDS_PN = "64";
"CS0_B_N":   PN = "84"  !CDS_PN = "84";
"CS1_A_N":   PN = "209"  !CDS_PN = "209";
"CS1_B_N":   PN = "229"  !CDS_PN = "229";
"DQ0_A":   PN = "7"  !CDS_PN = "7";
"DQ0_B":   PN = "100"  !CDS_PN = "100";
"DQ1_A":   PN = "9"  !CDS_PN = "9";
"DQ1_B":   PN = "102"  !CDS_PN = "102";
"DQ2_A":   PN = "152"  !CDS_PN = "152";
"DQ2_B":   PN = "245"  !CDS_PN = "245";
"DQ3_A":   PN = "154"  !CDS_PN = "154";
"DQ3_B":   PN = "247"  !CDS_PN = "247";
"DQ4_A":   PN = "14"  !CDS_PN = "14";
"DQ4_B":   PN = "107"  !CDS_PN = "107";
"DQ5_A":   PN = "16"  !CDS_PN = "16";
"DQ5_B":   PN = "109"  !CDS_PN = "109";
"DQ6_A":   PN = "159"  !CDS_PN = "159";
"DQ6_B":   PN = "252"  !CDS_PN = "252";
"DQ7_A":   PN = "161"  !CDS_PN = "161";
"DQ7_B":   PN = "254"  !CDS_PN = "254";
"DQ8_A":   PN = "18"  !CDS_PN = "18";
"DQ8_B":   PN = "111"  !CDS_PN = "111";
"DQ9_A":   PN = "20"  !CDS_PN = "20";
"DQ9_B":   PN = "113"  !CDS_PN = "113";
"DQ10_A":   PN = "163"  !CDS_PN = "163";
"DQ10_B":   PN = "256"  !CDS_PN = "256";
"DQ11_A":   PN = "165"  !CDS_PN = "165";
"DQ11_B":   PN = "258"  !CDS_PN = "258";
"DQ12_A":   PN = "25"  !CDS_PN = "25";
"DQ12_B":   PN = "118"  !CDS_PN = "118";
"DQ13_A":   PN = "27"  !CDS_PN = "27";
"DQ13_B":   PN = "120"  !CDS_PN = "120";
"DQ14_A":   PN = "170"  !CDS_PN = "170";
"DQ14_B":   PN = "263"  !CDS_PN = "263";
"DQ15_A":   PN = "172"  !CDS_PN = "172";
"DQ15_B":   PN = "265"  !CDS_PN = "265";
"DQ16_A":   PN = "29"  !CDS_PN = "29";
"DQ16_B":   PN = "122"  !CDS_PN = "122";
"DQ17_A":   PN = "31"  !CDS_PN = "31";
"DQ17_B":   PN = "124"  !CDS_PN = "124";
"DQ18_A":   PN = "174"  !CDS_PN = "174";
"DQ18_B":   PN = "267"  !CDS_PN = "267";
"DQ19_A":   PN = "176"  !CDS_PN = "176";
"DQ19_B":   PN = "269"  !CDS_PN = "269";
"DQ20_A":   PN = "36"  !CDS_PN = "36";
"DQ20_B":   PN = "129"  !CDS_PN = "129";
"DQ21_A":   PN = "38"  !CDS_PN = "38";
"DQ21_B":   PN = "131"  !CDS_PN = "131";
"DQ22_A":   PN = "181"  !CDS_PN = "181";
"DQ22_B":   PN = "274"  !CDS_PN = "274";
"DQ23_A":   PN = "183"  !CDS_PN = "183";
"DQ23_B":   PN = "276"  !CDS_PN = "276";
"DQ24_A":   PN = "40"  !CDS_PN = "40";
"DQ24_B":   PN = "133"  !CDS_PN = "133";
"DQ25_A":   PN = "42"  !CDS_PN = "42";
"DQ25_B":   PN = "135"  !CDS_PN = "135";
"DQ26_A":   PN = "185"  !CDS_PN = "185";
"DQ26_B":   PN = "278"  !CDS_PN = "278";
"DQ27_A":   PN = "187"  !CDS_PN = "187";
"DQ27_B":   PN = "280"  !CDS_PN = "280";
"DQ28_A":   PN = "47"  !CDS_PN = "47";
"DQ28_B":   PN = "140"  !CDS_PN = "140";
"DQ29_A":   PN = "49"  !CDS_PN = "49";
"DQ29_B":   PN = "142"  !CDS_PN = "142";
"DQ30_A":   PN = "192"  !CDS_PN = "192";
"DQ30_B":   PN = "285"  !CDS_PN = "285";
"DQ31_A":   PN = "194"  !CDS_PN = "194";
"DQ31_B":   PN = "287"  !CDS_PN = "287";
"HSA":   PN = "148"  !CDS_PN = "148";
"HSCL":   PN = "4"  !CDS_PN = "4";
"HSDA":   PN = "5"  !CDS_PN = "5";
"LBD||RSP_A_N":   PN = "86"  !CDS_PN = "86";
"LBS||RSP_B_N":   PN = "87"  !CDS_PN = "87";
"PAR_A":   PN = "74"  !CDS_PN = "74";
"PAR_B":   PN = "227"  !CDS_PN = "227";
"PWR_GOOD||FAIL_N":   PN = "147"  !CDS_PN = "147";
"RESET_N":   PN = "207"  !CDS_PN = "207";
"RFU0":   PN = "2"  !CDS_PN = "2";
"RFU1":   PN = "144"  !CDS_PN = "144";
"RFU2":   PN = "149"  !CDS_PN = "149";
"RFU3":   PN = "150"  !CDS_PN = "150";
"RFU4":   PN = "220"  !CDS_PN = "220";
"RFU5":   PN = "231"  !CDS_PN = "231";
"RFU6":   PN = "232"  !CDS_PN = "232";
"VIN_MGMT":   PN = "3"  !CDS_PN = "3";
BODY = "Q_CAP","I122": LOCATION = "C50" #&CDS_LOCATION = "C50" &SEC = "1" #&CDS_SEC = "1";
"A":   PN = "1"  !CDS_PN = "1";
"B":   PN = "2"  !CDS_PN = "2";
BODY = "Q_CAP","I123": LOCATION = "C51" #&CDS_LOCATION = "C51" &SEC = "1" #&CDS_SEC = "1";
"A":   PN = "1"  !CDS_PN = "1";
"B":   PN = "2"  !CDS_PN = "2";
BODY = "Q_CAP","I145": LOCATION = "C52" #&CDS_LOCATION = "C52" &SEC = "1" #&CDS_SEC = "1";
"A":   PN = "1"  !CDS_PN = "1";
"B":   PN = "2"  !CDS_PN = "2";
BODY = "SCONN288_ADR50017P130CC","I147": LOCATION = "J17" #&CDS_LOCATION = "J17" &SEC = "3" #&CDS_SEC = "3";
"G1":   PN = "G1"  !CDS_PN = "G1";
"G2":   PN = "G2"  !CDS_PN = "G2";
"G3":   PN = "G3"  !CDS_PN = "G3";
"VIN_BULK0":   PN = "1"  !CDS_PN = "1";
"VIN_BULK1":   PN = "145"  !CDS_PN = "145";
"VIN_BULK2":   PN = "146"  !CDS_PN = "146";
"VSS0":   PN = "6"  !CDS_PN = "6";
"VSS1":   PN = "8"  !CDS_PN = "8";
"VSS2":   PN = "10"  !CDS_PN = "10";
"VSS3":   PN = "13"  !CDS_PN = "13";
"VSS4":   PN = "15"  !CDS_PN = "15";
"VSS5":   PN = "17"  !CDS_PN = "17";
"VSS6":   PN = "19"  !CDS_PN = "19";
"VSS7":   PN = "21"  !CDS_PN = "21";
"VSS8":   PN = "24"  !CDS_PN = "24";
"VSS9":   PN = "26"  !CDS_PN = "26";
"VSS10":   PN = "28"  !CDS_PN = "28";
"VSS11":   PN = "30"  !CDS_PN = "30";
"VSS12":   PN = "32"  !CDS_PN = "32";
"VSS13":   PN = "35"  !CDS_PN = "35";
"VSS14":   PN = "37"  !CDS_PN = "37";
"VSS15":   PN = "39"  !CDS_PN = "39";
"VSS16":   PN = "41"  !CDS_PN = "41";
"VSS17":   PN = "43"  !CDS_PN = "43";
"VSS18":   PN = "46"  !CDS_PN = "46";
"VSS19":   PN = "48"  !CDS_PN = "48";
"VSS20":   PN = "50"  !CDS_PN = "50";
"VSS21":   PN = "52"  !CDS_PN = "52";
"VSS22":   PN = "54"  !CDS_PN = "54";
"VSS23":   PN = "57"  !CDS_PN = "57";
"VSS24":   PN = "59"  !CDS_PN = "59";
"VSS25":   PN = "61"  !CDS_PN = "61";
"VSS26":   PN = "63"  !CDS_PN = "63";
"VSS27":   PN = "65"  !CDS_PN = "65";
"VSS28":   PN = "67"  !CDS_PN = "67";
"VSS29":   PN = "69"  !CDS_PN = "69";
"VSS30":   PN = "71"  !CDS_PN = "71";
"VSS31":   PN = "73"  !CDS_PN = "73";
"VSS32":   PN = "75"  !CDS_PN = "75";
"VSS33":   PN = "77"  !CDS_PN = "77";
"VSS34":   PN = "79"  !CDS_PN = "79";
"VSS35":   PN = "81"  !CDS_PN = "81";
"VSS36":   PN = "83"  !CDS_PN = "83";
"VSS37":   PN = "85"  !CDS_PN = "85";
"VSS38":   PN = "88"  !CDS_PN = "88";
"VSS39":   PN = "90"  !CDS_PN = "90";
"VSS40":   PN = "92"  !CDS_PN = "92";
"VSS41":   PN = "95"  !CDS_PN = "95";
"VSS42":   PN = "97"  !CDS_PN = "97";
"VSS43":   PN = "99"  !CDS_PN = "99";
"VSS44":   PN = "101"  !CDS_PN = "101";
"VSS45":   PN = "103"  !CDS_PN = "103";
"VSS46":   PN = "106"  !CDS_PN = "106";
"VSS47":   PN = "108"  !CDS_PN = "108";
"VSS48":   PN = "110"  !CDS_PN = "110";
"VSS49":   PN = "112"  !CDS_PN = "112";
"VSS50":   PN = "114"  !CDS_PN = "114";
"VSS51":   PN = "117"  !CDS_PN = "117";
"VSS52":   PN = "119"  !CDS_PN = "119";
"VSS53":   PN = "121"  !CDS_PN = "121";
"VSS54":   PN = "123"  !CDS_PN = "123";
"VSS55":   PN = "125"  !CDS_PN = "125";
"VSS56":   PN = "128"  !CDS_PN = "128";
"VSS57":   PN = "130"  !CDS_PN = "130";
"VSS58":   PN = "132"  !CDS_PN = "132";
"VSS59":   PN = "134"  !CDS_PN = "134";
"VSS60":   PN = "136"  !CDS_PN = "136";
"VSS61":   PN = "139"  !CDS_PN = "139";
"VSS62":   PN = "141"  !CDS_PN = "141";
"VSS63":   PN = "143"  !CDS_PN = "143";
"VSS64":   PN = "151"  !CDS_PN = "151";
"VSS65":   PN = "153"  !CDS_PN = "153";
"VSS66":   PN = "155"  !CDS_PN = "155";
"VSS67":   PN = "158"  !CDS_PN = "158";
"VSS68":   PN = "160"  !CDS_PN = "160";
"VSS69":   PN = "162"  !CDS_PN = "162";
"VSS70":   PN = "164"  !CDS_PN = "164";
"VSS71":   PN = "166"  !CDS_PN = "166";
"VSS72":   PN = "169"  !CDS_PN = "169";
"VSS73":   PN = "171"  !CDS_PN = "171";
"VSS74":   PN = "173"  !CDS_PN = "173";
"VSS75":   PN = "175"  !CDS_PN = "175";
"VSS76":   PN = "177"  !CDS_PN = "177";
"VSS77":   PN = "180"  !CDS_PN = "180";
"VSS78":   PN = "182"  !CDS_PN = "182";
"VSS79":   PN = "184"  !CDS_PN = "184";
"VSS80":   PN = "186"  !CDS_PN = "186";
"VSS81":   PN = "188"  !CDS_PN = "188";
"VSS82":   PN = "191"  !CDS_PN = "191";
"VSS83":   PN = "193"  !CDS_PN = "193";
"VSS84":   PN = "195"  !CDS_PN = "195";
"VSS85":   PN = "197"  !CDS_PN = "197";
"VSS86":   PN = "199"  !CDS_PN = "199";
"VSS87":   PN = "202"  !CDS_PN = "202";
"VSS88":   PN = "204"  !CDS_PN = "204";
"VSS89":   PN = "206"  !CDS_PN = "206";
"VSS90":   PN = "208"  !CDS_PN = "208";
"VSS91":   PN = "210"  !CDS_PN = "210";
"VSS92":   PN = "212"  !CDS_PN = "212";
"VSS93":   PN = "214"  !CDS_PN = "214";
"VSS94":   PN = "216"  !CDS_PN = "216";
"VSS95":   PN = "219"  !CDS_PN = "219";
"VSS96":   PN = "222"  !CDS_PN = "222";
"VSS97":   PN = "224"  !CDS_PN = "224";
"VSS98":   PN = "226"  !CDS_PN = "226";
"VSS99":   PN = "228"  !CDS_PN = "228";
"VSS100":   PN = "230"  !CDS_PN = "230";
"VSS101":   PN = "233"  !CDS_PN = "233";
"VSS102":   PN = "235"  !CDS_PN = "235";
"VSS103":   PN = "237"  !CDS_PN = "237";
"VSS104":   PN = "240"  !CDS_PN = "240";
"VSS105":   PN = "242"  !CDS_PN = "242";
"VSS106":   PN = "244"  !CDS_PN = "244";
"VSS107":   PN = "246"  !CDS_PN = "246";
"VSS108":   PN = "248"  !CDS_PN = "248";
"VSS109":   PN = "251"  !CDS_PN = "251";
"VSS110":   PN = "253"  !CDS_PN = "253";
"VSS111":   PN = "255"  !CDS_PN = "255";
"VSS112":   PN = "257"  !CDS_PN = "257";
"VSS113":   PN = "259"  !CDS_PN = "259";
"VSS114":   PN = "262"  !CDS_PN = "262";
"VSS115":   PN = "264"  !CDS_PN = "264";
"VSS116":   PN = "266"  !CDS_PN = "266";
"VSS117":   PN = "268"  !CDS_PN = "268";
"VSS118":   PN = "270"  !CDS_PN = "270";
"VSS119":   PN = "273"  !CDS_PN = "273";
"VSS120":   PN = "275"  !CDS_PN = "275";
"VSS121":   PN = "277"  !CDS_PN = "277";
"VSS122":   PN = "279"  !CDS_PN = "279";
"VSS123":   PN = "281"  !CDS_PN = "281";
"VSS124":   PN = "284"  !CDS_PN = "284";
"VSS125":   PN = "286"  !CDS_PN = "286";
"VSS126":   PN = "288"  !CDS_PN = "288";
BODY = "SCONN288_ADR50017P130CC","I178": #LOCATION = "J17" !CDS_LOCATION = "J17" &SEC = "2" #&CDS_SEC = "2";
"DQS0_A_C":   PN = "12"  !CDS_PN = "12";
"DQS0_A_T":   PN = "11"  !CDS_PN = "11";
"DQS0_B_C":   PN = "105"  !CDS_PN = "105";
"DQS0_B_T":   PN = "104"  !CDS_PN = "104";
"DQS1_A_C":   PN = "23"  !CDS_PN = "23";
"DQS1_A_T":   PN = "22"  !CDS_PN = "22";
"DQS1_B_C":   PN = "116"  !CDS_PN = "116";
"DQS1_B_T":   PN = "115"  !CDS_PN = "115";
"DQS2_A_C":   PN = "34"  !CDS_PN = "34";
"DQS2_A_T":   PN = "33"  !CDS_PN = "33";
"DQS2_B_C":   PN = "127"  !CDS_PN = "127";
"DQS2_B_T":   PN = "126"  !CDS_PN = "126";
"DQS3_A_C":   PN = "45"  !CDS_PN = "45";
"DQS3_A_T":   PN = "44"  !CDS_PN = "44";
"DQS3_B_C":   PN = "138"  !CDS_PN = "138";
"DQS3_B_T":   PN = "137"  !CDS_PN = "137";
"DQS4_A_C":   PN = "56"  !CDS_PN = "56";
"DQS4_A_T":   PN = "55"  !CDS_PN = "55";
"DQS4_B_C":   PN = "238"  !CDS_PN = "238";
"DQS4_B_T":   PN = "239"  !CDS_PN = "239";
"DQS5_A_C||TDQS5_A_C||DQS5_A_T||TDQS5_A_T":   PN = "156"  !CDS_PN = "156";
"DQS5_A_T||TDQS5_A_T":   PN = "157"  !CDS_PN = "157";
"DQS5_B_C||TDQS5_B_C":   PN = "249"  !CDS_PN = "249";
"DQS5_B_T||TDQS5_B_T":   PN = "250"  !CDS_PN = "250";
"DQS6_A_C||TDQS6_A_C||DQS6_A_T||TDQS6_A_T":   PN = "167"  !CDS_PN = "167";
"DQS6_A_T||TDQS6_A_T":   PN = "168"  !CDS_PN = "168";
"DQS6_B_C||TDQS6_B_C":   PN = "260"  !CDS_PN = "260";
"DQS6_B_T||TDQS6_B_T":   PN = "261"  !CDS_PN = "261";
"DQS7_A_C||TDQS7_A_C":   PN = "178"  !CDS_PN = "178";
"DQS7_A_T||TDQS7_A_T":   PN = "179"  !CDS_PN = "179";
"DQS7_B_C||TDQS7_B_C":   PN = "271"  !CDS_PN = "271";
"DQS7_B_T||TDQS7_B_T":   PN = "272"  !CDS_PN = "272";
"DQS8_A_C||TDQS8_A_C":   PN = "189"  !CDS_PN = "189";
"DQS8_A_T||TDQS8_A_T":   PN = "190"  !CDS_PN = "190";
"DQS8_B_C||TDQS8_B_C":   PN = "282"  !CDS_PN = "282";
"DQS8_B_T||TDQS8_B_T":   PN = "283"  !CDS_PN = "283";
"DQS9_A_C||TDQS9_A_C":   PN = "200"  !CDS_PN = "200";
"DQS9_A_T||TDQS9_A_T":   PN = "201"  !CDS_PN = "201";
"DQS9_B_C||TDQS9_B_C":   PN = "94"  !CDS_PN = "94";
"DQS9_B_T||TDQS9_B_T||DBI4_B_N":   PN = "93"  !CDS_PN = "93";
BODY = "Q_RES","I179": LOCATION = "R3891" #&CDS_LOCATION = "R3891" &SEC = "1" #&CDS_SEC = "1";
"A":   PN = "1"  !CDS_PN = "1";
"B":   PN = "2"  !CDS_PN = "2";
DRAWING = "@s9s_mb_2u_lib.s9s_mb_2u(sch_1):page99";
BODY = "Q_RES","I2": LOCATION = "R43" #&CDS_LOCATION = "R43" &SEC = "1" #&CDS_SEC = "1";
"A":   PN = "1"  !CDS_PN = "1";
"B":   PN = "2"  !CDS_PN = "2";
BODY = "SCONN288_ADR50017P087CC","I24": LOCATION = "J18" #&CDS_LOCATION = "J18" &SEC = "1" #&CDS_SEC = "1";
"ALERT_N":   PN = "62"  !CDS_PN = "62";
"CA0_A":   PN = "66"  !CDS_PN = "66";
"CA0_B":   PN = "76"  !CDS_PN = "76";
"CA1_A":   PN = "211"  !CDS_PN = "211";
"CA1_B":   PN = "221"  !CDS_PN = "221";
"CA2_A":   PN = "68"  !CDS_PN = "68";
"CA2_B":   PN = "78"  !CDS_PN = "78";
"CA3_A":   PN = "213"  !CDS_PN = "213";
"CA3_B":   PN = "223"  !CDS_PN = "223";
"CA4_A":   PN = "70"  !CDS_PN = "70";
"CA4_B":   PN = "80"  !CDS_PN = "80";
"CA5_A":   PN = "215"  !CDS_PN = "215";
"CA5_B":   PN = "225"  !CDS_PN = "225";
"CA6_A":   PN = "72"  !CDS_PN = "72";
"CA6_B":   PN = "82"  !CDS_PN = "82";
"CB0_A":   PN = "51"  !CDS_PN = "51";
"CB0_B":   PN = "96"  !CDS_PN = "96";
"CB1_A":   PN = "53"  !CDS_PN = "53";
"CB1_B":   PN = "98"  !CDS_PN = "98";
"CB2_A":   PN = "196"  !CDS_PN = "196";
"CB2_B":   PN = "241"  !CDS_PN = "241";
"CB3_A":   PN = "198"  !CDS_PN = "198";
"CB3_B":   PN = "243"  !CDS_PN = "243";
"CB4_A":   PN = "58"  !CDS_PN = "58";
"CB4_B":   PN = "89"  !CDS_PN = "89";
"CB5_A":   PN = "60"  !CDS_PN = "60";
"CB5_B":   PN = "91"  !CDS_PN = "91";
"CB6_A":   PN = "203"  !CDS_PN = "203";
"CB6_B":   PN = "234"  !CDS_PN = "234";
"CB7_A":   PN = "205"  !CDS_PN = "205";
"CB7_B":   PN = "236"  !CDS_PN = "236";
"CK_C":   PN = "218"  !CDS_PN = "218";
"CK_T":   PN = "217"  !CDS_PN = "217";
"CS0_A_N":   PN = "64"  !CDS_PN = "64";
"CS0_B_N":   PN = "84"  !CDS_PN = "84";
"CS1_A_N":   PN = "209"  !CDS_PN = "209";
"CS1_B_N":   PN = "229"  !CDS_PN = "229";
"DQ0_A":   PN = "7"  !CDS_PN = "7";
"DQ0_B":   PN = "100"  !CDS_PN = "100";
"DQ1_A":   PN = "9"  !CDS_PN = "9";
"DQ1_B":   PN = "102"  !CDS_PN = "102";
"DQ2_A":   PN = "152"  !CDS_PN = "152";
"DQ2_B":   PN = "245"  !CDS_PN = "245";
"DQ3_A":   PN = "154"  !CDS_PN = "154";
"DQ3_B":   PN = "247"  !CDS_PN = "247";
"DQ4_A":   PN = "14"  !CDS_PN = "14";
"DQ4_B":   PN = "107"  !CDS_PN = "107";
"DQ5_A":   PN = "16"  !CDS_PN = "16";
"DQ5_B":   PN = "109"  !CDS_PN = "109";
"DQ6_A":   PN = "159"  !CDS_PN = "159";
"DQ6_B":   PN = "252"  !CDS_PN = "252";
"DQ7_A":   PN = "161"  !CDS_PN = "161";
"DQ7_B":   PN = "254"  !CDS_PN = "254";
"DQ8_A":   PN = "18"  !CDS_PN = "18";
"DQ8_B":   PN = "111"  !CDS_PN = "111";
"DQ9_A":   PN = "20"  !CDS_PN = "20";
"DQ9_B":   PN = "113"  !CDS_PN = "113";
"DQ10_A":   PN = "163"  !CDS_PN = "163";
"DQ10_B":   PN = "256"  !CDS_PN = "256";
"DQ11_A":   PN = "165"  !CDS_PN = "165";
"DQ11_B":   PN = "258"  !CDS_PN = "258";
"DQ12_A":   PN = "25"  !CDS_PN = "25";
"DQ12_B":   PN = "118"  !CDS_PN = "118";
"DQ13_A":   PN = "27"  !CDS_PN = "27";
"DQ13_B":   PN = "120"  !CDS_PN = "120";
"DQ14_A":   PN = "170"  !CDS_PN = "170";
"DQ14_B":   PN = "263"  !CDS_PN = "263";
"DQ15_A":   PN = "172"  !CDS_PN = "172";
"DQ15_B":   PN = "265"  !CDS_PN = "265";
"DQ16_A":   PN = "29"  !CDS_PN = "29";
"DQ16_B":   PN = "122"  !CDS_PN = "122";
"DQ17_A":   PN = "31"  !CDS_PN = "31";
"DQ17_B":   PN = "124"  !CDS_PN = "124";
"DQ18_A":   PN = "174"  !CDS_PN = "174";
"DQ18_B":   PN = "267"  !CDS_PN = "267";
"DQ19_A":   PN = "176"  !CDS_PN = "176";
"DQ19_B":   PN = "269"  !CDS_PN = "269";
"DQ20_A":   PN = "36"  !CDS_PN = "36";
"DQ20_B":   PN = "129"  !CDS_PN = "129";
"DQ21_A":   PN = "38"  !CDS_PN = "38";
"DQ21_B":   PN = "131"  !CDS_PN = "131";
"DQ22_A":   PN = "181"  !CDS_PN = "181";
"DQ22_B":   PN = "274"  !CDS_PN = "274";
"DQ23_A":   PN = "183"  !CDS_PN = "183";
"DQ23_B":   PN = "276"  !CDS_PN = "276";
"DQ24_A":   PN = "40"  !CDS_PN = "40";
"DQ24_B":   PN = "133"  !CDS_PN = "133";
"DQ25_A":   PN = "42"  !CDS_PN = "42";
"DQ25_B":   PN = "135"  !CDS_PN = "135";
"DQ26_A":   PN = "185"  !CDS_PN = "185";
"DQ26_B":   PN = "278"  !CDS_PN = "278";
"DQ27_A":   PN = "187"  !CDS_PN = "187";
"DQ27_B":   PN = "280"  !CDS_PN = "280";
"DQ28_A":   PN = "47"  !CDS_PN = "47";
"DQ28_B":   PN = "140"  !CDS_PN = "140";
"DQ29_A":   PN = "49"  !CDS_PN = "49";
"DQ29_B":   PN = "142"  !CDS_PN = "142";
"DQ30_A":   PN = "192"  !CDS_PN = "192";
"DQ30_B":   PN = "285"  !CDS_PN = "285";
"DQ31_A":   PN = "194"  !CDS_PN = "194";
"DQ31_B":   PN = "287"  !CDS_PN = "287";
"HSA":   PN = "148"  !CDS_PN = "148";
"HSCL":   PN = "4"  !CDS_PN = "4";
"HSDA":   PN = "5"  !CDS_PN = "5";
"LBD||RSP_A_N":   PN = "86"  !CDS_PN = "86";
"LBS||RSP_B_N":   PN = "87"  !CDS_PN = "87";
"PAR_A":   PN = "74"  !CDS_PN = "74";
"PAR_B":   PN = "227"  !CDS_PN = "227";
"PWR_GOOD||FAIL_N":   PN = "147"  !CDS_PN = "147";
"RESET_N":   PN = "207"  !CDS_PN = "207";
"RFU0":   PN = "2"  !CDS_PN = "2";
"RFU1":   PN = "144"  !CDS_PN = "144";
"RFU2":   PN = "149"  !CDS_PN = "149";
"RFU3":   PN = "150"  !CDS_PN = "150";
"RFU4":   PN = "220"  !CDS_PN = "220";
"RFU5":   PN = "231"  !CDS_PN = "231";
"RFU6":   PN = "232"  !CDS_PN = "232";
"VIN_MGMT":   PN = "3"  !CDS_PN = "3";
BODY = "Q_CAP","I122": LOCATION = "C53" #&CDS_LOCATION = "C53" &SEC = "1" #&CDS_SEC = "1";
"A":   PN = "1"  !CDS_PN = "1";
"B":   PN = "2"  !CDS_PN = "2";
BODY = "Q_CAP","I126": LOCATION = "C54" #&CDS_LOCATION = "C54" &SEC = "1" #&CDS_SEC = "1";
"A":   PN = "1"  !CDS_PN = "1";
"B":   PN = "2"  !CDS_PN = "2";
BODY = "Q_CAP","I128": LOCATION = "C55" #&CDS_LOCATION = "C55" &SEC = "1" #&CDS_SEC = "1";
"A":   PN = "1"  !CDS_PN = "1";
"B":   PN = "2"  !CDS_PN = "2";
BODY = "SCONN288_ADR50017P087CC","I175": LOCATION = "J18" #&CDS_LOCATION = "J18" &SEC = "3" #&CDS_SEC = "3";
"G1":   PN = "G1"  !CDS_PN = "G1";
"G2":   PN = "G2"  !CDS_PN = "G2";
"G3":   PN = "G3"  !CDS_PN = "G3";
"VIN_BULK0":   PN = "1"  !CDS_PN = "1";
"VIN_BULK1":   PN = "145"  !CDS_PN = "145";
"VIN_BULK2":   PN = "146"  !CDS_PN = "146";
"VSS0":   PN = "6"  !CDS_PN = "6";
"VSS1":   PN = "8"  !CDS_PN = "8";
"VSS2":   PN = "10"  !CDS_PN = "10";
"VSS3":   PN = "13"  !CDS_PN = "13";
"VSS4":   PN = "15"  !CDS_PN = "15";
"VSS5":   PN = "17"  !CDS_PN = "17";
"VSS6":   PN = "19"  !CDS_PN = "19";
"VSS7":   PN = "21"  !CDS_PN = "21";
"VSS8":   PN = "24"  !CDS_PN = "24";
"VSS9":   PN = "26"  !CDS_PN = "26";
"VSS10":   PN = "28"  !CDS_PN = "28";
"VSS11":   PN = "30"  !CDS_PN = "30";
"VSS12":   PN = "32"  !CDS_PN = "32";
"VSS13":   PN = "35"  !CDS_PN = "35";
"VSS14":   PN = "37"  !CDS_PN = "37";
"VSS15":   PN = "39"  !CDS_PN = "39";
"VSS16":   PN = "41"  !CDS_PN = "41";
"VSS17":   PN = "43"  !CDS_PN = "43";
"VSS18":   PN = "46"  !CDS_PN = "46";
"VSS19":   PN = "48"  !CDS_PN = "48";
"VSS20":   PN = "50"  !CDS_PN = "50";
"VSS21":   PN = "52"  !CDS_PN = "52";
"VSS22":   PN = "54"  !CDS_PN = "54";
"VSS23":   PN = "57"  !CDS_PN = "57";
"VSS24":   PN = "59"  !CDS_PN = "59";
"VSS25":   PN = "61"  !CDS_PN = "61";
"VSS26":   PN = "63"  !CDS_PN = "63";
"VSS27":   PN = "65"  !CDS_PN = "65";
"VSS28":   PN = "67"  !CDS_PN = "67";
"VSS29":   PN = "69"  !CDS_PN = "69";
"VSS30":   PN = "71"  !CDS_PN = "71";
"VSS31":   PN = "73"  !CDS_PN = "73";
"VSS32":   PN = "75"  !CDS_PN = "75";
"VSS33":   PN = "77"  !CDS_PN = "77";
"VSS34":   PN = "79"  !CDS_PN = "79";
"VSS35":   PN = "81"  !CDS_PN = "81";
"VSS36":   PN = "83"  !CDS_PN = "83";
"VSS37":   PN = "85"  !CDS_PN = "85";
"VSS38":   PN = "88"  !CDS_PN = "88";
"VSS39":   PN = "90"  !CDS_PN = "90";
"VSS40":   PN = "92"  !CDS_PN = "92";
"VSS41":   PN = "95"  !CDS_PN = "95";
"VSS42":   PN = "97"  !CDS_PN = "97";
"VSS43":   PN = "99"  !CDS_PN = "99";
"VSS44":   PN = "101"  !CDS_PN = "101";
"VSS45":   PN = "103"  !CDS_PN = "103";
"VSS46":   PN = "106"  !CDS_PN = "106";
"VSS47":   PN = "108"  !CDS_PN = "108";
"VSS48":   PN = "110"  !CDS_PN = "110";
"VSS49":   PN = "112"  !CDS_PN = "112";
"VSS50":   PN = "114"  !CDS_PN = "114";
"VSS51":   PN = "117"  !CDS_PN = "117";
"VSS52":   PN = "119"  !CDS_PN = "119";
"VSS53":   PN = "121"  !CDS_PN = "121";
"VSS54":   PN = "123"  !CDS_PN = "123";
"VSS55":   PN = "125"  !CDS_PN = "125";
"VSS56":   PN = "128"  !CDS_PN = "128";
"VSS57":   PN = "130"  !CDS_PN = "130";
"VSS58":   PN = "132"  !CDS_PN = "132";
"VSS59":   PN = "134"  !CDS_PN = "134";
"VSS60":   PN = "136"  !CDS_PN = "136";
"VSS61":   PN = "139"  !CDS_PN = "139";
"VSS62":   PN = "141"  !CDS_PN = "141";
"VSS63":   PN = "143"  !CDS_PN = "143";
"VSS64":   PN = "151"  !CDS_PN = "151";
"VSS65":   PN = "153"  !CDS_PN = "153";
"VSS66":   PN = "155"  !CDS_PN = "155";
"VSS67":   PN = "158"  !CDS_PN = "158";
"VSS68":   PN = "160"  !CDS_PN = "160";
"VSS69":   PN = "162"  !CDS_PN = "162";
"VSS70":   PN = "164"  !CDS_PN = "164";
"VSS71":   PN = "166"  !CDS_PN = "166";
"VSS72":   PN = "169"  !CDS_PN = "169";
"VSS73":   PN = "171"  !CDS_PN = "171";
"VSS74":   PN = "173"  !CDS_PN = "173";
"VSS75":   PN = "175"  !CDS_PN = "175";
"VSS76":   PN = "177"  !CDS_PN = "177";
"VSS77":   PN = "180"  !CDS_PN = "180";
"VSS78":   PN = "182"  !CDS_PN = "182";
"VSS79":   PN = "184"  !CDS_PN = "184";
"VSS80":   PN = "186"  !CDS_PN = "186";
"VSS81":   PN = "188"  !CDS_PN = "188";
"VSS82":   PN = "191"  !CDS_PN = "191";
"VSS83":   PN = "193"  !CDS_PN = "193";
"VSS84":   PN = "195"  !CDS_PN = "195";
"VSS85":   PN = "197"  !CDS_PN = "197";
"VSS86":   PN = "199"  !CDS_PN = "199";
"VSS87":   PN = "202"  !CDS_PN = "202";
"VSS88":   PN = "204"  !CDS_PN = "204";
"VSS89":   PN = "206"  !CDS_PN = "206";
"VSS90":   PN = "208"  !CDS_PN = "208";
"VSS91":   PN = "210"  !CDS_PN = "210";
"VSS92":   PN = "212"  !CDS_PN = "212";
"VSS93":   PN = "214"  !CDS_PN = "214";
"VSS94":   PN = "216"  !CDS_PN = "216";
"VSS95":   PN = "219"  !CDS_PN = "219";
"VSS96":   PN = "222"  !CDS_PN = "222";
"VSS97":   PN = "224"  !CDS_PN = "224";
"VSS98":   PN = "226"  !CDS_PN = "226";
"VSS99":   PN = "228"  !CDS_PN = "228";
"VSS100":   PN = "230"  !CDS_PN = "230";
"VSS101":   PN = "233"  !CDS_PN = "233";
"VSS102":   PN = "235"  !CDS_PN = "235";
"VSS103":   PN = "237"  !CDS_PN = "237";
"VSS104":   PN = "240"  !CDS_PN = "240";
"VSS105":   PN = "242"  !CDS_PN = "242";
"VSS106":   PN = "244"  !CDS_PN = "244";
"VSS107":   PN = "246"  !CDS_PN = "246";
"VSS108":   PN = "248"  !CDS_PN = "248";
"VSS109":   PN = "251"  !CDS_PN = "251";
"VSS110":   PN = "253"  !CDS_PN = "253";
"VSS111":   PN = "255"  !CDS_PN = "255";
"VSS112":   PN = "257"  !CDS_PN = "257";
"VSS113":   PN = "259"  !CDS_PN = "259";
"VSS114":   PN = "262"  !CDS_PN = "262";
"VSS115":   PN = "264"  !CDS_PN = "264";
"VSS116":   PN = "266"  !CDS_PN = "266";
"VSS117":   PN = "268"  !CDS_PN = "268";
"VSS118":   PN = "270"  !CDS_PN = "270";
"VSS119":   PN = "273"  !CDS_PN = "273";
"VSS120":   PN = "275"  !CDS_PN = "275";
"VSS121":   PN = "277"  !CDS_PN = "277";
"VSS122":   PN = "279"  !CDS_PN = "279";
"VSS123":   PN = "281"  !CDS_PN = "281";
"VSS124":   PN = "284"  !CDS_PN = "284";
"VSS125":   PN = "286"  !CDS_PN = "286";
"VSS126":   PN = "288"  !CDS_PN = "288";
BODY = "SCONN288_ADR50017P087CC","I178": #LOCATION = "J18" !CDS_LOCATION = "J18" &SEC = "2" #&CDS_SEC = "2";
"DQS0_A_C":   PN = "12"  !CDS_PN = "12";
"DQS0_A_T":   PN = "11"  !CDS_PN = "11";
"DQS0_B_C":   PN = "105"  !CDS_PN = "105";
"DQS0_B_T":   PN = "104"  !CDS_PN = "104";
"DQS1_A_C":   PN = "23"  !CDS_PN = "23";
"DQS1_A_T":   PN = "22"  !CDS_PN = "22";
"DQS1_B_C":   PN = "116"  !CDS_PN = "116";
"DQS1_B_T":   PN = "115"  !CDS_PN = "115";
"DQS2_A_C":   PN = "34"  !CDS_PN = "34";
"DQS2_A_T":   PN = "33"  !CDS_PN = "33";
"DQS2_B_C":   PN = "127"  !CDS_PN = "127";
"DQS2_B_T":   PN = "126"  !CDS_PN = "126";
"DQS3_A_C":   PN = "45"  !CDS_PN = "45";
"DQS3_A_T":   PN = "44"  !CDS_PN = "44";
"DQS3_B_C":   PN = "138"  !CDS_PN = "138";
"DQS3_B_T":   PN = "137"  !CDS_PN = "137";
"DQS4_A_C":   PN = "56"  !CDS_PN = "56";
"DQS4_A_T":   PN = "55"  !CDS_PN = "55";
"DQS4_B_C":   PN = "238"  !CDS_PN = "238";
"DQS4_B_T":   PN = "239"  !CDS_PN = "239";
"DQS5_A_C||TDQS5_A_C||DQS5_A_T||TDQS5_A_T":   PN = "156"  !CDS_PN = "156";
"DQS5_A_T||TDQS5_A_T":   PN = "157"  !CDS_PN = "157";
"DQS5_B_C||TDQS5_B_C":   PN = "249"  !CDS_PN = "249";
"DQS5_B_T||TDQS5_B_T":   PN = "250"  !CDS_PN = "250";
"DQS6_A_C||TDQS6_A_C||DQS6_A_T||TDQS6_A_T":   PN = "167"  !CDS_PN = "167";
"DQS6_A_T||TDQS6_A_T":   PN = "168"  !CDS_PN = "168";
"DQS6_B_C||TDQS6_B_C":   PN = "260"  !CDS_PN = "260";
"DQS6_B_T||TDQS6_B_T":   PN = "261"  !CDS_PN = "261";
"DQS7_A_C||TDQS7_A_C":   PN = "178"  !CDS_PN = "178";
"DQS7_A_T||TDQS7_A_T":   PN = "179"  !CDS_PN = "179";
"DQS7_B_C||TDQS7_B_C":   PN = "271"  !CDS_PN = "271";
"DQS7_B_T||TDQS7_B_T":   PN = "272"  !CDS_PN = "272";
"DQS8_A_C||TDQS8_A_C":   PN = "189"  !CDS_PN = "189";
"DQS8_A_T||TDQS8_A_T":   PN = "190"  !CDS_PN = "190";
"DQS8_B_C||TDQS8_B_C":   PN = "282"  !CDS_PN = "282";
"DQS8_B_T||TDQS8_B_T":   PN = "283"  !CDS_PN = "283";
"DQS9_A_C||TDQS9_A_C":   PN = "200"  !CDS_PN = "200";
"DQS9_A_T||TDQS9_A_T":   PN = "201"  !CDS_PN = "201";
"DQS9_B_C||TDQS9_B_C":   PN = "94"  !CDS_PN = "94";
"DQS9_B_T||TDQS9_B_T||DBI4_B_N":   PN = "93"  !CDS_PN = "93";
BODY = "Q_RES","I180": LOCATION = "R3892" #&CDS_LOCATION = "R3892" &SEC = "1" #&CDS_SEC = "1";
"A":   PN = "1"  !CDS_PN = "1";
"B":   PN = "2"  !CDS_PN = "2";
DRAWING = "@s9s_mb_2u_lib.s9s_mb_2u(sch_1):page100";
BODY = "Q_RES","I3": LOCATION = "R44" #&CDS_LOCATION = "R44" &SEC = "1" #&CDS_SEC = "1";
"A":   PN = "1"  !CDS_PN = "1";
"B":   PN = "2"  !CDS_PN = "2";
BODY = "SCONN288_ADR50017P130CC","I25": LOCATION = "J19" #&CDS_LOCATION = "J19" &SEC = "1" #&CDS_SEC = "1";
"ALERT_N":   PN = "62"  !CDS_PN = "62";
"CA0_A":   PN = "66"  !CDS_PN = "66";
"CA0_B":   PN = "76"  !CDS_PN = "76";
"CA1_A":   PN = "211"  !CDS_PN = "211";
"CA1_B":   PN = "221"  !CDS_PN = "221";
"CA2_A":   PN = "68"  !CDS_PN = "68";
"CA2_B":   PN = "78"  !CDS_PN = "78";
"CA3_A":   PN = "213"  !CDS_PN = "213";
"CA3_B":   PN = "223"  !CDS_PN = "223";
"CA4_A":   PN = "70"  !CDS_PN = "70";
"CA4_B":   PN = "80"  !CDS_PN = "80";
"CA5_A":   PN = "215"  !CDS_PN = "215";
"CA5_B":   PN = "225"  !CDS_PN = "225";
"CA6_A":   PN = "72"  !CDS_PN = "72";
"CA6_B":   PN = "82"  !CDS_PN = "82";
"CB0_A":   PN = "51"  !CDS_PN = "51";
"CB0_B":   PN = "96"  !CDS_PN = "96";
"CB1_A":   PN = "53"  !CDS_PN = "53";
"CB1_B":   PN = "98"  !CDS_PN = "98";
"CB2_A":   PN = "196"  !CDS_PN = "196";
"CB2_B":   PN = "241"  !CDS_PN = "241";
"CB3_A":   PN = "198"  !CDS_PN = "198";
"CB3_B":   PN = "243"  !CDS_PN = "243";
"CB4_A":   PN = "58"  !CDS_PN = "58";
"CB4_B":   PN = "89"  !CDS_PN = "89";
"CB5_A":   PN = "60"  !CDS_PN = "60";
"CB5_B":   PN = "91"  !CDS_PN = "91";
"CB6_A":   PN = "203"  !CDS_PN = "203";
"CB6_B":   PN = "234"  !CDS_PN = "234";
"CB7_A":   PN = "205"  !CDS_PN = "205";
"CB7_B":   PN = "236"  !CDS_PN = "236";
"CK_C":   PN = "218"  !CDS_PN = "218";
"CK_T":   PN = "217"  !CDS_PN = "217";
"CS0_A_N":   PN = "64"  !CDS_PN = "64";
"CS0_B_N":   PN = "84"  !CDS_PN = "84";
"CS1_A_N":   PN = "209"  !CDS_PN = "209";
"CS1_B_N":   PN = "229"  !CDS_PN = "229";
"DQ0_A":   PN = "7"  !CDS_PN = "7";
"DQ0_B":   PN = "100"  !CDS_PN = "100";
"DQ1_A":   PN = "9"  !CDS_PN = "9";
"DQ1_B":   PN = "102"  !CDS_PN = "102";
"DQ2_A":   PN = "152"  !CDS_PN = "152";
"DQ2_B":   PN = "245"  !CDS_PN = "245";
"DQ3_A":   PN = "154"  !CDS_PN = "154";
"DQ3_B":   PN = "247"  !CDS_PN = "247";
"DQ4_A":   PN = "14"  !CDS_PN = "14";
"DQ4_B":   PN = "107"  !CDS_PN = "107";
"DQ5_A":   PN = "16"  !CDS_PN = "16";
"DQ5_B":   PN = "109"  !CDS_PN = "109";
"DQ6_A":   PN = "159"  !CDS_PN = "159";
"DQ6_B":   PN = "252"  !CDS_PN = "252";
"DQ7_A":   PN = "161"  !CDS_PN = "161";
"DQ7_B":   PN = "254"  !CDS_PN = "254";
"DQ8_A":   PN = "18"  !CDS_PN = "18";
"DQ8_B":   PN = "111"  !CDS_PN = "111";
"DQ9_A":   PN = "20"  !CDS_PN = "20";
"DQ9_B":   PN = "113"  !CDS_PN = "113";
"DQ10_A":   PN = "163"  !CDS_PN = "163";
"DQ10_B":   PN = "256"  !CDS_PN = "256";
"DQ11_A":   PN = "165"  !CDS_PN = "165";
"DQ11_B":   PN = "258"  !CDS_PN = "258";
"DQ12_A":   PN = "25"  !CDS_PN = "25";
"DQ12_B":   PN = "118"  !CDS_PN = "118";
"DQ13_A":   PN = "27"  !CDS_PN = "27";
"DQ13_B":   PN = "120"  !CDS_PN = "120";
"DQ14_A":   PN = "170"  !CDS_PN = "170";
"DQ14_B":   PN = "263"  !CDS_PN = "263";
"DQ15_A":   PN = "172"  !CDS_PN = "172";
"DQ15_B":   PN = "265"  !CDS_PN = "265";
"DQ16_A":   PN = "29"  !CDS_PN = "29";
"DQ16_B":   PN = "122"  !CDS_PN = "122";
"DQ17_A":   PN = "31"  !CDS_PN = "31";
"DQ17_B":   PN = "124"  !CDS_PN = "124";
"DQ18_A":   PN = "174"  !CDS_PN = "174";
"DQ18_B":   PN = "267"  !CDS_PN = "267";
"DQ19_A":   PN = "176"  !CDS_PN = "176";
"DQ19_B":   PN = "269"  !CDS_PN = "269";
"DQ20_A":   PN = "36"  !CDS_PN = "36";
"DQ20_B":   PN = "129"  !CDS_PN = "129";
"DQ21_A":   PN = "38"  !CDS_PN = "38";
"DQ21_B":   PN = "131"  !CDS_PN = "131";
"DQ22_A":   PN = "181"  !CDS_PN = "181";
"DQ22_B":   PN = "274"  !CDS_PN = "274";
"DQ23_A":   PN = "183"  !CDS_PN = "183";
"DQ23_B":   PN = "276"  !CDS_PN = "276";
"DQ24_A":   PN = "40"  !CDS_PN = "40";
"DQ24_B":   PN = "133"  !CDS_PN = "133";
"DQ25_A":   PN = "42"  !CDS_PN = "42";
"DQ25_B":   PN = "135"  !CDS_PN = "135";
"DQ26_A":   PN = "185"  !CDS_PN = "185";
"DQ26_B":   PN = "278"  !CDS_PN = "278";
"DQ27_A":   PN = "187"  !CDS_PN = "187";
"DQ27_B":   PN = "280"  !CDS_PN = "280";
"DQ28_A":   PN = "47"  !CDS_PN = "47";
"DQ28_B":   PN = "140"  !CDS_PN = "140";
"DQ29_A":   PN = "49"  !CDS_PN = "49";
"DQ29_B":   PN = "142"  !CDS_PN = "142";
"DQ30_A":   PN = "192"  !CDS_PN = "192";
"DQ30_B":   PN = "285"  !CDS_PN = "285";
"DQ31_A":   PN = "194"  !CDS_PN = "194";
"DQ31_B":   PN = "287"  !CDS_PN = "287";
"HSA":   PN = "148"  !CDS_PN = "148";
"HSCL":   PN = "4"  !CDS_PN = "4";
"HSDA":   PN = "5"  !CDS_PN = "5";
"LBD||RSP_A_N":   PN = "86"  !CDS_PN = "86";
"LBS||RSP_B_N":   PN = "87"  !CDS_PN = "87";
"PAR_A":   PN = "74"  !CDS_PN = "74";
"PAR_B":   PN = "227"  !CDS_PN = "227";
"PWR_GOOD||FAIL_N":   PN = "147"  !CDS_PN = "147";
"RESET_N":   PN = "207"  !CDS_PN = "207";
"RFU0":   PN = "2"  !CDS_PN = "2";
"RFU1":   PN = "144"  !CDS_PN = "144";
"RFU2":   PN = "149"  !CDS_PN = "149";
"RFU3":   PN = "150"  !CDS_PN = "150";
"RFU4":   PN = "220"  !CDS_PN = "220";
"RFU5":   PN = "231"  !CDS_PN = "231";
"RFU6":   PN = "232"  !CDS_PN = "232";
"VIN_MGMT":   PN = "3"  !CDS_PN = "3";
BODY = "Q_CAP","I121": LOCATION = "C56" #&CDS_LOCATION = "C56" &SEC = "1" #&CDS_SEC = "1";
"A":   PN = "1"  !CDS_PN = "1";
"B":   PN = "2"  !CDS_PN = "2";
BODY = "Q_CAP","I122": LOCATION = "C57" #&CDS_LOCATION = "C57" &SEC = "1" #&CDS_SEC = "1";
"A":   PN = "1"  !CDS_PN = "1";
"B":   PN = "2"  !CDS_PN = "2";
BODY = "Q_CAP","I124": LOCATION = "C58" #&CDS_LOCATION = "C58" &SEC = "1" #&CDS_SEC = "1";
"A":   PN = "1"  !CDS_PN = "1";
"B":   PN = "2"  !CDS_PN = "2";
BODY = "SCONN288_ADR50017P130CC","I175": LOCATION = "J19" #&CDS_LOCATION = "J19" &SEC = "3" #&CDS_SEC = "3";
"G1":   PN = "G1"  !CDS_PN = "G1";
"G2":   PN = "G2"  !CDS_PN = "G2";
"G3":   PN = "G3"  !CDS_PN = "G3";
"VIN_BULK0":   PN = "1"  !CDS_PN = "1";
"VIN_BULK1":   PN = "145"  !CDS_PN = "145";
"VIN_BULK2":   PN = "146"  !CDS_PN = "146";
"VSS0":   PN = "6"  !CDS_PN = "6";
"VSS1":   PN = "8"  !CDS_PN = "8";
"VSS2":   PN = "10"  !CDS_PN = "10";
"VSS3":   PN = "13"  !CDS_PN = "13";
"VSS4":   PN = "15"  !CDS_PN = "15";
"VSS5":   PN = "17"  !CDS_PN = "17";
"VSS6":   PN = "19"  !CDS_PN = "19";
"VSS7":   PN = "21"  !CDS_PN = "21";
"VSS8":   PN = "24"  !CDS_PN = "24";
"VSS9":   PN = "26"  !CDS_PN = "26";
"VSS10":   PN = "28"  !CDS_PN = "28";
"VSS11":   PN = "30"  !CDS_PN = "30";
"VSS12":   PN = "32"  !CDS_PN = "32";
"VSS13":   PN = "35"  !CDS_PN = "35";
"VSS14":   PN = "37"  !CDS_PN = "37";
"VSS15":   PN = "39"  !CDS_PN = "39";
"VSS16":   PN = "41"  !CDS_PN = "41";
"VSS17":   PN = "43"  !CDS_PN = "43";
"VSS18":   PN = "46"  !CDS_PN = "46";
"VSS19":   PN = "48"  !CDS_PN = "48";
"VSS20":   PN = "50"  !CDS_PN = "50";
"VSS21":   PN = "52"  !CDS_PN = "52";
"VSS22":   PN = "54"  !CDS_PN = "54";
"VSS23":   PN = "57"  !CDS_PN = "57";
"VSS24":   PN = "59"  !CDS_PN = "59";
"VSS25":   PN = "61"  !CDS_PN = "61";
"VSS26":   PN = "63"  !CDS_PN = "63";
"VSS27":   PN = "65"  !CDS_PN = "65";
"VSS28":   PN = "67"  !CDS_PN = "67";
"VSS29":   PN = "69"  !CDS_PN = "69";
"VSS30":   PN = "71"  !CDS_PN = "71";
"VSS31":   PN = "73"  !CDS_PN = "73";
"VSS32":   PN = "75"  !CDS_PN = "75";
"VSS33":   PN = "77"  !CDS_PN = "77";
"VSS34":   PN = "79"  !CDS_PN = "79";
"VSS35":   PN = "81"  !CDS_PN = "81";
"VSS36":   PN = "83"  !CDS_PN = "83";
"VSS37":   PN = "85"  !CDS_PN = "85";
"VSS38":   PN = "88"  !CDS_PN = "88";
"VSS39":   PN = "90"  !CDS_PN = "90";
"VSS40":   PN = "92"  !CDS_PN = "92";
"VSS41":   PN = "95"  !CDS_PN = "95";
"VSS42":   PN = "97"  !CDS_PN = "97";
"VSS43":   PN = "99"  !CDS_PN = "99";
"VSS44":   PN = "101"  !CDS_PN = "101";
"VSS45":   PN = "103"  !CDS_PN = "103";
"VSS46":   PN = "106"  !CDS_PN = "106";
"VSS47":   PN = "108"  !CDS_PN = "108";
"VSS48":   PN = "110"  !CDS_PN = "110";
"VSS49":   PN = "112"  !CDS_PN = "112";
"VSS50":   PN = "114"  !CDS_PN = "114";
"VSS51":   PN = "117"  !CDS_PN = "117";
"VSS52":   PN = "119"  !CDS_PN = "119";
"VSS53":   PN = "121"  !CDS_PN = "121";
"VSS54":   PN = "123"  !CDS_PN = "123";
"VSS55":   PN = "125"  !CDS_PN = "125";
"VSS56":   PN = "128"  !CDS_PN = "128";
"VSS57":   PN = "130"  !CDS_PN = "130";
"VSS58":   PN = "132"  !CDS_PN = "132";
"VSS59":   PN = "134"  !CDS_PN = "134";
"VSS60":   PN = "136"  !CDS_PN = "136";
"VSS61":   PN = "139"  !CDS_PN = "139";
"VSS62":   PN = "141"  !CDS_PN = "141";
"VSS63":   PN = "143"  !CDS_PN = "143";
"VSS64":   PN = "151"  !CDS_PN = "151";
"VSS65":   PN = "153"  !CDS_PN = "153";
"VSS66":   PN = "155"  !CDS_PN = "155";
"VSS67":   PN = "158"  !CDS_PN = "158";
"VSS68":   PN = "160"  !CDS_PN = "160";
"VSS69":   PN = "162"  !CDS_PN = "162";
"VSS70":   PN = "164"  !CDS_PN = "164";
"VSS71":   PN = "166"  !CDS_PN = "166";
"VSS72":   PN = "169"  !CDS_PN = "169";
"VSS73":   PN = "171"  !CDS_PN = "171";
"VSS74":   PN = "173"  !CDS_PN = "173";
"VSS75":   PN = "175"  !CDS_PN = "175";
"VSS76":   PN = "177"  !CDS_PN = "177";
"VSS77":   PN = "180"  !CDS_PN = "180";
"VSS78":   PN = "182"  !CDS_PN = "182";
"VSS79":   PN = "184"  !CDS_PN = "184";
"VSS80":   PN = "186"  !CDS_PN = "186";
"VSS81":   PN = "188"  !CDS_PN = "188";
"VSS82":   PN = "191"  !CDS_PN = "191";
"VSS83":   PN = "193"  !CDS_PN = "193";
"VSS84":   PN = "195"  !CDS_PN = "195";
"VSS85":   PN = "197"  !CDS_PN = "197";
"VSS86":   PN = "199"  !CDS_PN = "199";
"VSS87":   PN = "202"  !CDS_PN = "202";
"VSS88":   PN = "204"  !CDS_PN = "204";
"VSS89":   PN = "206"  !CDS_PN = "206";
"VSS90":   PN = "208"  !CDS_PN = "208";
"VSS91":   PN = "210"  !CDS_PN = "210";
"VSS92":   PN = "212"  !CDS_PN = "212";
"VSS93":   PN = "214"  !CDS_PN = "214";
"VSS94":   PN = "216"  !CDS_PN = "216";
"VSS95":   PN = "219"  !CDS_PN = "219";
"VSS96":   PN = "222"  !CDS_PN = "222";
"VSS97":   PN = "224"  !CDS_PN = "224";
"VSS98":   PN = "226"  !CDS_PN = "226";
"VSS99":   PN = "228"  !CDS_PN = "228";
"VSS100":   PN = "230"  !CDS_PN = "230";
"VSS101":   PN = "233"  !CDS_PN = "233";
"VSS102":   PN = "235"  !CDS_PN = "235";
"VSS103":   PN = "237"  !CDS_PN = "237";
"VSS104":   PN = "240"  !CDS_PN = "240";
"VSS105":   PN = "242"  !CDS_PN = "242";
"VSS106":   PN = "244"  !CDS_PN = "244";
"VSS107":   PN = "246"  !CDS_PN = "246";
"VSS108":   PN = "248"  !CDS_PN = "248";
"VSS109":   PN = "251"  !CDS_PN = "251";
"VSS110":   PN = "253"  !CDS_PN = "253";
"VSS111":   PN = "255"  !CDS_PN = "255";
"VSS112":   PN = "257"  !CDS_PN = "257";
"VSS113":   PN = "259"  !CDS_PN = "259";
"VSS114":   PN = "262"  !CDS_PN = "262";
"VSS115":   PN = "264"  !CDS_PN = "264";
"VSS116":   PN = "266"  !CDS_PN = "266";
"VSS117":   PN = "268"  !CDS_PN = "268";
"VSS118":   PN = "270"  !CDS_PN = "270";
"VSS119":   PN = "273"  !CDS_PN = "273";
"VSS120":   PN = "275"  !CDS_PN = "275";
"VSS121":   PN = "277"  !CDS_PN = "277";
"VSS122":   PN = "279"  !CDS_PN = "279";
"VSS123":   PN = "281"  !CDS_PN = "281";
"VSS124":   PN = "284"  !CDS_PN = "284";
"VSS125":   PN = "286"  !CDS_PN = "286";
"VSS126":   PN = "288"  !CDS_PN = "288";
BODY = "SCONN288_ADR50017P130CC","I178": #LOCATION = "J19" !CDS_LOCATION = "J19" &SEC = "2" #&CDS_SEC = "2";
"DQS0_A_C":   PN = "12"  !CDS_PN = "12";
"DQS0_A_T":   PN = "11"  !CDS_PN = "11";
"DQS0_B_C":   PN = "105"  !CDS_PN = "105";
"DQS0_B_T":   PN = "104"  !CDS_PN = "104";
"DQS1_A_C":   PN = "23"  !CDS_PN = "23";
"DQS1_A_T":   PN = "22"  !CDS_PN = "22";
"DQS1_B_C":   PN = "116"  !CDS_PN = "116";
"DQS1_B_T":   PN = "115"  !CDS_PN = "115";
"DQS2_A_C":   PN = "34"  !CDS_PN = "34";
"DQS2_A_T":   PN = "33"  !CDS_PN = "33";
"DQS2_B_C":   PN = "127"  !CDS_PN = "127";
"DQS2_B_T":   PN = "126"  !CDS_PN = "126";
"DQS3_A_C":   PN = "45"  !CDS_PN = "45";
"DQS3_A_T":   PN = "44"  !CDS_PN = "44";
"DQS3_B_C":   PN = "138"  !CDS_PN = "138";
"DQS3_B_T":   PN = "137"  !CDS_PN = "137";
"DQS4_A_C":   PN = "56"  !CDS_PN = "56";
"DQS4_A_T":   PN = "55"  !CDS_PN = "55";
"DQS4_B_C":   PN = "238"  !CDS_PN = "238";
"DQS4_B_T":   PN = "239"  !CDS_PN = "239";
"DQS5_A_C||TDQS5_A_C||DQS5_A_T||TDQS5_A_T":   PN = "156"  !CDS_PN = "156";
"DQS5_A_T||TDQS5_A_T":   PN = "157"  !CDS_PN = "157";
"DQS5_B_C||TDQS5_B_C":   PN = "249"  !CDS_PN = "249";
"DQS5_B_T||TDQS5_B_T":   PN = "250"  !CDS_PN = "250";
"DQS6_A_C||TDQS6_A_C||DQS6_A_T||TDQS6_A_T":   PN = "167"  !CDS_PN = "167";
"DQS6_A_T||TDQS6_A_T":   PN = "168"  !CDS_PN = "168";
"DQS6_B_C||TDQS6_B_C":   PN = "260"  !CDS_PN = "260";
"DQS6_B_T||TDQS6_B_T":   PN = "261"  !CDS_PN = "261";
"DQS7_A_C||TDQS7_A_C":   PN = "178"  !CDS_PN = "178";
"DQS7_A_T||TDQS7_A_T":   PN = "179"  !CDS_PN = "179";
"DQS7_B_C||TDQS7_B_C":   PN = "271"  !CDS_PN = "271";
"DQS7_B_T||TDQS7_B_T":   PN = "272"  !CDS_PN = "272";
"DQS8_A_C||TDQS8_A_C":   PN = "189"  !CDS_PN = "189";
"DQS8_A_T||TDQS8_A_T":   PN = "190"  !CDS_PN = "190";
"DQS8_B_C||TDQS8_B_C":   PN = "282"  !CDS_PN = "282";
"DQS8_B_T||TDQS8_B_T":   PN = "283"  !CDS_PN = "283";
"DQS9_A_C||TDQS9_A_C":   PN = "200"  !CDS_PN = "200";
"DQS9_A_T||TDQS9_A_T":   PN = "201"  !CDS_PN = "201";
"DQS9_B_C||TDQS9_B_C":   PN = "94"  !CDS_PN = "94";
"DQS9_B_T||TDQS9_B_T||DBI4_B_N":   PN = "93"  !CDS_PN = "93";
BODY = "Q_RES","I180": LOCATION = "R3893" #&CDS_LOCATION = "R3893" &SEC = "1" #&CDS_SEC = "1";
"A":   PN = "1"  !CDS_PN = "1";
"B":   PN = "2"  !CDS_PN = "2";
DRAWING = "@s9s_mb_2u_lib.s9s_mb_2u(sch_1):page101";
BODY = "Q_RES","I46": LOCATION = "R45" #&CDS_LOCATION = "R45" &SEC = "1" #&CDS_SEC = "1";
"A":   PN = "1"  !CDS_PN = "1";
"B":   PN = "2"  !CDS_PN = "2";
BODY = "SCONN288_ADR50017P087CC","I47": LOCATION = "J20" #&CDS_LOCATION = "J20" &SEC = "1" #&CDS_SEC = "1";
"ALERT_N":   PN = "62"  !CDS_PN = "62";
"CA0_A":   PN = "66"  !CDS_PN = "66";
"CA0_B":   PN = "76"  !CDS_PN = "76";
"CA1_A":   PN = "211"  !CDS_PN = "211";
"CA1_B":   PN = "221"  !CDS_PN = "221";
"CA2_A":   PN = "68"  !CDS_PN = "68";
"CA2_B":   PN = "78"  !CDS_PN = "78";
"CA3_A":   PN = "213"  !CDS_PN = "213";
"CA3_B":   PN = "223"  !CDS_PN = "223";
"CA4_A":   PN = "70"  !CDS_PN = "70";
"CA4_B":   PN = "80"  !CDS_PN = "80";
"CA5_A":   PN = "215"  !CDS_PN = "215";
"CA5_B":   PN = "225"  !CDS_PN = "225";
"CA6_A":   PN = "72"  !CDS_PN = "72";
"CA6_B":   PN = "82"  !CDS_PN = "82";
"CB0_A":   PN = "51"  !CDS_PN = "51";
"CB0_B":   PN = "96"  !CDS_PN = "96";
"CB1_A":   PN = "53"  !CDS_PN = "53";
"CB1_B":   PN = "98"  !CDS_PN = "98";
"CB2_A":   PN = "196"  !CDS_PN = "196";
"CB2_B":   PN = "241"  !CDS_PN = "241";
"CB3_A":   PN = "198"  !CDS_PN = "198";
"CB3_B":   PN = "243"  !CDS_PN = "243";
"CB4_A":   PN = "58"  !CDS_PN = "58";
"CB4_B":   PN = "89"  !CDS_PN = "89";
"CB5_A":   PN = "60"  !CDS_PN = "60";
"CB5_B":   PN = "91"  !CDS_PN = "91";
"CB6_A":   PN = "203"  !CDS_PN = "203";
"CB6_B":   PN = "234"  !CDS_PN = "234";
"CB7_A":   PN = "205"  !CDS_PN = "205";
"CB7_B":   PN = "236"  !CDS_PN = "236";
"CK_C":   PN = "218"  !CDS_PN = "218";
"CK_T":   PN = "217"  !CDS_PN = "217";
"CS0_A_N":   PN = "64"  !CDS_PN = "64";
"CS0_B_N":   PN = "84"  !CDS_PN = "84";
"CS1_A_N":   PN = "209"  !CDS_PN = "209";
"CS1_B_N":   PN = "229"  !CDS_PN = "229";
"DQ0_A":   PN = "7"  !CDS_PN = "7";
"DQ0_B":   PN = "100"  !CDS_PN = "100";
"DQ1_A":   PN = "9"  !CDS_PN = "9";
"DQ1_B":   PN = "102"  !CDS_PN = "102";
"DQ2_A":   PN = "152"  !CDS_PN = "152";
"DQ2_B":   PN = "245"  !CDS_PN = "245";
"DQ3_A":   PN = "154"  !CDS_PN = "154";
"DQ3_B":   PN = "247"  !CDS_PN = "247";
"DQ4_A":   PN = "14"  !CDS_PN = "14";
"DQ4_B":   PN = "107"  !CDS_PN = "107";
"DQ5_A":   PN = "16"  !CDS_PN = "16";
"DQ5_B":   PN = "109"  !CDS_PN = "109";
"DQ6_A":   PN = "159"  !CDS_PN = "159";
"DQ6_B":   PN = "252"  !CDS_PN = "252";
"DQ7_A":   PN = "161"  !CDS_PN = "161";
"DQ7_B":   PN = "254"  !CDS_PN = "254";
"DQ8_A":   PN = "18"  !CDS_PN = "18";
"DQ8_B":   PN = "111"  !CDS_PN = "111";
"DQ9_A":   PN = "20"  !CDS_PN = "20";
"DQ9_B":   PN = "113"  !CDS_PN = "113";
"DQ10_A":   PN = "163"  !CDS_PN = "163";
"DQ10_B":   PN = "256"  !CDS_PN = "256";
"DQ11_A":   PN = "165"  !CDS_PN = "165";
"DQ11_B":   PN = "258"  !CDS_PN = "258";
"DQ12_A":   PN = "25"  !CDS_PN = "25";
"DQ12_B":   PN = "118"  !CDS_PN = "118";
"DQ13_A":   PN = "27"  !CDS_PN = "27";
"DQ13_B":   PN = "120"  !CDS_PN = "120";
"DQ14_A":   PN = "170"  !CDS_PN = "170";
"DQ14_B":   PN = "263"  !CDS_PN = "263";
"DQ15_A":   PN = "172"  !CDS_PN = "172";
"DQ15_B":   PN = "265"  !CDS_PN = "265";
"DQ16_A":   PN = "29"  !CDS_PN = "29";
"DQ16_B":   PN = "122"  !CDS_PN = "122";
"DQ17_A":   PN = "31"  !CDS_PN = "31";
"DQ17_B":   PN = "124"  !CDS_PN = "124";
"DQ18_A":   PN = "174"  !CDS_PN = "174";
"DQ18_B":   PN = "267"  !CDS_PN = "267";
"DQ19_A":   PN = "176"  !CDS_PN = "176";
"DQ19_B":   PN = "269"  !CDS_PN = "269";
"DQ20_A":   PN = "36"  !CDS_PN = "36";
"DQ20_B":   PN = "129"  !CDS_PN = "129";
"DQ21_A":   PN = "38"  !CDS_PN = "38";
"DQ21_B":   PN = "131"  !CDS_PN = "131";
"DQ22_A":   PN = "181"  !CDS_PN = "181";
"DQ22_B":   PN = "274"  !CDS_PN = "274";
"DQ23_A":   PN = "183"  !CDS_PN = "183";
"DQ23_B":   PN = "276"  !CDS_PN = "276";
"DQ24_A":   PN = "40"  !CDS_PN = "40";
"DQ24_B":   PN = "133"  !CDS_PN = "133";
"DQ25_A":   PN = "42"  !CDS_PN = "42";
"DQ25_B":   PN = "135"  !CDS_PN = "135";
"DQ26_A":   PN = "185"  !CDS_PN = "185";
"DQ26_B":   PN = "278"  !CDS_PN = "278";
"DQ27_A":   PN = "187"  !CDS_PN = "187";
"DQ27_B":   PN = "280"  !CDS_PN = "280";
"DQ28_A":   PN = "47"  !CDS_PN = "47";
"DQ28_B":   PN = "140"  !CDS_PN = "140";
"DQ29_A":   PN = "49"  !CDS_PN = "49";
"DQ29_B":   PN = "142"  !CDS_PN = "142";
"DQ30_A":   PN = "192"  !CDS_PN = "192";
"DQ30_B":   PN = "285"  !CDS_PN = "285";
"DQ31_A":   PN = "194"  !CDS_PN = "194";
"DQ31_B":   PN = "287"  !CDS_PN = "287";
"HSA":   PN = "148"  !CDS_PN = "148";
"HSCL":   PN = "4"  !CDS_PN = "4";
"HSDA":   PN = "5"  !CDS_PN = "5";
"LBD||RSP_A_N":   PN = "86"  !CDS_PN = "86";
"LBS||RSP_B_N":   PN = "87"  !CDS_PN = "87";
"PAR_A":   PN = "74"  !CDS_PN = "74";
"PAR_B":   PN = "227"  !CDS_PN = "227";
"PWR_GOOD||FAIL_N":   PN = "147"  !CDS_PN = "147";
"RESET_N":   PN = "207"  !CDS_PN = "207";
"RFU0":   PN = "2"  !CDS_PN = "2";
"RFU1":   PN = "144"  !CDS_PN = "144";
"RFU2":   PN = "149"  !CDS_PN = "149";
"RFU3":   PN = "150"  !CDS_PN = "150";
"RFU4":   PN = "220"  !CDS_PN = "220";
"RFU5":   PN = "231"  !CDS_PN = "231";
"RFU6":   PN = "232"  !CDS_PN = "232";
"VIN_MGMT":   PN = "3"  !CDS_PN = "3";
BODY = "Q_CAP","I121": LOCATION = "C59" #&CDS_LOCATION = "C59" &SEC = "1" #&CDS_SEC = "1";
"A":   PN = "1"  !CDS_PN = "1";
"B":   PN = "2"  !CDS_PN = "2";
BODY = "Q_CAP","I125": LOCATION = "C60" #&CDS_LOCATION = "C60" &SEC = "1" #&CDS_SEC = "1";
"A":   PN = "1"  !CDS_PN = "1";
"B":   PN = "2"  !CDS_PN = "2";
BODY = "Q_CAP","I127": LOCATION = "C61" #&CDS_LOCATION = "C61" &SEC = "1" #&CDS_SEC = "1";
"A":   PN = "1"  !CDS_PN = "1";
"B":   PN = "2"  !CDS_PN = "2";
BODY = "SCONN288_ADR50017P087CC","I176": LOCATION = "J20" #&CDS_LOCATION = "J20" &SEC = "3" #&CDS_SEC = "3";
"G1":   PN = "G1"  !CDS_PN = "G1";
"G2":   PN = "G2"  !CDS_PN = "G2";
"G3":   PN = "G3"  !CDS_PN = "G3";
"VIN_BULK0":   PN = "1"  !CDS_PN = "1";
"VIN_BULK1":   PN = "145"  !CDS_PN = "145";
"VIN_BULK2":   PN = "146"  !CDS_PN = "146";
"VSS0":   PN = "6"  !CDS_PN = "6";
"VSS1":   PN = "8"  !CDS_PN = "8";
"VSS2":   PN = "10"  !CDS_PN = "10";
"VSS3":   PN = "13"  !CDS_PN = "13";
"VSS4":   PN = "15"  !CDS_PN = "15";
"VSS5":   PN = "17"  !CDS_PN = "17";
"VSS6":   PN = "19"  !CDS_PN = "19";
"VSS7":   PN = "21"  !CDS_PN = "21";
"VSS8":   PN = "24"  !CDS_PN = "24";
"VSS9":   PN = "26"  !CDS_PN = "26";
"VSS10":   PN = "28"  !CDS_PN = "28";
"VSS11":   PN = "30"  !CDS_PN = "30";
"VSS12":   PN = "32"  !CDS_PN = "32";
"VSS13":   PN = "35"  !CDS_PN = "35";
"VSS14":   PN = "37"  !CDS_PN = "37";
"VSS15":   PN = "39"  !CDS_PN = "39";
"VSS16":   PN = "41"  !CDS_PN = "41";
"VSS17":   PN = "43"  !CDS_PN = "43";
"VSS18":   PN = "46"  !CDS_PN = "46";
"VSS19":   PN = "48"  !CDS_PN = "48";
"VSS20":   PN = "50"  !CDS_PN = "50";
"VSS21":   PN = "52"  !CDS_PN = "52";
"VSS22":   PN = "54"  !CDS_PN = "54";
"VSS23":   PN = "57"  !CDS_PN = "57";
"VSS24":   PN = "59"  !CDS_PN = "59";
"VSS25":   PN = "61"  !CDS_PN = "61";
"VSS26":   PN = "63"  !CDS_PN = "63";
"VSS27":   PN = "65"  !CDS_PN = "65";
"VSS28":   PN = "67"  !CDS_PN = "67";
"VSS29":   PN = "69"  !CDS_PN = "69";
"VSS30":   PN = "71"  !CDS_PN = "71";
"VSS31":   PN = "73"  !CDS_PN = "73";
"VSS32":   PN = "75"  !CDS_PN = "75";
"VSS33":   PN = "77"  !CDS_PN = "77";
"VSS34":   PN = "79"  !CDS_PN = "79";
"VSS35":   PN = "81"  !CDS_PN = "81";
"VSS36":   PN = "83"  !CDS_PN = "83";
"VSS37":   PN = "85"  !CDS_PN = "85";
"VSS38":   PN = "88"  !CDS_PN = "88";
"VSS39":   PN = "90"  !CDS_PN = "90";
"VSS40":   PN = "92"  !CDS_PN = "92";
"VSS41":   PN = "95"  !CDS_PN = "95";
"VSS42":   PN = "97"  !CDS_PN = "97";
"VSS43":   PN = "99"  !CDS_PN = "99";
"VSS44":   PN = "101"  !CDS_PN = "101";
"VSS45":   PN = "103"  !CDS_PN = "103";
"VSS46":   PN = "106"  !CDS_PN = "106";
"VSS47":   PN = "108"  !CDS_PN = "108";
"VSS48":   PN = "110"  !CDS_PN = "110";
"VSS49":   PN = "112"  !CDS_PN = "112";
"VSS50":   PN = "114"  !CDS_PN = "114";
"VSS51":   PN = "117"  !CDS_PN = "117";
"VSS52":   PN = "119"  !CDS_PN = "119";
"VSS53":   PN = "121"  !CDS_PN = "121";
"VSS54":   PN = "123"  !CDS_PN = "123";
"VSS55":   PN = "125"  !CDS_PN = "125";
"VSS56":   PN = "128"  !CDS_PN = "128";
"VSS57":   PN = "130"  !CDS_PN = "130";
"VSS58":   PN = "132"  !CDS_PN = "132";
"VSS59":   PN = "134"  !CDS_PN = "134";
"VSS60":   PN = "136"  !CDS_PN = "136";
"VSS61":   PN = "139"  !CDS_PN = "139";
"VSS62":   PN = "141"  !CDS_PN = "141";
"VSS63":   PN = "143"  !CDS_PN = "143";
"VSS64":   PN = "151"  !CDS_PN = "151";
"VSS65":   PN = "153"  !CDS_PN = "153";
"VSS66":   PN = "155"  !CDS_PN = "155";
"VSS67":   PN = "158"  !CDS_PN = "158";
"VSS68":   PN = "160"  !CDS_PN = "160";
"VSS69":   PN = "162"  !CDS_PN = "162";
"VSS70":   PN = "164"  !CDS_PN = "164";
"VSS71":   PN = "166"  !CDS_PN = "166";
"VSS72":   PN = "169"  !CDS_PN = "169";
"VSS73":   PN = "171"  !CDS_PN = "171";
"VSS74":   PN = "173"  !CDS_PN = "173";
"VSS75":   PN = "175"  !CDS_PN = "175";
"VSS76":   PN = "177"  !CDS_PN = "177";
"VSS77":   PN = "180"  !CDS_PN = "180";
"VSS78":   PN = "182"  !CDS_PN = "182";
"VSS79":   PN = "184"  !CDS_PN = "184";
"VSS80":   PN = "186"  !CDS_PN = "186";
"VSS81":   PN = "188"  !CDS_PN = "188";
"VSS82":   PN = "191"  !CDS_PN = "191";
"VSS83":   PN = "193"  !CDS_PN = "193";
"VSS84":   PN = "195"  !CDS_PN = "195";
"VSS85":   PN = "197"  !CDS_PN = "197";
"VSS86":   PN = "199"  !CDS_PN = "199";
"VSS87":   PN = "202"  !CDS_PN = "202";
"VSS88":   PN = "204"  !CDS_PN = "204";
"VSS89":   PN = "206"  !CDS_PN = "206";
"VSS90":   PN = "208"  !CDS_PN = "208";
"VSS91":   PN = "210"  !CDS_PN = "210";
"VSS92":   PN = "212"  !CDS_PN = "212";
"VSS93":   PN = "214"  !CDS_PN = "214";
"VSS94":   PN = "216"  !CDS_PN = "216";
"VSS95":   PN = "219"  !CDS_PN = "219";
"VSS96":   PN = "222"  !CDS_PN = "222";
"VSS97":   PN = "224"  !CDS_PN = "224";
"VSS98":   PN = "226"  !CDS_PN = "226";
"VSS99":   PN = "228"  !CDS_PN = "228";
"VSS100":   PN = "230"  !CDS_PN = "230";
"VSS101":   PN = "233"  !CDS_PN = "233";
"VSS102":   PN = "235"  !CDS_PN = "235";
"VSS103":   PN = "237"  !CDS_PN = "237";
"VSS104":   PN = "240"  !CDS_PN = "240";
"VSS105":   PN = "242"  !CDS_PN = "242";
"VSS106":   PN = "244"  !CDS_PN = "244";
"VSS107":   PN = "246"  !CDS_PN = "246";
"VSS108":   PN = "248"  !CDS_PN = "248";
"VSS109":   PN = "251"  !CDS_PN = "251";
"VSS110":   PN = "253"  !CDS_PN = "253";
"VSS111":   PN = "255"  !CDS_PN = "255";
"VSS112":   PN = "257"  !CDS_PN = "257";
"VSS113":   PN = "259"  !CDS_PN = "259";
"VSS114":   PN = "262"  !CDS_PN = "262";
"VSS115":   PN = "264"  !CDS_PN = "264";
"VSS116":   PN = "266"  !CDS_PN = "266";
"VSS117":   PN = "268"  !CDS_PN = "268";
"VSS118":   PN = "270"  !CDS_PN = "270";
"VSS119":   PN = "273"  !CDS_PN = "273";
"VSS120":   PN = "275"  !CDS_PN = "275";
"VSS121":   PN = "277"  !CDS_PN = "277";
"VSS122":   PN = "279"  !CDS_PN = "279";
"VSS123":   PN = "281"  !CDS_PN = "281";
"VSS124":   PN = "284"  !CDS_PN = "284";
"VSS125":   PN = "286"  !CDS_PN = "286";
"VSS126":   PN = "288"  !CDS_PN = "288";
BODY = "SCONN288_ADR50017P087CC","I178": #LOCATION = "J20" !CDS_LOCATION = "J20" &SEC = "2" #&CDS_SEC = "2";
"DQS0_A_C":   PN = "12"  !CDS_PN = "12";
"DQS0_A_T":   PN = "11"  !CDS_PN = "11";
"DQS0_B_C":   PN = "105"  !CDS_PN = "105";
"DQS0_B_T":   PN = "104"  !CDS_PN = "104";
"DQS1_A_C":   PN = "23"  !CDS_PN = "23";
"DQS1_A_T":   PN = "22"  !CDS_PN = "22";
"DQS1_B_C":   PN = "116"  !CDS_PN = "116";
"DQS1_B_T":   PN = "115"  !CDS_PN = "115";
"DQS2_A_C":   PN = "34"  !CDS_PN = "34";
"DQS2_A_T":   PN = "33"  !CDS_PN = "33";
"DQS2_B_C":   PN = "127"  !CDS_PN = "127";
"DQS2_B_T":   PN = "126"  !CDS_PN = "126";
"DQS3_A_C":   PN = "45"  !CDS_PN = "45";
"DQS3_A_T":   PN = "44"  !CDS_PN = "44";
"DQS3_B_C":   PN = "138"  !CDS_PN = "138";
"DQS3_B_T":   PN = "137"  !CDS_PN = "137";
"DQS4_A_C":   PN = "56"  !CDS_PN = "56";
"DQS4_A_T":   PN = "55"  !CDS_PN = "55";
"DQS4_B_C":   PN = "238"  !CDS_PN = "238";
"DQS4_B_T":   PN = "239"  !CDS_PN = "239";
"DQS5_A_C||TDQS5_A_C||DQS5_A_T||TDQS5_A_T":   PN = "156"  !CDS_PN = "156";
"DQS5_A_T||TDQS5_A_T":   PN = "157"  !CDS_PN = "157";
"DQS5_B_C||TDQS5_B_C":   PN = "249"  !CDS_PN = "249";
"DQS5_B_T||TDQS5_B_T":   PN = "250"  !CDS_PN = "250";
"DQS6_A_C||TDQS6_A_C||DQS6_A_T||TDQS6_A_T":   PN = "167"  !CDS_PN = "167";
"DQS6_A_T||TDQS6_A_T":   PN = "168"  !CDS_PN = "168";
"DQS6_B_C||TDQS6_B_C":   PN = "260"  !CDS_PN = "260";
"DQS6_B_T||TDQS6_B_T":   PN = "261"  !CDS_PN = "261";
"DQS7_A_C||TDQS7_A_C":   PN = "178"  !CDS_PN = "178";
"DQS7_A_T||TDQS7_A_T":   PN = "179"  !CDS_PN = "179";
"DQS7_B_C||TDQS7_B_C":   PN = "271"  !CDS_PN = "271";
"DQS7_B_T||TDQS7_B_T":   PN = "272"  !CDS_PN = "272";
"DQS8_A_C||TDQS8_A_C":   PN = "189"  !CDS_PN = "189";
"DQS8_A_T||TDQS8_A_T":   PN = "190"  !CDS_PN = "190";
"DQS8_B_C||TDQS8_B_C":   PN = "282"  !CDS_PN = "282";
"DQS8_B_T||TDQS8_B_T":   PN = "283"  !CDS_PN = "283";
"DQS9_A_C||TDQS9_A_C":   PN = "200"  !CDS_PN = "200";
"DQS9_A_T||TDQS9_A_T":   PN = "201"  !CDS_PN = "201";
"DQS9_B_C||TDQS9_B_C":   PN = "94"  !CDS_PN = "94";
"DQS9_B_T||TDQS9_B_T||DBI4_B_N":   PN = "93"  !CDS_PN = "93";
BODY = "Q_RES","I180": LOCATION = "R3894" #&CDS_LOCATION = "R3894" &SEC = "1" #&CDS_SEC = "1";
"A":   PN = "1"  !CDS_PN = "1";
"B":   PN = "2"  !CDS_PN = "2";
DRAWING = "@s9s_mb_2u_lib.s9s_mb_2u(sch_1):page102";
BODY = "Q_RES","I2": LOCATION = "R46" #&CDS_LOCATION = "R46" &SEC = "1" #&CDS_SEC = "1";
"A":   PN = "1"  !CDS_PN = "1";
"B":   PN = "2"  !CDS_PN = "2";
BODY = "SCONN288_ADR50017P130CC","I13": LOCATION = "J21" #&CDS_LOCATION = "J21" &SEC = "1" #&CDS_SEC = "1";
"ALERT_N":   PN = "62"  !CDS_PN = "62";
"CA0_A":   PN = "66"  !CDS_PN = "66";
"CA0_B":   PN = "76"  !CDS_PN = "76";
"CA1_A":   PN = "211"  !CDS_PN = "211";
"CA1_B":   PN = "221"  !CDS_PN = "221";
"CA2_A":   PN = "68"  !CDS_PN = "68";
"CA2_B":   PN = "78"  !CDS_PN = "78";
"CA3_A":   PN = "213"  !CDS_PN = "213";
"CA3_B":   PN = "223"  !CDS_PN = "223";
"CA4_A":   PN = "70"  !CDS_PN = "70";
"CA4_B":   PN = "80"  !CDS_PN = "80";
"CA5_A":   PN = "215"  !CDS_PN = "215";
"CA5_B":   PN = "225"  !CDS_PN = "225";
"CA6_A":   PN = "72"  !CDS_PN = "72";
"CA6_B":   PN = "82"  !CDS_PN = "82";
"CB0_A":   PN = "51"  !CDS_PN = "51";
"CB0_B":   PN = "96"  !CDS_PN = "96";
"CB1_A":   PN = "53"  !CDS_PN = "53";
"CB1_B":   PN = "98"  !CDS_PN = "98";
"CB2_A":   PN = "196"  !CDS_PN = "196";
"CB2_B":   PN = "241"  !CDS_PN = "241";
"CB3_A":   PN = "198"  !CDS_PN = "198";
"CB3_B":   PN = "243"  !CDS_PN = "243";
"CB4_A":   PN = "58"  !CDS_PN = "58";
"CB4_B":   PN = "89"  !CDS_PN = "89";
"CB5_A":   PN = "60"  !CDS_PN = "60";
"CB5_B":   PN = "91"  !CDS_PN = "91";
"CB6_A":   PN = "203"  !CDS_PN = "203";
"CB6_B":   PN = "234"  !CDS_PN = "234";
"CB7_A":   PN = "205"  !CDS_PN = "205";
"CB7_B":   PN = "236"  !CDS_PN = "236";
"CK_C":   PN = "218"  !CDS_PN = "218";
"CK_T":   PN = "217"  !CDS_PN = "217";
"CS0_A_N":   PN = "64"  !CDS_PN = "64";
"CS0_B_N":   PN = "84"  !CDS_PN = "84";
"CS1_A_N":   PN = "209"  !CDS_PN = "209";
"CS1_B_N":   PN = "229"  !CDS_PN = "229";
"DQ0_A":   PN = "7"  !CDS_PN = "7";
"DQ0_B":   PN = "100"  !CDS_PN = "100";
"DQ1_A":   PN = "9"  !CDS_PN = "9";
"DQ1_B":   PN = "102"  !CDS_PN = "102";
"DQ2_A":   PN = "152"  !CDS_PN = "152";
"DQ2_B":   PN = "245"  !CDS_PN = "245";
"DQ3_A":   PN = "154"  !CDS_PN = "154";
"DQ3_B":   PN = "247"  !CDS_PN = "247";
"DQ4_A":   PN = "14"  !CDS_PN = "14";
"DQ4_B":   PN = "107"  !CDS_PN = "107";
"DQ5_A":   PN = "16"  !CDS_PN = "16";
"DQ5_B":   PN = "109"  !CDS_PN = "109";
"DQ6_A":   PN = "159"  !CDS_PN = "159";
"DQ6_B":   PN = "252"  !CDS_PN = "252";
"DQ7_A":   PN = "161"  !CDS_PN = "161";
"DQ7_B":   PN = "254"  !CDS_PN = "254";
"DQ8_A":   PN = "18"  !CDS_PN = "18";
"DQ8_B":   PN = "111"  !CDS_PN = "111";
"DQ9_A":   PN = "20"  !CDS_PN = "20";
"DQ9_B":   PN = "113"  !CDS_PN = "113";
"DQ10_A":   PN = "163"  !CDS_PN = "163";
"DQ10_B":   PN = "256"  !CDS_PN = "256";
"DQ11_A":   PN = "165"  !CDS_PN = "165";
"DQ11_B":   PN = "258"  !CDS_PN = "258";
"DQ12_A":   PN = "25"  !CDS_PN = "25";
"DQ12_B":   PN = "118"  !CDS_PN = "118";
"DQ13_A":   PN = "27"  !CDS_PN = "27";
"DQ13_B":   PN = "120"  !CDS_PN = "120";
"DQ14_A":   PN = "170"  !CDS_PN = "170";
"DQ14_B":   PN = "263"  !CDS_PN = "263";
"DQ15_A":   PN = "172"  !CDS_PN = "172";
"DQ15_B":   PN = "265"  !CDS_PN = "265";
"DQ16_A":   PN = "29"  !CDS_PN = "29";
"DQ16_B":   PN = "122"  !CDS_PN = "122";
"DQ17_A":   PN = "31"  !CDS_PN = "31";
"DQ17_B":   PN = "124"  !CDS_PN = "124";
"DQ18_A":   PN = "174"  !CDS_PN = "174";
"DQ18_B":   PN = "267"  !CDS_PN = "267";
"DQ19_A":   PN = "176"  !CDS_PN = "176";
"DQ19_B":   PN = "269"  !CDS_PN = "269";
"DQ20_A":   PN = "36"  !CDS_PN = "36";
"DQ20_B":   PN = "129"  !CDS_PN = "129";
"DQ21_A":   PN = "38"  !CDS_PN = "38";
"DQ21_B":   PN = "131"  !CDS_PN = "131";
"DQ22_A":   PN = "181"  !CDS_PN = "181";
"DQ22_B":   PN = "274"  !CDS_PN = "274";
"DQ23_A":   PN = "183"  !CDS_PN = "183";
"DQ23_B":   PN = "276"  !CDS_PN = "276";
"DQ24_A":   PN = "40"  !CDS_PN = "40";
"DQ24_B":   PN = "133"  !CDS_PN = "133";
"DQ25_A":   PN = "42"  !CDS_PN = "42";
"DQ25_B":   PN = "135"  !CDS_PN = "135";
"DQ26_A":   PN = "185"  !CDS_PN = "185";
"DQ26_B":   PN = "278"  !CDS_PN = "278";
"DQ27_A":   PN = "187"  !CDS_PN = "187";
"DQ27_B":   PN = "280"  !CDS_PN = "280";
"DQ28_A":   PN = "47"  !CDS_PN = "47";
"DQ28_B":   PN = "140"  !CDS_PN = "140";
"DQ29_A":   PN = "49"  !CDS_PN = "49";
"DQ29_B":   PN = "142"  !CDS_PN = "142";
"DQ30_A":   PN = "192"  !CDS_PN = "192";
"DQ30_B":   PN = "285"  !CDS_PN = "285";
"DQ31_A":   PN = "194"  !CDS_PN = "194";
"DQ31_B":   PN = "287"  !CDS_PN = "287";
"HSA":   PN = "148"  !CDS_PN = "148";
"HSCL":   PN = "4"  !CDS_PN = "4";
"HSDA":   PN = "5"  !CDS_PN = "5";
"LBD||RSP_A_N":   PN = "86"  !CDS_PN = "86";
"LBS||RSP_B_N":   PN = "87"  !CDS_PN = "87";
"PAR_A":   PN = "74"  !CDS_PN = "74";
"PAR_B":   PN = "227"  !CDS_PN = "227";
"PWR_GOOD||FAIL_N":   PN = "147"  !CDS_PN = "147";
"RESET_N":   PN = "207"  !CDS_PN = "207";
"RFU0":   PN = "2"  !CDS_PN = "2";
"RFU1":   PN = "144"  !CDS_PN = "144";
"RFU2":   PN = "149"  !CDS_PN = "149";
"RFU3":   PN = "150"  !CDS_PN = "150";
"RFU4":   PN = "220"  !CDS_PN = "220";
"RFU5":   PN = "231"  !CDS_PN = "231";
"RFU6":   PN = "232"  !CDS_PN = "232";
"VIN_MGMT":   PN = "3"  !CDS_PN = "3";
BODY = "Q_CAP","I124": LOCATION = "C62" #&CDS_LOCATION = "C62" &SEC = "1" #&CDS_SEC = "1";
"A":   PN = "1"  !CDS_PN = "1";
"B":   PN = "2"  !CDS_PN = "2";
BODY = "Q_CAP","I127": LOCATION = "C63" #&CDS_LOCATION = "C63" &SEC = "1" #&CDS_SEC = "1";
"A":   PN = "1"  !CDS_PN = "1";
"B":   PN = "2"  !CDS_PN = "2";
BODY = "Q_CAP","I167": LOCATION = "C64" #&CDS_LOCATION = "C64" &SEC = "1" #&CDS_SEC = "1";
"A":   PN = "1"  !CDS_PN = "1";
"B":   PN = "2"  !CDS_PN = "2";
BODY = "SCONN288_ADR50017P130CC","I169": LOCATION = "J21" #&CDS_LOCATION = "J21" &SEC = "3" #&CDS_SEC = "3";
"G1":   PN = "G1"  !CDS_PN = "G1";
"G2":   PN = "G2"  !CDS_PN = "G2";
"G3":   PN = "G3"  !CDS_PN = "G3";
"VIN_BULK0":   PN = "1"  !CDS_PN = "1";
"VIN_BULK1":   PN = "145"  !CDS_PN = "145";
"VIN_BULK2":   PN = "146"  !CDS_PN = "146";
"VSS0":   PN = "6"  !CDS_PN = "6";
"VSS1":   PN = "8"  !CDS_PN = "8";
"VSS2":   PN = "10"  !CDS_PN = "10";
"VSS3":   PN = "13"  !CDS_PN = "13";
"VSS4":   PN = "15"  !CDS_PN = "15";
"VSS5":   PN = "17"  !CDS_PN = "17";
"VSS6":   PN = "19"  !CDS_PN = "19";
"VSS7":   PN = "21"  !CDS_PN = "21";
"VSS8":   PN = "24"  !CDS_PN = "24";
"VSS9":   PN = "26"  !CDS_PN = "26";
"VSS10":   PN = "28"  !CDS_PN = "28";
"VSS11":   PN = "30"  !CDS_PN = "30";
"VSS12":   PN = "32"  !CDS_PN = "32";
"VSS13":   PN = "35"  !CDS_PN = "35";
"VSS14":   PN = "37"  !CDS_PN = "37";
"VSS15":   PN = "39"  !CDS_PN = "39";
"VSS16":   PN = "41"  !CDS_PN = "41";
"VSS17":   PN = "43"  !CDS_PN = "43";
"VSS18":   PN = "46"  !CDS_PN = "46";
"VSS19":   PN = "48"  !CDS_PN = "48";
"VSS20":   PN = "50"  !CDS_PN = "50";
"VSS21":   PN = "52"  !CDS_PN = "52";
"VSS22":   PN = "54"  !CDS_PN = "54";
"VSS23":   PN = "57"  !CDS_PN = "57";
"VSS24":   PN = "59"  !CDS_PN = "59";
"VSS25":   PN = "61"  !CDS_PN = "61";
"VSS26":   PN = "63"  !CDS_PN = "63";
"VSS27":   PN = "65"  !CDS_PN = "65";
"VSS28":   PN = "67"  !CDS_PN = "67";
"VSS29":   PN = "69"  !CDS_PN = "69";
"VSS30":   PN = "71"  !CDS_PN = "71";
"VSS31":   PN = "73"  !CDS_PN = "73";
"VSS32":   PN = "75"  !CDS_PN = "75";
"VSS33":   PN = "77"  !CDS_PN = "77";
"VSS34":   PN = "79"  !CDS_PN = "79";
"VSS35":   PN = "81"  !CDS_PN = "81";
"VSS36":   PN = "83"  !CDS_PN = "83";
"VSS37":   PN = "85"  !CDS_PN = "85";
"VSS38":   PN = "88"  !CDS_PN = "88";
"VSS39":   PN = "90"  !CDS_PN = "90";
"VSS40":   PN = "92"  !CDS_PN = "92";
"VSS41":   PN = "95"  !CDS_PN = "95";
"VSS42":   PN = "97"  !CDS_PN = "97";
"VSS43":   PN = "99"  !CDS_PN = "99";
"VSS44":   PN = "101"  !CDS_PN = "101";
"VSS45":   PN = "103"  !CDS_PN = "103";
"VSS46":   PN = "106"  !CDS_PN = "106";
"VSS47":   PN = "108"  !CDS_PN = "108";
"VSS48":   PN = "110"  !CDS_PN = "110";
"VSS49":   PN = "112"  !CDS_PN = "112";
"VSS50":   PN = "114"  !CDS_PN = "114";
"VSS51":   PN = "117"  !CDS_PN = "117";
"VSS52":   PN = "119"  !CDS_PN = "119";
"VSS53":   PN = "121"  !CDS_PN = "121";
"VSS54":   PN = "123"  !CDS_PN = "123";
"VSS55":   PN = "125"  !CDS_PN = "125";
"VSS56":   PN = "128"  !CDS_PN = "128";
"VSS57":   PN = "130"  !CDS_PN = "130";
"VSS58":   PN = "132"  !CDS_PN = "132";
"VSS59":   PN = "134"  !CDS_PN = "134";
"VSS60":   PN = "136"  !CDS_PN = "136";
"VSS61":   PN = "139"  !CDS_PN = "139";
"VSS62":   PN = "141"  !CDS_PN = "141";
"VSS63":   PN = "143"  !CDS_PN = "143";
"VSS64":   PN = "151"  !CDS_PN = "151";
"VSS65":   PN = "153"  !CDS_PN = "153";
"VSS66":   PN = "155"  !CDS_PN = "155";
"VSS67":   PN = "158"  !CDS_PN = "158";
"VSS68":   PN = "160"  !CDS_PN = "160";
"VSS69":   PN = "162"  !CDS_PN = "162";
"VSS70":   PN = "164"  !CDS_PN = "164";
"VSS71":   PN = "166"  !CDS_PN = "166";
"VSS72":   PN = "169"  !CDS_PN = "169";
"VSS73":   PN = "171"  !CDS_PN = "171";
"VSS74":   PN = "173"  !CDS_PN = "173";
"VSS75":   PN = "175"  !CDS_PN = "175";
"VSS76":   PN = "177"  !CDS_PN = "177";
"VSS77":   PN = "180"  !CDS_PN = "180";
"VSS78":   PN = "182"  !CDS_PN = "182";
"VSS79":   PN = "184"  !CDS_PN = "184";
"VSS80":   PN = "186"  !CDS_PN = "186";
"VSS81":   PN = "188"  !CDS_PN = "188";
"VSS82":   PN = "191"  !CDS_PN = "191";
"VSS83":   PN = "193"  !CDS_PN = "193";
"VSS84":   PN = "195"  !CDS_PN = "195";
"VSS85":   PN = "197"  !CDS_PN = "197";
"VSS86":   PN = "199"  !CDS_PN = "199";
"VSS87":   PN = "202"  !CDS_PN = "202";
"VSS88":   PN = "204"  !CDS_PN = "204";
"VSS89":   PN = "206"  !CDS_PN = "206";
"VSS90":   PN = "208"  !CDS_PN = "208";
"VSS91":   PN = "210"  !CDS_PN = "210";
"VSS92":   PN = "212"  !CDS_PN = "212";
"VSS93":   PN = "214"  !CDS_PN = "214";
"VSS94":   PN = "216"  !CDS_PN = "216";
"VSS95":   PN = "219"  !CDS_PN = "219";
"VSS96":   PN = "222"  !CDS_PN = "222";
"VSS97":   PN = "224"  !CDS_PN = "224";
"VSS98":   PN = "226"  !CDS_PN = "226";
"VSS99":   PN = "228"  !CDS_PN = "228";
"VSS100":   PN = "230"  !CDS_PN = "230";
"VSS101":   PN = "233"  !CDS_PN = "233";
"VSS102":   PN = "235"  !CDS_PN = "235";
"VSS103":   PN = "237"  !CDS_PN = "237";
"VSS104":   PN = "240"  !CDS_PN = "240";
"VSS105":   PN = "242"  !CDS_PN = "242";
"VSS106":   PN = "244"  !CDS_PN = "244";
"VSS107":   PN = "246"  !CDS_PN = "246";
"VSS108":   PN = "248"  !CDS_PN = "248";
"VSS109":   PN = "251"  !CDS_PN = "251";
"VSS110":   PN = "253"  !CDS_PN = "253";
"VSS111":   PN = "255"  !CDS_PN = "255";
"VSS112":   PN = "257"  !CDS_PN = "257";
"VSS113":   PN = "259"  !CDS_PN = "259";
"VSS114":   PN = "262"  !CDS_PN = "262";
"VSS115":   PN = "264"  !CDS_PN = "264";
"VSS116":   PN = "266"  !CDS_PN = "266";
"VSS117":   PN = "268"  !CDS_PN = "268";
"VSS118":   PN = "270"  !CDS_PN = "270";
"VSS119":   PN = "273"  !CDS_PN = "273";
"VSS120":   PN = "275"  !CDS_PN = "275";
"VSS121":   PN = "277"  !CDS_PN = "277";
"VSS122":   PN = "279"  !CDS_PN = "279";
"VSS123":   PN = "281"  !CDS_PN = "281";
"VSS124":   PN = "284"  !CDS_PN = "284";
"VSS125":   PN = "286"  !CDS_PN = "286";
"VSS126":   PN = "288"  !CDS_PN = "288";
BODY = "SCONN288_ADR50017P130CC","I178": #LOCATION = "J21" !CDS_LOCATION = "J21" &SEC = "2" #&CDS_SEC = "2";
"DQS0_A_C":   PN = "12"  !CDS_PN = "12";
"DQS0_A_T":   PN = "11"  !CDS_PN = "11";
"DQS0_B_C":   PN = "105"  !CDS_PN = "105";
"DQS0_B_T":   PN = "104"  !CDS_PN = "104";
"DQS1_A_C":   PN = "23"  !CDS_PN = "23";
"DQS1_A_T":   PN = "22"  !CDS_PN = "22";
"DQS1_B_C":   PN = "116"  !CDS_PN = "116";
"DQS1_B_T":   PN = "115"  !CDS_PN = "115";
"DQS2_A_C":   PN = "34"  !CDS_PN = "34";
"DQS2_A_T":   PN = "33"  !CDS_PN = "33";
"DQS2_B_C":   PN = "127"  !CDS_PN = "127";
"DQS2_B_T":   PN = "126"  !CDS_PN = "126";
"DQS3_A_C":   PN = "45"  !CDS_PN = "45";
"DQS3_A_T":   PN = "44"  !CDS_PN = "44";
"DQS3_B_C":   PN = "138"  !CDS_PN = "138";
"DQS3_B_T":   PN = "137"  !CDS_PN = "137";
"DQS4_A_C":   PN = "56"  !CDS_PN = "56";
"DQS4_A_T":   PN = "55"  !CDS_PN = "55";
"DQS4_B_C":   PN = "238"  !CDS_PN = "238";
"DQS4_B_T":   PN = "239"  !CDS_PN = "239";
"DQS5_A_C||TDQS5_A_C||DQS5_A_T||TDQS5_A_T":   PN = "156"  !CDS_PN = "156";
"DQS5_A_T||TDQS5_A_T":   PN = "157"  !CDS_PN = "157";
"DQS5_B_C||TDQS5_B_C":   PN = "249"  !CDS_PN = "249";
"DQS5_B_T||TDQS5_B_T":   PN = "250"  !CDS_PN = "250";
"DQS6_A_C||TDQS6_A_C||DQS6_A_T||TDQS6_A_T":   PN = "167"  !CDS_PN = "167";
"DQS6_A_T||TDQS6_A_T":   PN = "168"  !CDS_PN = "168";
"DQS6_B_C||TDQS6_B_C":   PN = "260"  !CDS_PN = "260";
"DQS6_B_T||TDQS6_B_T":   PN = "261"  !CDS_PN = "261";
"DQS7_A_C||TDQS7_A_C":   PN = "178"  !CDS_PN = "178";
"DQS7_A_T||TDQS7_A_T":   PN = "179"  !CDS_PN = "179";
"DQS7_B_C||TDQS7_B_C":   PN = "271"  !CDS_PN = "271";
"DQS7_B_T||TDQS7_B_T":   PN = "272"  !CDS_PN = "272";
"DQS8_A_C||TDQS8_A_C":   PN = "189"  !CDS_PN = "189";
"DQS8_A_T||TDQS8_A_T":   PN = "190"  !CDS_PN = "190";
"DQS8_B_C||TDQS8_B_C":   PN = "282"  !CDS_PN = "282";
"DQS8_B_T||TDQS8_B_T":   PN = "283"  !CDS_PN = "283";
"DQS9_A_C||TDQS9_A_C":   PN = "200"  !CDS_PN = "200";
"DQS9_A_T||TDQS9_A_T":   PN = "201"  !CDS_PN = "201";
"DQS9_B_C||TDQS9_B_C":   PN = "94"  !CDS_PN = "94";
"DQS9_B_T||TDQS9_B_T||DBI4_B_N":   PN = "93"  !CDS_PN = "93";
BODY = "Q_RES","I180": LOCATION = "R3895" #&CDS_LOCATION = "R3895" &SEC = "1" #&CDS_SEC = "1";
"A":   PN = "1"  !CDS_PN = "1";
"B":   PN = "2"  !CDS_PN = "2";
DRAWING = "@s9s_mb_2u_lib.s9s_mb_2u(sch_1):page103";
BODY = "Q_RES","I2": LOCATION = "R47" #&CDS_LOCATION = "R47" &SEC = "1" #&CDS_SEC = "1";
"A":   PN = "1"  !CDS_PN = "1";
"B":   PN = "2"  !CDS_PN = "2";
BODY = "SCONN288_ADR50017P087CC","I51": LOCATION = "J22" #&CDS_LOCATION = "J22" &SEC = "1" #&CDS_SEC = "1";
"ALERT_N":   PN = "62"  !CDS_PN = "62";
"CA0_A":   PN = "66"  !CDS_PN = "66";
"CA0_B":   PN = "76"  !CDS_PN = "76";
"CA1_A":   PN = "211"  !CDS_PN = "211";
"CA1_B":   PN = "221"  !CDS_PN = "221";
"CA2_A":   PN = "68"  !CDS_PN = "68";
"CA2_B":   PN = "78"  !CDS_PN = "78";
"CA3_A":   PN = "213"  !CDS_PN = "213";
"CA3_B":   PN = "223"  !CDS_PN = "223";
"CA4_A":   PN = "70"  !CDS_PN = "70";
"CA4_B":   PN = "80"  !CDS_PN = "80";
"CA5_A":   PN = "215"  !CDS_PN = "215";
"CA5_B":   PN = "225"  !CDS_PN = "225";
"CA6_A":   PN = "72"  !CDS_PN = "72";
"CA6_B":   PN = "82"  !CDS_PN = "82";
"CB0_A":   PN = "51"  !CDS_PN = "51";
"CB0_B":   PN = "96"  !CDS_PN = "96";
"CB1_A":   PN = "53"  !CDS_PN = "53";
"CB1_B":   PN = "98"  !CDS_PN = "98";
"CB2_A":   PN = "196"  !CDS_PN = "196";
"CB2_B":   PN = "241"  !CDS_PN = "241";
"CB3_A":   PN = "198"  !CDS_PN = "198";
"CB3_B":   PN = "243"  !CDS_PN = "243";
"CB4_A":   PN = "58"  !CDS_PN = "58";
"CB4_B":   PN = "89"  !CDS_PN = "89";
"CB5_A":   PN = "60"  !CDS_PN = "60";
"CB5_B":   PN = "91"  !CDS_PN = "91";
"CB6_A":   PN = "203"  !CDS_PN = "203";
"CB6_B":   PN = "234"  !CDS_PN = "234";
"CB7_A":   PN = "205"  !CDS_PN = "205";
"CB7_B":   PN = "236"  !CDS_PN = "236";
"CK_C":   PN = "218"  !CDS_PN = "218";
"CK_T":   PN = "217"  !CDS_PN = "217";
"CS0_A_N":   PN = "64"  !CDS_PN = "64";
"CS0_B_N":   PN = "84"  !CDS_PN = "84";
"CS1_A_N":   PN = "209"  !CDS_PN = "209";
"CS1_B_N":   PN = "229"  !CDS_PN = "229";
"DQ0_A":   PN = "7"  !CDS_PN = "7";
"DQ0_B":   PN = "100"  !CDS_PN = "100";
"DQ1_A":   PN = "9"  !CDS_PN = "9";
"DQ1_B":   PN = "102"  !CDS_PN = "102";
"DQ2_A":   PN = "152"  !CDS_PN = "152";
"DQ2_B":   PN = "245"  !CDS_PN = "245";
"DQ3_A":   PN = "154"  !CDS_PN = "154";
"DQ3_B":   PN = "247"  !CDS_PN = "247";
"DQ4_A":   PN = "14"  !CDS_PN = "14";
"DQ4_B":   PN = "107"  !CDS_PN = "107";
"DQ5_A":   PN = "16"  !CDS_PN = "16";
"DQ5_B":   PN = "109"  !CDS_PN = "109";
"DQ6_A":   PN = "159"  !CDS_PN = "159";
"DQ6_B":   PN = "252"  !CDS_PN = "252";
"DQ7_A":   PN = "161"  !CDS_PN = "161";
"DQ7_B":   PN = "254"  !CDS_PN = "254";
"DQ8_A":   PN = "18"  !CDS_PN = "18";
"DQ8_B":   PN = "111"  !CDS_PN = "111";
"DQ9_A":   PN = "20"  !CDS_PN = "20";
"DQ9_B":   PN = "113"  !CDS_PN = "113";
"DQ10_A":   PN = "163"  !CDS_PN = "163";
"DQ10_B":   PN = "256"  !CDS_PN = "256";
"DQ11_A":   PN = "165"  !CDS_PN = "165";
"DQ11_B":   PN = "258"  !CDS_PN = "258";
"DQ12_A":   PN = "25"  !CDS_PN = "25";
"DQ12_B":   PN = "118"  !CDS_PN = "118";
"DQ13_A":   PN = "27"  !CDS_PN = "27";
"DQ13_B":   PN = "120"  !CDS_PN = "120";
"DQ14_A":   PN = "170"  !CDS_PN = "170";
"DQ14_B":   PN = "263"  !CDS_PN = "263";
"DQ15_A":   PN = "172"  !CDS_PN = "172";
"DQ15_B":   PN = "265"  !CDS_PN = "265";
"DQ16_A":   PN = "29"  !CDS_PN = "29";
"DQ16_B":   PN = "122"  !CDS_PN = "122";
"DQ17_A":   PN = "31"  !CDS_PN = "31";
"DQ17_B":   PN = "124"  !CDS_PN = "124";
"DQ18_A":   PN = "174"  !CDS_PN = "174";
"DQ18_B":   PN = "267"  !CDS_PN = "267";
"DQ19_A":   PN = "176"  !CDS_PN = "176";
"DQ19_B":   PN = "269"  !CDS_PN = "269";
"DQ20_A":   PN = "36"  !CDS_PN = "36";
"DQ20_B":   PN = "129"  !CDS_PN = "129";
"DQ21_A":   PN = "38"  !CDS_PN = "38";
"DQ21_B":   PN = "131"  !CDS_PN = "131";
"DQ22_A":   PN = "181"  !CDS_PN = "181";
"DQ22_B":   PN = "274"  !CDS_PN = "274";
"DQ23_A":   PN = "183"  !CDS_PN = "183";
"DQ23_B":   PN = "276"  !CDS_PN = "276";
"DQ24_A":   PN = "40"  !CDS_PN = "40";
"DQ24_B":   PN = "133"  !CDS_PN = "133";
"DQ25_A":   PN = "42"  !CDS_PN = "42";
"DQ25_B":   PN = "135"  !CDS_PN = "135";
"DQ26_A":   PN = "185"  !CDS_PN = "185";
"DQ26_B":   PN = "278"  !CDS_PN = "278";
"DQ27_A":   PN = "187"  !CDS_PN = "187";
"DQ27_B":   PN = "280"  !CDS_PN = "280";
"DQ28_A":   PN = "47"  !CDS_PN = "47";
"DQ28_B":   PN = "140"  !CDS_PN = "140";
"DQ29_A":   PN = "49"  !CDS_PN = "49";
"DQ29_B":   PN = "142"  !CDS_PN = "142";
"DQ30_A":   PN = "192"  !CDS_PN = "192";
"DQ30_B":   PN = "285"  !CDS_PN = "285";
"DQ31_A":   PN = "194"  !CDS_PN = "194";
"DQ31_B":   PN = "287"  !CDS_PN = "287";
"HSA":   PN = "148"  !CDS_PN = "148";
"HSCL":   PN = "4"  !CDS_PN = "4";
"HSDA":   PN = "5"  !CDS_PN = "5";
"LBD||RSP_A_N":   PN = "86"  !CDS_PN = "86";
"LBS||RSP_B_N":   PN = "87"  !CDS_PN = "87";
"PAR_A":   PN = "74"  !CDS_PN = "74";
"PAR_B":   PN = "227"  !CDS_PN = "227";
"PWR_GOOD||FAIL_N":   PN = "147"  !CDS_PN = "147";
"RESET_N":   PN = "207"  !CDS_PN = "207";
"RFU0":   PN = "2"  !CDS_PN = "2";
"RFU1":   PN = "144"  !CDS_PN = "144";
"RFU2":   PN = "149"  !CDS_PN = "149";
"RFU3":   PN = "150"  !CDS_PN = "150";
"RFU4":   PN = "220"  !CDS_PN = "220";
"RFU5":   PN = "231"  !CDS_PN = "231";
"RFU6":   PN = "232"  !CDS_PN = "232";
"VIN_MGMT":   PN = "3"  !CDS_PN = "3";
BODY = "Q_CAP","I122": LOCATION = "C65" #&CDS_LOCATION = "C65" &SEC = "1" #&CDS_SEC = "1";
"A":   PN = "1"  !CDS_PN = "1";
"B":   PN = "2"  !CDS_PN = "2";
BODY = "Q_CAP","I126": LOCATION = "C66" #&CDS_LOCATION = "C66" &SEC = "1" #&CDS_SEC = "1";
"A":   PN = "1"  !CDS_PN = "1";
"B":   PN = "2"  !CDS_PN = "2";
BODY = "Q_CAP","I128": LOCATION = "C67" #&CDS_LOCATION = "C67" &SEC = "1" #&CDS_SEC = "1";
"A":   PN = "1"  !CDS_PN = "1";
"B":   PN = "2"  !CDS_PN = "2";
BODY = "SCONN288_ADR50017P087CC","I176": LOCATION = "J22" #&CDS_LOCATION = "J22" &SEC = "3" #&CDS_SEC = "3";
"G1":   PN = "G1"  !CDS_PN = "G1";
"G2":   PN = "G2"  !CDS_PN = "G2";
"G3":   PN = "G3"  !CDS_PN = "G3";
"VIN_BULK0":   PN = "1"  !CDS_PN = "1";
"VIN_BULK1":   PN = "145"  !CDS_PN = "145";
"VIN_BULK2":   PN = "146"  !CDS_PN = "146";
"VSS0":   PN = "6"  !CDS_PN = "6";
"VSS1":   PN = "8"  !CDS_PN = "8";
"VSS2":   PN = "10"  !CDS_PN = "10";
"VSS3":   PN = "13"  !CDS_PN = "13";
"VSS4":   PN = "15"  !CDS_PN = "15";
"VSS5":   PN = "17"  !CDS_PN = "17";
"VSS6":   PN = "19"  !CDS_PN = "19";
"VSS7":   PN = "21"  !CDS_PN = "21";
"VSS8":   PN = "24"  !CDS_PN = "24";
"VSS9":   PN = "26"  !CDS_PN = "26";
"VSS10":   PN = "28"  !CDS_PN = "28";
"VSS11":   PN = "30"  !CDS_PN = "30";
"VSS12":   PN = "32"  !CDS_PN = "32";
"VSS13":   PN = "35"  !CDS_PN = "35";
"VSS14":   PN = "37"  !CDS_PN = "37";
"VSS15":   PN = "39"  !CDS_PN = "39";
"VSS16":   PN = "41"  !CDS_PN = "41";
"VSS17":   PN = "43"  !CDS_PN = "43";
"VSS18":   PN = "46"  !CDS_PN = "46";
"VSS19":   PN = "48"  !CDS_PN = "48";
"VSS20":   PN = "50"  !CDS_PN = "50";
"VSS21":   PN = "52"  !CDS_PN = "52";
"VSS22":   PN = "54"  !CDS_PN = "54";
"VSS23":   PN = "57"  !CDS_PN = "57";
"VSS24":   PN = "59"  !CDS_PN = "59";
"VSS25":   PN = "61"  !CDS_PN = "61";
"VSS26":   PN = "63"  !CDS_PN = "63";
"VSS27":   PN = "65"  !CDS_PN = "65";
"VSS28":   PN = "67"  !CDS_PN = "67";
"VSS29":   PN = "69"  !CDS_PN = "69";
"VSS30":   PN = "71"  !CDS_PN = "71";
"VSS31":   PN = "73"  !CDS_PN = "73";
"VSS32":   PN = "75"  !CDS_PN = "75";
"VSS33":   PN = "77"  !CDS_PN = "77";
"VSS34":   PN = "79"  !CDS_PN = "79";
"VSS35":   PN = "81"  !CDS_PN = "81";
"VSS36":   PN = "83"  !CDS_PN = "83";
"VSS37":   PN = "85"  !CDS_PN = "85";
"VSS38":   PN = "88"  !CDS_PN = "88";
"VSS39":   PN = "90"  !CDS_PN = "90";
"VSS40":   PN = "92"  !CDS_PN = "92";
"VSS41":   PN = "95"  !CDS_PN = "95";
"VSS42":   PN = "97"  !CDS_PN = "97";
"VSS43":   PN = "99"  !CDS_PN = "99";
"VSS44":   PN = "101"  !CDS_PN = "101";
"VSS45":   PN = "103"  !CDS_PN = "103";
"VSS46":   PN = "106"  !CDS_PN = "106";
"VSS47":   PN = "108"  !CDS_PN = "108";
"VSS48":   PN = "110"  !CDS_PN = "110";
"VSS49":   PN = "112"  !CDS_PN = "112";
"VSS50":   PN = "114"  !CDS_PN = "114";
"VSS51":   PN = "117"  !CDS_PN = "117";
"VSS52":   PN = "119"  !CDS_PN = "119";
"VSS53":   PN = "121"  !CDS_PN = "121";
"VSS54":   PN = "123"  !CDS_PN = "123";
"VSS55":   PN = "125"  !CDS_PN = "125";
"VSS56":   PN = "128"  !CDS_PN = "128";
"VSS57":   PN = "130"  !CDS_PN = "130";
"VSS58":   PN = "132"  !CDS_PN = "132";
"VSS59":   PN = "134"  !CDS_PN = "134";
"VSS60":   PN = "136"  !CDS_PN = "136";
"VSS61":   PN = "139"  !CDS_PN = "139";
"VSS62":   PN = "141"  !CDS_PN = "141";
"VSS63":   PN = "143"  !CDS_PN = "143";
"VSS64":   PN = "151"  !CDS_PN = "151";
"VSS65":   PN = "153"  !CDS_PN = "153";
"VSS66":   PN = "155"  !CDS_PN = "155";
"VSS67":   PN = "158"  !CDS_PN = "158";
"VSS68":   PN = "160"  !CDS_PN = "160";
"VSS69":   PN = "162"  !CDS_PN = "162";
"VSS70":   PN = "164"  !CDS_PN = "164";
"VSS71":   PN = "166"  !CDS_PN = "166";
"VSS72":   PN = "169"  !CDS_PN = "169";
"VSS73":   PN = "171"  !CDS_PN = "171";
"VSS74":   PN = "173"  !CDS_PN = "173";
"VSS75":   PN = "175"  !CDS_PN = "175";
"VSS76":   PN = "177"  !CDS_PN = "177";
"VSS77":   PN = "180"  !CDS_PN = "180";
"VSS78":   PN = "182"  !CDS_PN = "182";
"VSS79":   PN = "184"  !CDS_PN = "184";
"VSS80":   PN = "186"  !CDS_PN = "186";
"VSS81":   PN = "188"  !CDS_PN = "188";
"VSS82":   PN = "191"  !CDS_PN = "191";
"VSS83":   PN = "193"  !CDS_PN = "193";
"VSS84":   PN = "195"  !CDS_PN = "195";
"VSS85":   PN = "197"  !CDS_PN = "197";
"VSS86":   PN = "199"  !CDS_PN = "199";
"VSS87":   PN = "202"  !CDS_PN = "202";
"VSS88":   PN = "204"  !CDS_PN = "204";
"VSS89":   PN = "206"  !CDS_PN = "206";
"VSS90":   PN = "208"  !CDS_PN = "208";
"VSS91":   PN = "210"  !CDS_PN = "210";
"VSS92":   PN = "212"  !CDS_PN = "212";
"VSS93":   PN = "214"  !CDS_PN = "214";
"VSS94":   PN = "216"  !CDS_PN = "216";
"VSS95":   PN = "219"  !CDS_PN = "219";
"VSS96":   PN = "222"  !CDS_PN = "222";
"VSS97":   PN = "224"  !CDS_PN = "224";
"VSS98":   PN = "226"  !CDS_PN = "226";
"VSS99":   PN = "228"  !CDS_PN = "228";
"VSS100":   PN = "230"  !CDS_PN = "230";
"VSS101":   PN = "233"  !CDS_PN = "233";
"VSS102":   PN = "235"  !CDS_PN = "235";
"VSS103":   PN = "237"  !CDS_PN = "237";
"VSS104":   PN = "240"  !CDS_PN = "240";
"VSS105":   PN = "242"  !CDS_PN = "242";
"VSS106":   PN = "244"  !CDS_PN = "244";
"VSS107":   PN = "246"  !CDS_PN = "246";
"VSS108":   PN = "248"  !CDS_PN = "248";
"VSS109":   PN = "251"  !CDS_PN = "251";
"VSS110":   PN = "253"  !CDS_PN = "253";
"VSS111":   PN = "255"  !CDS_PN = "255";
"VSS112":   PN = "257"  !CDS_PN = "257";
"VSS113":   PN = "259"  !CDS_PN = "259";
"VSS114":   PN = "262"  !CDS_PN = "262";
"VSS115":   PN = "264"  !CDS_PN = "264";
"VSS116":   PN = "266"  !CDS_PN = "266";
"VSS117":   PN = "268"  !CDS_PN = "268";
"VSS118":   PN = "270"  !CDS_PN = "270";
"VSS119":   PN = "273"  !CDS_PN = "273";
"VSS120":   PN = "275"  !CDS_PN = "275";
"VSS121":   PN = "277"  !CDS_PN = "277";
"VSS122":   PN = "279"  !CDS_PN = "279";
"VSS123":   PN = "281"  !CDS_PN = "281";
"VSS124":   PN = "284"  !CDS_PN = "284";
"VSS125":   PN = "286"  !CDS_PN = "286";
"VSS126":   PN = "288"  !CDS_PN = "288";
BODY = "SCONN288_ADR50017P087CC","I178": #LOCATION = "J22" !CDS_LOCATION = "J22" &SEC = "2" #&CDS_SEC = "2";
"DQS0_A_C":   PN = "12"  !CDS_PN = "12";
"DQS0_A_T":   PN = "11"  !CDS_PN = "11";
"DQS0_B_C":   PN = "105"  !CDS_PN = "105";
"DQS0_B_T":   PN = "104"  !CDS_PN = "104";
"DQS1_A_C":   PN = "23"  !CDS_PN = "23";
"DQS1_A_T":   PN = "22"  !CDS_PN = "22";
"DQS1_B_C":   PN = "116"  !CDS_PN = "116";
"DQS1_B_T":   PN = "115"  !CDS_PN = "115";
"DQS2_A_C":   PN = "34"  !CDS_PN = "34";
"DQS2_A_T":   PN = "33"  !CDS_PN = "33";
"DQS2_B_C":   PN = "127"  !CDS_PN = "127";
"DQS2_B_T":   PN = "126"  !CDS_PN = "126";
"DQS3_A_C":   PN = "45"  !CDS_PN = "45";
"DQS3_A_T":   PN = "44"  !CDS_PN = "44";
"DQS3_B_C":   PN = "138"  !CDS_PN = "138";
"DQS3_B_T":   PN = "137"  !CDS_PN = "137";
"DQS4_A_C":   PN = "56"  !CDS_PN = "56";
"DQS4_A_T":   PN = "55"  !CDS_PN = "55";
"DQS4_B_C":   PN = "238"  !CDS_PN = "238";
"DQS4_B_T":   PN = "239"  !CDS_PN = "239";
"DQS5_A_C||TDQS5_A_C||DQS5_A_T||TDQS5_A_T":   PN = "156"  !CDS_PN = "156";
"DQS5_A_T||TDQS5_A_T":   PN = "157"  !CDS_PN = "157";
"DQS5_B_C||TDQS5_B_C":   PN = "249"  !CDS_PN = "249";
"DQS5_B_T||TDQS5_B_T":   PN = "250"  !CDS_PN = "250";
"DQS6_A_C||TDQS6_A_C||DQS6_A_T||TDQS6_A_T":   PN = "167"  !CDS_PN = "167";
"DQS6_A_T||TDQS6_A_T":   PN = "168"  !CDS_PN = "168";
"DQS6_B_C||TDQS6_B_C":   PN = "260"  !CDS_PN = "260";
"DQS6_B_T||TDQS6_B_T":   PN = "261"  !CDS_PN = "261";
"DQS7_A_C||TDQS7_A_C":   PN = "178"  !CDS_PN = "178";
"DQS7_A_T||TDQS7_A_T":   PN = "179"  !CDS_PN = "179";
"DQS7_B_C||TDQS7_B_C":   PN = "271"  !CDS_PN = "271";
"DQS7_B_T||TDQS7_B_T":   PN = "272"  !CDS_PN = "272";
"DQS8_A_C||TDQS8_A_C":   PN = "189"  !CDS_PN = "189";
"DQS8_A_T||TDQS8_A_T":   PN = "190"  !CDS_PN = "190";
"DQS8_B_C||TDQS8_B_C":   PN = "282"  !CDS_PN = "282";
"DQS8_B_T||TDQS8_B_T":   PN = "283"  !CDS_PN = "283";
"DQS9_A_C||TDQS9_A_C":   PN = "200"  !CDS_PN = "200";
"DQS9_A_T||TDQS9_A_T":   PN = "201"  !CDS_PN = "201";
"DQS9_B_C||TDQS9_B_C":   PN = "94"  !CDS_PN = "94";
"DQS9_B_T||TDQS9_B_T||DBI4_B_N":   PN = "93"  !CDS_PN = "93";
BODY = "Q_RES","I180": LOCATION = "R3896" #&CDS_LOCATION = "R3896" &SEC = "1" #&CDS_SEC = "1";
"A":   PN = "1"  !CDS_PN = "1";
"B":   PN = "2"  !CDS_PN = "2";
DRAWING = "@s9s_mb_2u_lib.s9s_mb_2u(sch_1):page104";
BODY = "Q_RES","I2": LOCATION = "R48" #&CDS_LOCATION = "R48" &SEC = "1" #&CDS_SEC = "1";
"A":   PN = "1"  !CDS_PN = "1";
"B":   PN = "2"  !CDS_PN = "2";
BODY = "SCONN288_ADR50017P130CC","I25": LOCATION = "J23" #&CDS_LOCATION = "J23" &SEC = "1" #&CDS_SEC = "1";
"ALERT_N":   PN = "62"  !CDS_PN = "62";
"CA0_A":   PN = "66"  !CDS_PN = "66";
"CA0_B":   PN = "76"  !CDS_PN = "76";
"CA1_A":   PN = "211"  !CDS_PN = "211";
"CA1_B":   PN = "221"  !CDS_PN = "221";
"CA2_A":   PN = "68"  !CDS_PN = "68";
"CA2_B":   PN = "78"  !CDS_PN = "78";
"CA3_A":   PN = "213"  !CDS_PN = "213";
"CA3_B":   PN = "223"  !CDS_PN = "223";
"CA4_A":   PN = "70"  !CDS_PN = "70";
"CA4_B":   PN = "80"  !CDS_PN = "80";
"CA5_A":   PN = "215"  !CDS_PN = "215";
"CA5_B":   PN = "225"  !CDS_PN = "225";
"CA6_A":   PN = "72"  !CDS_PN = "72";
"CA6_B":   PN = "82"  !CDS_PN = "82";
"CB0_A":   PN = "51"  !CDS_PN = "51";
"CB0_B":   PN = "96"  !CDS_PN = "96";
"CB1_A":   PN = "53"  !CDS_PN = "53";
"CB1_B":   PN = "98"  !CDS_PN = "98";
"CB2_A":   PN = "196"  !CDS_PN = "196";
"CB2_B":   PN = "241"  !CDS_PN = "241";
"CB3_A":   PN = "198"  !CDS_PN = "198";
"CB3_B":   PN = "243"  !CDS_PN = "243";
"CB4_A":   PN = "58"  !CDS_PN = "58";
"CB4_B":   PN = "89"  !CDS_PN = "89";
"CB5_A":   PN = "60"  !CDS_PN = "60";
"CB5_B":   PN = "91"  !CDS_PN = "91";
"CB6_A":   PN = "203"  !CDS_PN = "203";
"CB6_B":   PN = "234"  !CDS_PN = "234";
"CB7_A":   PN = "205"  !CDS_PN = "205";
"CB7_B":   PN = "236"  !CDS_PN = "236";
"CK_C":   PN = "218"  !CDS_PN = "218";
"CK_T":   PN = "217"  !CDS_PN = "217";
"CS0_A_N":   PN = "64"  !CDS_PN = "64";
"CS0_B_N":   PN = "84"  !CDS_PN = "84";
"CS1_A_N":   PN = "209"  !CDS_PN = "209";
"CS1_B_N":   PN = "229"  !CDS_PN = "229";
"DQ0_A":   PN = "7"  !CDS_PN = "7";
"DQ0_B":   PN = "100"  !CDS_PN = "100";
"DQ1_A":   PN = "9"  !CDS_PN = "9";
"DQ1_B":   PN = "102"  !CDS_PN = "102";
"DQ2_A":   PN = "152"  !CDS_PN = "152";
"DQ2_B":   PN = "245"  !CDS_PN = "245";
"DQ3_A":   PN = "154"  !CDS_PN = "154";
"DQ3_B":   PN = "247"  !CDS_PN = "247";
"DQ4_A":   PN = "14"  !CDS_PN = "14";
"DQ4_B":   PN = "107"  !CDS_PN = "107";
"DQ5_A":   PN = "16"  !CDS_PN = "16";
"DQ5_B":   PN = "109"  !CDS_PN = "109";
"DQ6_A":   PN = "159"  !CDS_PN = "159";
"DQ6_B":   PN = "252"  !CDS_PN = "252";
"DQ7_A":   PN = "161"  !CDS_PN = "161";
"DQ7_B":   PN = "254"  !CDS_PN = "254";
"DQ8_A":   PN = "18"  !CDS_PN = "18";
"DQ8_B":   PN = "111"  !CDS_PN = "111";
"DQ9_A":   PN = "20"  !CDS_PN = "20";
"DQ9_B":   PN = "113"  !CDS_PN = "113";
"DQ10_A":   PN = "163"  !CDS_PN = "163";
"DQ10_B":   PN = "256"  !CDS_PN = "256";
"DQ11_A":   PN = "165"  !CDS_PN = "165";
"DQ11_B":   PN = "258"  !CDS_PN = "258";
"DQ12_A":   PN = "25"  !CDS_PN = "25";
"DQ12_B":   PN = "118"  !CDS_PN = "118";
"DQ13_A":   PN = "27"  !CDS_PN = "27";
"DQ13_B":   PN = "120"  !CDS_PN = "120";
"DQ14_A":   PN = "170"  !CDS_PN = "170";
"DQ14_B":   PN = "263"  !CDS_PN = "263";
"DQ15_A":   PN = "172"  !CDS_PN = "172";
"DQ15_B":   PN = "265"  !CDS_PN = "265";
"DQ16_A":   PN = "29"  !CDS_PN = "29";
"DQ16_B":   PN = "122"  !CDS_PN = "122";
"DQ17_A":   PN = "31"  !CDS_PN = "31";
"DQ17_B":   PN = "124"  !CDS_PN = "124";
"DQ18_A":   PN = "174"  !CDS_PN = "174";
"DQ18_B":   PN = "267"  !CDS_PN = "267";
"DQ19_A":   PN = "176"  !CDS_PN = "176";
"DQ19_B":   PN = "269"  !CDS_PN = "269";
"DQ20_A":   PN = "36"  !CDS_PN = "36";
"DQ20_B":   PN = "129"  !CDS_PN = "129";
"DQ21_A":   PN = "38"  !CDS_PN = "38";
"DQ21_B":   PN = "131"  !CDS_PN = "131";
"DQ22_A":   PN = "181"  !CDS_PN = "181";
"DQ22_B":   PN = "274"  !CDS_PN = "274";
"DQ23_A":   PN = "183"  !CDS_PN = "183";
"DQ23_B":   PN = "276"  !CDS_PN = "276";
"DQ24_A":   PN = "40"  !CDS_PN = "40";
"DQ24_B":   PN = "133"  !CDS_PN = "133";
"DQ25_A":   PN = "42"  !CDS_PN = "42";
"DQ25_B":   PN = "135"  !CDS_PN = "135";
"DQ26_A":   PN = "185"  !CDS_PN = "185";
"DQ26_B":   PN = "278"  !CDS_PN = "278";
"DQ27_A":   PN = "187"  !CDS_PN = "187";
"DQ27_B":   PN = "280"  !CDS_PN = "280";
"DQ28_A":   PN = "47"  !CDS_PN = "47";
"DQ28_B":   PN = "140"  !CDS_PN = "140";
"DQ29_A":   PN = "49"  !CDS_PN = "49";
"DQ29_B":   PN = "142"  !CDS_PN = "142";
"DQ30_A":   PN = "192"  !CDS_PN = "192";
"DQ30_B":   PN = "285"  !CDS_PN = "285";
"DQ31_A":   PN = "194"  !CDS_PN = "194";
"DQ31_B":   PN = "287"  !CDS_PN = "287";
"HSA":   PN = "148"  !CDS_PN = "148";
"HSCL":   PN = "4"  !CDS_PN = "4";
"HSDA":   PN = "5"  !CDS_PN = "5";
"LBD||RSP_A_N":   PN = "86"  !CDS_PN = "86";
"LBS||RSP_B_N":   PN = "87"  !CDS_PN = "87";
"PAR_A":   PN = "74"  !CDS_PN = "74";
"PAR_B":   PN = "227"  !CDS_PN = "227";
"PWR_GOOD||FAIL_N":   PN = "147"  !CDS_PN = "147";
"RESET_N":   PN = "207"  !CDS_PN = "207";
"RFU0":   PN = "2"  !CDS_PN = "2";
"RFU1":   PN = "144"  !CDS_PN = "144";
"RFU2":   PN = "149"  !CDS_PN = "149";
"RFU3":   PN = "150"  !CDS_PN = "150";
"RFU4":   PN = "220"  !CDS_PN = "220";
"RFU5":   PN = "231"  !CDS_PN = "231";
"RFU6":   PN = "232"  !CDS_PN = "232";
"VIN_MGMT":   PN = "3"  !CDS_PN = "3";
BODY = "Q_CAP","I122": LOCATION = "C68" #&CDS_LOCATION = "C68" &SEC = "1" #&CDS_SEC = "1";
"A":   PN = "1"  !CDS_PN = "1";
"B":   PN = "2"  !CDS_PN = "2";
BODY = "Q_CAP","I127": LOCATION = "C69" #&CDS_LOCATION = "C69" &SEC = "1" #&CDS_SEC = "1";
"A":   PN = "1"  !CDS_PN = "1";
"B":   PN = "2"  !CDS_PN = "2";
BODY = "Q_CAP","I129": LOCATION = "C70" #&CDS_LOCATION = "C70" &SEC = "1" #&CDS_SEC = "1";
"A":   PN = "1"  !CDS_PN = "1";
"B":   PN = "2"  !CDS_PN = "2";
BODY = "SCONN288_ADR50017P130CC","I175": LOCATION = "J23" #&CDS_LOCATION = "J23" &SEC = "3" #&CDS_SEC = "3";
"G1":   PN = "G1"  !CDS_PN = "G1";
"G2":   PN = "G2"  !CDS_PN = "G2";
"G3":   PN = "G3"  !CDS_PN = "G3";
"VIN_BULK0":   PN = "1"  !CDS_PN = "1";
"VIN_BULK1":   PN = "145"  !CDS_PN = "145";
"VIN_BULK2":   PN = "146"  !CDS_PN = "146";
"VSS0":   PN = "6"  !CDS_PN = "6";
"VSS1":   PN = "8"  !CDS_PN = "8";
"VSS2":   PN = "10"  !CDS_PN = "10";
"VSS3":   PN = "13"  !CDS_PN = "13";
"VSS4":   PN = "15"  !CDS_PN = "15";
"VSS5":   PN = "17"  !CDS_PN = "17";
"VSS6":   PN = "19"  !CDS_PN = "19";
"VSS7":   PN = "21"  !CDS_PN = "21";
"VSS8":   PN = "24"  !CDS_PN = "24";
"VSS9":   PN = "26"  !CDS_PN = "26";
"VSS10":   PN = "28"  !CDS_PN = "28";
"VSS11":   PN = "30"  !CDS_PN = "30";
"VSS12":   PN = "32"  !CDS_PN = "32";
"VSS13":   PN = "35"  !CDS_PN = "35";
"VSS14":   PN = "37"  !CDS_PN = "37";
"VSS15":   PN = "39"  !CDS_PN = "39";
"VSS16":   PN = "41"  !CDS_PN = "41";
"VSS17":   PN = "43"  !CDS_PN = "43";
"VSS18":   PN = "46"  !CDS_PN = "46";
"VSS19":   PN = "48"  !CDS_PN = "48";
"VSS20":   PN = "50"  !CDS_PN = "50";
"VSS21":   PN = "52"  !CDS_PN = "52";
"VSS22":   PN = "54"  !CDS_PN = "54";
"VSS23":   PN = "57"  !CDS_PN = "57";
"VSS24":   PN = "59"  !CDS_PN = "59";
"VSS25":   PN = "61"  !CDS_PN = "61";
"VSS26":   PN = "63"  !CDS_PN = "63";
"VSS27":   PN = "65"  !CDS_PN = "65";
"VSS28":   PN = "67"  !CDS_PN = "67";
"VSS29":   PN = "69"  !CDS_PN = "69";
"VSS30":   PN = "71"  !CDS_PN = "71";
"VSS31":   PN = "73"  !CDS_PN = "73";
"VSS32":   PN = "75"  !CDS_PN = "75";
"VSS33":   PN = "77"  !CDS_PN = "77";
"VSS34":   PN = "79"  !CDS_PN = "79";
"VSS35":   PN = "81"  !CDS_PN = "81";
"VSS36":   PN = "83"  !CDS_PN = "83";
"VSS37":   PN = "85"  !CDS_PN = "85";
"VSS38":   PN = "88"  !CDS_PN = "88";
"VSS39":   PN = "90"  !CDS_PN = "90";
"VSS40":   PN = "92"  !CDS_PN = "92";
"VSS41":   PN = "95"  !CDS_PN = "95";
"VSS42":   PN = "97"  !CDS_PN = "97";
"VSS43":   PN = "99"  !CDS_PN = "99";
"VSS44":   PN = "101"  !CDS_PN = "101";
"VSS45":   PN = "103"  !CDS_PN = "103";
"VSS46":   PN = "106"  !CDS_PN = "106";
"VSS47":   PN = "108"  !CDS_PN = "108";
"VSS48":   PN = "110"  !CDS_PN = "110";
"VSS49":   PN = "112"  !CDS_PN = "112";
"VSS50":   PN = "114"  !CDS_PN = "114";
"VSS51":   PN = "117"  !CDS_PN = "117";
"VSS52":   PN = "119"  !CDS_PN = "119";
"VSS53":   PN = "121"  !CDS_PN = "121";
"VSS54":   PN = "123"  !CDS_PN = "123";
"VSS55":   PN = "125"  !CDS_PN = "125";
"VSS56":   PN = "128"  !CDS_PN = "128";
"VSS57":   PN = "130"  !CDS_PN = "130";
"VSS58":   PN = "132"  !CDS_PN = "132";
"VSS59":   PN = "134"  !CDS_PN = "134";
"VSS60":   PN = "136"  !CDS_PN = "136";
"VSS61":   PN = "139"  !CDS_PN = "139";
"VSS62":   PN = "141"  !CDS_PN = "141";
"VSS63":   PN = "143"  !CDS_PN = "143";
"VSS64":   PN = "151"  !CDS_PN = "151";
"VSS65":   PN = "153"  !CDS_PN = "153";
"VSS66":   PN = "155"  !CDS_PN = "155";
"VSS67":   PN = "158"  !CDS_PN = "158";
"VSS68":   PN = "160"  !CDS_PN = "160";
"VSS69":   PN = "162"  !CDS_PN = "162";
"VSS70":   PN = "164"  !CDS_PN = "164";
"VSS71":   PN = "166"  !CDS_PN = "166";
"VSS72":   PN = "169"  !CDS_PN = "169";
"VSS73":   PN = "171"  !CDS_PN = "171";
"VSS74":   PN = "173"  !CDS_PN = "173";
"VSS75":   PN = "175"  !CDS_PN = "175";
"VSS76":   PN = "177"  !CDS_PN = "177";
"VSS77":   PN = "180"  !CDS_PN = "180";
"VSS78":   PN = "182"  !CDS_PN = "182";
"VSS79":   PN = "184"  !CDS_PN = "184";
"VSS80":   PN = "186"  !CDS_PN = "186";
"VSS81":   PN = "188"  !CDS_PN = "188";
"VSS82":   PN = "191"  !CDS_PN = "191";
"VSS83":   PN = "193"  !CDS_PN = "193";
"VSS84":   PN = "195"  !CDS_PN = "195";
"VSS85":   PN = "197"  !CDS_PN = "197";
"VSS86":   PN = "199"  !CDS_PN = "199";
"VSS87":   PN = "202"  !CDS_PN = "202";
"VSS88":   PN = "204"  !CDS_PN = "204";
"VSS89":   PN = "206"  !CDS_PN = "206";
"VSS90":   PN = "208"  !CDS_PN = "208";
"VSS91":   PN = "210"  !CDS_PN = "210";
"VSS92":   PN = "212"  !CDS_PN = "212";
"VSS93":   PN = "214"  !CDS_PN = "214";
"VSS94":   PN = "216"  !CDS_PN = "216";
"VSS95":   PN = "219"  !CDS_PN = "219";
"VSS96":   PN = "222"  !CDS_PN = "222";
"VSS97":   PN = "224"  !CDS_PN = "224";
"VSS98":   PN = "226"  !CDS_PN = "226";
"VSS99":   PN = "228"  !CDS_PN = "228";
"VSS100":   PN = "230"  !CDS_PN = "230";
"VSS101":   PN = "233"  !CDS_PN = "233";
"VSS102":   PN = "235"  !CDS_PN = "235";
"VSS103":   PN = "237"  !CDS_PN = "237";
"VSS104":   PN = "240"  !CDS_PN = "240";
"VSS105":   PN = "242"  !CDS_PN = "242";
"VSS106":   PN = "244"  !CDS_PN = "244";
"VSS107":   PN = "246"  !CDS_PN = "246";
"VSS108":   PN = "248"  !CDS_PN = "248";
"VSS109":   PN = "251"  !CDS_PN = "251";
"VSS110":   PN = "253"  !CDS_PN = "253";
"VSS111":   PN = "255"  !CDS_PN = "255";
"VSS112":   PN = "257"  !CDS_PN = "257";
"VSS113":   PN = "259"  !CDS_PN = "259";
"VSS114":   PN = "262"  !CDS_PN = "262";
"VSS115":   PN = "264"  !CDS_PN = "264";
"VSS116":   PN = "266"  !CDS_PN = "266";
"VSS117":   PN = "268"  !CDS_PN = "268";
"VSS118":   PN = "270"  !CDS_PN = "270";
"VSS119":   PN = "273"  !CDS_PN = "273";
"VSS120":   PN = "275"  !CDS_PN = "275";
"VSS121":   PN = "277"  !CDS_PN = "277";
"VSS122":   PN = "279"  !CDS_PN = "279";
"VSS123":   PN = "281"  !CDS_PN = "281";
"VSS124":   PN = "284"  !CDS_PN = "284";
"VSS125":   PN = "286"  !CDS_PN = "286";
"VSS126":   PN = "288"  !CDS_PN = "288";
BODY = "SCONN288_ADR50017P130CC","I178": #LOCATION = "J23" !CDS_LOCATION = "J23" &SEC = "2" #&CDS_SEC = "2";
"DQS0_A_C":   PN = "12"  !CDS_PN = "12";
"DQS0_A_T":   PN = "11"  !CDS_PN = "11";
"DQS0_B_C":   PN = "105"  !CDS_PN = "105";
"DQS0_B_T":   PN = "104"  !CDS_PN = "104";
"DQS1_A_C":   PN = "23"  !CDS_PN = "23";
"DQS1_A_T":   PN = "22"  !CDS_PN = "22";
"DQS1_B_C":   PN = "116"  !CDS_PN = "116";
"DQS1_B_T":   PN = "115"  !CDS_PN = "115";
"DQS2_A_C":   PN = "34"  !CDS_PN = "34";
"DQS2_A_T":   PN = "33"  !CDS_PN = "33";
"DQS2_B_C":   PN = "127"  !CDS_PN = "127";
"DQS2_B_T":   PN = "126"  !CDS_PN = "126";
"DQS3_A_C":   PN = "45"  !CDS_PN = "45";
"DQS3_A_T":   PN = "44"  !CDS_PN = "44";
"DQS3_B_C":   PN = "138"  !CDS_PN = "138";
"DQS3_B_T":   PN = "137"  !CDS_PN = "137";
"DQS4_A_C":   PN = "56"  !CDS_PN = "56";
"DQS4_A_T":   PN = "55"  !CDS_PN = "55";
"DQS4_B_C":   PN = "238"  !CDS_PN = "238";
"DQS4_B_T":   PN = "239"  !CDS_PN = "239";
"DQS5_A_C||TDQS5_A_C||DQS5_A_T||TDQS5_A_T":   PN = "156"  !CDS_PN = "156";
"DQS5_A_T||TDQS5_A_T":   PN = "157"  !CDS_PN = "157";
"DQS5_B_C||TDQS5_B_C":   PN = "249"  !CDS_PN = "249";
"DQS5_B_T||TDQS5_B_T":   PN = "250"  !CDS_PN = "250";
"DQS6_A_C||TDQS6_A_C||DQS6_A_T||TDQS6_A_T":   PN = "167"  !CDS_PN = "167";
"DQS6_A_T||TDQS6_A_T":   PN = "168"  !CDS_PN = "168";
"DQS6_B_C||TDQS6_B_C":   PN = "260"  !CDS_PN = "260";
"DQS6_B_T||TDQS6_B_T":   PN = "261"  !CDS_PN = "261";
"DQS7_A_C||TDQS7_A_C":   PN = "178"  !CDS_PN = "178";
"DQS7_A_T||TDQS7_A_T":   PN = "179"  !CDS_PN = "179";
"DQS7_B_C||TDQS7_B_C":   PN = "271"  !CDS_PN = "271";
"DQS7_B_T||TDQS7_B_T":   PN = "272"  !CDS_PN = "272";
"DQS8_A_C||TDQS8_A_C":   PN = "189"  !CDS_PN = "189";
"DQS8_A_T||TDQS8_A_T":   PN = "190"  !CDS_PN = "190";
"DQS8_B_C||TDQS8_B_C":   PN = "282"  !CDS_PN = "282";
"DQS8_B_T||TDQS8_B_T":   PN = "283"  !CDS_PN = "283";
"DQS9_A_C||TDQS9_A_C":   PN = "200"  !CDS_PN = "200";
"DQS9_A_T||TDQS9_A_T":   PN = "201"  !CDS_PN = "201";
"DQS9_B_C||TDQS9_B_C":   PN = "94"  !CDS_PN = "94";
"DQS9_B_T||TDQS9_B_T||DBI4_B_N":   PN = "93"  !CDS_PN = "93";
BODY = "Q_RES","I180": LOCATION = "R3897" #&CDS_LOCATION = "R3897" &SEC = "1" #&CDS_SEC = "1";
"A":   PN = "1"  !CDS_PN = "1";
"B":   PN = "2"  !CDS_PN = "2";
DRAWING = "@s9s_mb_2u_lib.s9s_mb_2u(sch_1):page105";
BODY = "Q_RES","I2": LOCATION = "R80" #&CDS_LOCATION = "R80" &SEC = "1" #&CDS_SEC = "1";
"A":   PN = "1"  !CDS_PN = "1";
"B":   PN = "2"  !CDS_PN = "2";
BODY = "Q_CAP","I123": LOCATION = "C96" #&CDS_LOCATION = "C96" &SEC = "1" #&CDS_SEC = "1";
"A":   PN = "1"  !CDS_PN = "1";
"B":   PN = "2"  !CDS_PN = "2";
BODY = "Q_CAP","I124": LOCATION = "C97" #&CDS_LOCATION = "C97" &SEC = "1" #&CDS_SEC = "1";
"A":   PN = "1"  !CDS_PN = "1";
"B":   PN = "2"  !CDS_PN = "2";
BODY = "Q_CAP","I146": LOCATION = "C98" #&CDS_LOCATION = "C98" &SEC = "1" #&CDS_SEC = "1";
"A":   PN = "1"  !CDS_PN = "1";
"B":   PN = "2"  !CDS_PN = "2";
BODY = "SCONN288_ADR50017P087CC","I178": LOCATION = "J24" #&CDS_LOCATION = "J24" &SEC = "1" #&CDS_SEC = "1";
"ALERT_N":   PN = "62"  !CDS_PN = "62";
"CA0_A":   PN = "66"  !CDS_PN = "66";
"CA0_B":   PN = "76"  !CDS_PN = "76";
"CA1_A":   PN = "211"  !CDS_PN = "211";
"CA1_B":   PN = "221"  !CDS_PN = "221";
"CA2_A":   PN = "68"  !CDS_PN = "68";
"CA2_B":   PN = "78"  !CDS_PN = "78";
"CA3_A":   PN = "213"  !CDS_PN = "213";
"CA3_B":   PN = "223"  !CDS_PN = "223";
"CA4_A":   PN = "70"  !CDS_PN = "70";
"CA4_B":   PN = "80"  !CDS_PN = "80";
"CA5_A":   PN = "215"  !CDS_PN = "215";
"CA5_B":   PN = "225"  !CDS_PN = "225";
"CA6_A":   PN = "72"  !CDS_PN = "72";
"CA6_B":   PN = "82"  !CDS_PN = "82";
"CB0_A":   PN = "51"  !CDS_PN = "51";
"CB0_B":   PN = "96"  !CDS_PN = "96";
"CB1_A":   PN = "53"  !CDS_PN = "53";
"CB1_B":   PN = "98"  !CDS_PN = "98";
"CB2_A":   PN = "196"  !CDS_PN = "196";
"CB2_B":   PN = "241"  !CDS_PN = "241";
"CB3_A":   PN = "198"  !CDS_PN = "198";
"CB3_B":   PN = "243"  !CDS_PN = "243";
"CB4_A":   PN = "58"  !CDS_PN = "58";
"CB4_B":   PN = "89"  !CDS_PN = "89";
"CB5_A":   PN = "60"  !CDS_PN = "60";
"CB5_B":   PN = "91"  !CDS_PN = "91";
"CB6_A":   PN = "203"  !CDS_PN = "203";
"CB6_B":   PN = "234"  !CDS_PN = "234";
"CB7_A":   PN = "205"  !CDS_PN = "205";
"CB7_B":   PN = "236"  !CDS_PN = "236";
"CK_C":   PN = "218"  !CDS_PN = "218";
"CK_T":   PN = "217"  !CDS_PN = "217";
"CS0_A_N":   PN = "64"  !CDS_PN = "64";
"CS0_B_N":   PN = "84"  !CDS_PN = "84";
"CS1_A_N":   PN = "209"  !CDS_PN = "209";
"CS1_B_N":   PN = "229"  !CDS_PN = "229";
"DQ0_A":   PN = "7"  !CDS_PN = "7";
"DQ0_B":   PN = "100"  !CDS_PN = "100";
"DQ1_A":   PN = "9"  !CDS_PN = "9";
"DQ1_B":   PN = "102"  !CDS_PN = "102";
"DQ2_A":   PN = "152"  !CDS_PN = "152";
"DQ2_B":   PN = "245"  !CDS_PN = "245";
"DQ3_A":   PN = "154"  !CDS_PN = "154";
"DQ3_B":   PN = "247"  !CDS_PN = "247";
"DQ4_A":   PN = "14"  !CDS_PN = "14";
"DQ4_B":   PN = "107"  !CDS_PN = "107";
"DQ5_A":   PN = "16"  !CDS_PN = "16";
"DQ5_B":   PN = "109"  !CDS_PN = "109";
"DQ6_A":   PN = "159"  !CDS_PN = "159";
"DQ6_B":   PN = "252"  !CDS_PN = "252";
"DQ7_A":   PN = "161"  !CDS_PN = "161";
"DQ7_B":   PN = "254"  !CDS_PN = "254";
"DQ8_A":   PN = "18"  !CDS_PN = "18";
"DQ8_B":   PN = "111"  !CDS_PN = "111";
"DQ9_A":   PN = "20"  !CDS_PN = "20";
"DQ9_B":   PN = "113"  !CDS_PN = "113";
"DQ10_A":   PN = "163"  !CDS_PN = "163";
"DQ10_B":   PN = "256"  !CDS_PN = "256";
"DQ11_A":   PN = "165"  !CDS_PN = "165";
"DQ11_B":   PN = "258"  !CDS_PN = "258";
"DQ12_A":   PN = "25"  !CDS_PN = "25";
"DQ12_B":   PN = "118"  !CDS_PN = "118";
"DQ13_A":   PN = "27"  !CDS_PN = "27";
"DQ13_B":   PN = "120"  !CDS_PN = "120";
"DQ14_A":   PN = "170"  !CDS_PN = "170";
"DQ14_B":   PN = "263"  !CDS_PN = "263";
"DQ15_A":   PN = "172"  !CDS_PN = "172";
"DQ15_B":   PN = "265"  !CDS_PN = "265";
"DQ16_A":   PN = "29"  !CDS_PN = "29";
"DQ16_B":   PN = "122"  !CDS_PN = "122";
"DQ17_A":   PN = "31"  !CDS_PN = "31";
"DQ17_B":   PN = "124"  !CDS_PN = "124";
"DQ18_A":   PN = "174"  !CDS_PN = "174";
"DQ18_B":   PN = "267"  !CDS_PN = "267";
"DQ19_A":   PN = "176"  !CDS_PN = "176";
"DQ19_B":   PN = "269"  !CDS_PN = "269";
"DQ20_A":   PN = "36"  !CDS_PN = "36";
"DQ20_B":   PN = "129"  !CDS_PN = "129";
"DQ21_A":   PN = "38"  !CDS_PN = "38";
"DQ21_B":   PN = "131"  !CDS_PN = "131";
"DQ22_A":   PN = "181"  !CDS_PN = "181";
"DQ22_B":   PN = "274"  !CDS_PN = "274";
"DQ23_A":   PN = "183"  !CDS_PN = "183";
"DQ23_B":   PN = "276"  !CDS_PN = "276";
"DQ24_A":   PN = "40"  !CDS_PN = "40";
"DQ24_B":   PN = "133"  !CDS_PN = "133";
"DQ25_A":   PN = "42"  !CDS_PN = "42";
"DQ25_B":   PN = "135"  !CDS_PN = "135";
"DQ26_A":   PN = "185"  !CDS_PN = "185";
"DQ26_B":   PN = "278"  !CDS_PN = "278";
"DQ27_A":   PN = "187"  !CDS_PN = "187";
"DQ27_B":   PN = "280"  !CDS_PN = "280";
"DQ28_A":   PN = "47"  !CDS_PN = "47";
"DQ28_B":   PN = "140"  !CDS_PN = "140";
"DQ29_A":   PN = "49"  !CDS_PN = "49";
"DQ29_B":   PN = "142"  !CDS_PN = "142";
"DQ30_A":   PN = "192"  !CDS_PN = "192";
"DQ30_B":   PN = "285"  !CDS_PN = "285";
"DQ31_A":   PN = "194"  !CDS_PN = "194";
"DQ31_B":   PN = "287"  !CDS_PN = "287";
"HSA":   PN = "148"  !CDS_PN = "148";
"HSCL":   PN = "4"  !CDS_PN = "4";
"HSDA":   PN = "5"  !CDS_PN = "5";
"LBD||RSP_A_N":   PN = "86"  !CDS_PN = "86";
"LBS||RSP_B_N":   PN = "87"  !CDS_PN = "87";
"PAR_A":   PN = "74"  !CDS_PN = "74";
"PAR_B":   PN = "227"  !CDS_PN = "227";
"PWR_GOOD||FAIL_N":   PN = "147"  !CDS_PN = "147";
"RESET_N":   PN = "207"  !CDS_PN = "207";
"RFU0":   PN = "2"  !CDS_PN = "2";
"RFU1":   PN = "144"  !CDS_PN = "144";
"RFU2":   PN = "149"  !CDS_PN = "149";
"RFU3":   PN = "150"  !CDS_PN = "150";
"RFU4":   PN = "220"  !CDS_PN = "220";
"RFU5":   PN = "231"  !CDS_PN = "231";
"RFU6":   PN = "232"  !CDS_PN = "232";
"VIN_MGMT":   PN = "3"  !CDS_PN = "3";
BODY = "SCONN288_ADR50017P087CC","I180": LOCATION = "J24" #&CDS_LOCATION = "J24" &SEC = "3" #&CDS_SEC = "3";
"G1":   PN = "G1"  !CDS_PN = "G1";
"G2":   PN = "G2"  !CDS_PN = "G2";
"G3":   PN = "G3"  !CDS_PN = "G3";
"VIN_BULK0":   PN = "1"  !CDS_PN = "1";
"VIN_BULK1":   PN = "145"  !CDS_PN = "145";
"VIN_BULK2":   PN = "146"  !CDS_PN = "146";
"VSS0":   PN = "6"  !CDS_PN = "6";
"VSS1":   PN = "8"  !CDS_PN = "8";
"VSS2":   PN = "10"  !CDS_PN = "10";
"VSS3":   PN = "13"  !CDS_PN = "13";
"VSS4":   PN = "15"  !CDS_PN = "15";
"VSS5":   PN = "17"  !CDS_PN = "17";
"VSS6":   PN = "19"  !CDS_PN = "19";
"VSS7":   PN = "21"  !CDS_PN = "21";
"VSS8":   PN = "24"  !CDS_PN = "24";
"VSS9":   PN = "26"  !CDS_PN = "26";
"VSS10":   PN = "28"  !CDS_PN = "28";
"VSS11":   PN = "30"  !CDS_PN = "30";
"VSS12":   PN = "32"  !CDS_PN = "32";
"VSS13":   PN = "35"  !CDS_PN = "35";
"VSS14":   PN = "37"  !CDS_PN = "37";
"VSS15":   PN = "39"  !CDS_PN = "39";
"VSS16":   PN = "41"  !CDS_PN = "41";
"VSS17":   PN = "43"  !CDS_PN = "43";
"VSS18":   PN = "46"  !CDS_PN = "46";
"VSS19":   PN = "48"  !CDS_PN = "48";
"VSS20":   PN = "50"  !CDS_PN = "50";
"VSS21":   PN = "52"  !CDS_PN = "52";
"VSS22":   PN = "54"  !CDS_PN = "54";
"VSS23":   PN = "57"  !CDS_PN = "57";
"VSS24":   PN = "59"  !CDS_PN = "59";
"VSS25":   PN = "61"  !CDS_PN = "61";
"VSS26":   PN = "63"  !CDS_PN = "63";
"VSS27":   PN = "65"  !CDS_PN = "65";
"VSS28":   PN = "67"  !CDS_PN = "67";
"VSS29":   PN = "69"  !CDS_PN = "69";
"VSS30":   PN = "71"  !CDS_PN = "71";
"VSS31":   PN = "73"  !CDS_PN = "73";
"VSS32":   PN = "75"  !CDS_PN = "75";
"VSS33":   PN = "77"  !CDS_PN = "77";
"VSS34":   PN = "79"  !CDS_PN = "79";
"VSS35":   PN = "81"  !CDS_PN = "81";
"VSS36":   PN = "83"  !CDS_PN = "83";
"VSS37":   PN = "85"  !CDS_PN = "85";
"VSS38":   PN = "88"  !CDS_PN = "88";
"VSS39":   PN = "90"  !CDS_PN = "90";
"VSS40":   PN = "92"  !CDS_PN = "92";
"VSS41":   PN = "95"  !CDS_PN = "95";
"VSS42":   PN = "97"  !CDS_PN = "97";
"VSS43":   PN = "99"  !CDS_PN = "99";
"VSS44":   PN = "101"  !CDS_PN = "101";
"VSS45":   PN = "103"  !CDS_PN = "103";
"VSS46":   PN = "106"  !CDS_PN = "106";
"VSS47":   PN = "108"  !CDS_PN = "108";
"VSS48":   PN = "110"  !CDS_PN = "110";
"VSS49":   PN = "112"  !CDS_PN = "112";
"VSS50":   PN = "114"  !CDS_PN = "114";
"VSS51":   PN = "117"  !CDS_PN = "117";
"VSS52":   PN = "119"  !CDS_PN = "119";
"VSS53":   PN = "121"  !CDS_PN = "121";
"VSS54":   PN = "123"  !CDS_PN = "123";
"VSS55":   PN = "125"  !CDS_PN = "125";
"VSS56":   PN = "128"  !CDS_PN = "128";
"VSS57":   PN = "130"  !CDS_PN = "130";
"VSS58":   PN = "132"  !CDS_PN = "132";
"VSS59":   PN = "134"  !CDS_PN = "134";
"VSS60":   PN = "136"  !CDS_PN = "136";
"VSS61":   PN = "139"  !CDS_PN = "139";
"VSS62":   PN = "141"  !CDS_PN = "141";
"VSS63":   PN = "143"  !CDS_PN = "143";
"VSS64":   PN = "151"  !CDS_PN = "151";
"VSS65":   PN = "153"  !CDS_PN = "153";
"VSS66":   PN = "155"  !CDS_PN = "155";
"VSS67":   PN = "158"  !CDS_PN = "158";
"VSS68":   PN = "160"  !CDS_PN = "160";
"VSS69":   PN = "162"  !CDS_PN = "162";
"VSS70":   PN = "164"  !CDS_PN = "164";
"VSS71":   PN = "166"  !CDS_PN = "166";
"VSS72":   PN = "169"  !CDS_PN = "169";
"VSS73":   PN = "171"  !CDS_PN = "171";
"VSS74":   PN = "173"  !CDS_PN = "173";
"VSS75":   PN = "175"  !CDS_PN = "175";
"VSS76":   PN = "177"  !CDS_PN = "177";
"VSS77":   PN = "180"  !CDS_PN = "180";
"VSS78":   PN = "182"  !CDS_PN = "182";
"VSS79":   PN = "184"  !CDS_PN = "184";
"VSS80":   PN = "186"  !CDS_PN = "186";
"VSS81":   PN = "188"  !CDS_PN = "188";
"VSS82":   PN = "191"  !CDS_PN = "191";
"VSS83":   PN = "193"  !CDS_PN = "193";
"VSS84":   PN = "195"  !CDS_PN = "195";
"VSS85":   PN = "197"  !CDS_PN = "197";
"VSS86":   PN = "199"  !CDS_PN = "199";
"VSS87":   PN = "202"  !CDS_PN = "202";
"VSS88":   PN = "204"  !CDS_PN = "204";
"VSS89":   PN = "206"  !CDS_PN = "206";
"VSS90":   PN = "208"  !CDS_PN = "208";
"VSS91":   PN = "210"  !CDS_PN = "210";
"VSS92":   PN = "212"  !CDS_PN = "212";
"VSS93":   PN = "214"  !CDS_PN = "214";
"VSS94":   PN = "216"  !CDS_PN = "216";
"VSS95":   PN = "219"  !CDS_PN = "219";
"VSS96":   PN = "222"  !CDS_PN = "222";
"VSS97":   PN = "224"  !CDS_PN = "224";
"VSS98":   PN = "226"  !CDS_PN = "226";
"VSS99":   PN = "228"  !CDS_PN = "228";
"VSS100":   PN = "230"  !CDS_PN = "230";
"VSS101":   PN = "233"  !CDS_PN = "233";
"VSS102":   PN = "235"  !CDS_PN = "235";
"VSS103":   PN = "237"  !CDS_PN = "237";
"VSS104":   PN = "240"  !CDS_PN = "240";
"VSS105":   PN = "242"  !CDS_PN = "242";
"VSS106":   PN = "244"  !CDS_PN = "244";
"VSS107":   PN = "246"  !CDS_PN = "246";
"VSS108":   PN = "248"  !CDS_PN = "248";
"VSS109":   PN = "251"  !CDS_PN = "251";
"VSS110":   PN = "253"  !CDS_PN = "253";
"VSS111":   PN = "255"  !CDS_PN = "255";
"VSS112":   PN = "257"  !CDS_PN = "257";
"VSS113":   PN = "259"  !CDS_PN = "259";
"VSS114":   PN = "262"  !CDS_PN = "262";
"VSS115":   PN = "264"  !CDS_PN = "264";
"VSS116":   PN = "266"  !CDS_PN = "266";
"VSS117":   PN = "268"  !CDS_PN = "268";
"VSS118":   PN = "270"  !CDS_PN = "270";
"VSS119":   PN = "273"  !CDS_PN = "273";
"VSS120":   PN = "275"  !CDS_PN = "275";
"VSS121":   PN = "277"  !CDS_PN = "277";
"VSS122":   PN = "279"  !CDS_PN = "279";
"VSS123":   PN = "281"  !CDS_PN = "281";
"VSS124":   PN = "284"  !CDS_PN = "284";
"VSS125":   PN = "286"  !CDS_PN = "286";
"VSS126":   PN = "288"  !CDS_PN = "288";
BODY = "SCONN288_ADR50017P087CC","I181": #LOCATION = "J24" !CDS_LOCATION = "J24" &SEC = "2" #&CDS_SEC = "2";
"DQS0_A_C":   PN = "12"  !CDS_PN = "12";
"DQS0_A_T":   PN = "11"  !CDS_PN = "11";
"DQS0_B_C":   PN = "105"  !CDS_PN = "105";
"DQS0_B_T":   PN = "104"  !CDS_PN = "104";
"DQS1_A_C":   PN = "23"  !CDS_PN = "23";
"DQS1_A_T":   PN = "22"  !CDS_PN = "22";
"DQS1_B_C":   PN = "116"  !CDS_PN = "116";
"DQS1_B_T":   PN = "115"  !CDS_PN = "115";
"DQS2_A_C":   PN = "34"  !CDS_PN = "34";
"DQS2_A_T":   PN = "33"  !CDS_PN = "33";
"DQS2_B_C":   PN = "127"  !CDS_PN = "127";
"DQS2_B_T":   PN = "126"  !CDS_PN = "126";
"DQS3_A_C":   PN = "45"  !CDS_PN = "45";
"DQS3_A_T":   PN = "44"  !CDS_PN = "44";
"DQS3_B_C":   PN = "138"  !CDS_PN = "138";
"DQS3_B_T":   PN = "137"  !CDS_PN = "137";
"DQS4_A_C":   PN = "56"  !CDS_PN = "56";
"DQS4_A_T":   PN = "55"  !CDS_PN = "55";
"DQS4_B_C":   PN = "238"  !CDS_PN = "238";
"DQS4_B_T":   PN = "239"  !CDS_PN = "239";
"DQS5_A_C||TDQS5_A_C||DQS5_A_T||TDQS5_A_T":   PN = "156"  !CDS_PN = "156";
"DQS5_A_T||TDQS5_A_T":   PN = "157"  !CDS_PN = "157";
"DQS5_B_C||TDQS5_B_C":   PN = "249"  !CDS_PN = "249";
"DQS5_B_T||TDQS5_B_T":   PN = "250"  !CDS_PN = "250";
"DQS6_A_C||TDQS6_A_C||DQS6_A_T||TDQS6_A_T":   PN = "167"  !CDS_PN = "167";
"DQS6_A_T||TDQS6_A_T":   PN = "168"  !CDS_PN = "168";
"DQS6_B_C||TDQS6_B_C":   PN = "260"  !CDS_PN = "260";
"DQS6_B_T||TDQS6_B_T":   PN = "261"  !CDS_PN = "261";
"DQS7_A_C||TDQS7_A_C":   PN = "178"  !CDS_PN = "178";
"DQS7_A_T||TDQS7_A_T":   PN = "179"  !CDS_PN = "179";
"DQS7_B_C||TDQS7_B_C":   PN = "271"  !CDS_PN = "271";
"DQS7_B_T||TDQS7_B_T":   PN = "272"  !CDS_PN = "272";
"DQS8_A_C||TDQS8_A_C":   PN = "189"  !CDS_PN = "189";
"DQS8_A_T||TDQS8_A_T":   PN = "190"  !CDS_PN = "190";
"DQS8_B_C||TDQS8_B_C":   PN = "282"  !CDS_PN = "282";
"DQS8_B_T||TDQS8_B_T":   PN = "283"  !CDS_PN = "283";
"DQS9_A_C||TDQS9_A_C":   PN = "200"  !CDS_PN = "200";
"DQS9_A_T||TDQS9_A_T":   PN = "201"  !CDS_PN = "201";
"DQS9_B_C||TDQS9_B_C":   PN = "94"  !CDS_PN = "94";
"DQS9_B_T||TDQS9_B_T||DBI4_B_N":   PN = "93"  !CDS_PN = "93";
BODY = "Q_RES","I183": LOCATION = "R3898" #&CDS_LOCATION = "R3898" &SEC = "1" #&CDS_SEC = "1";
"A":   PN = "1"  !CDS_PN = "1";
"B":   PN = "2"  !CDS_PN = "2";
DRAWING = "@s9s_mb_2u_lib.s9s_mb_2u(sch_1):page106";
BODY = "Q_RES","I2": LOCATION = "R79" #&CDS_LOCATION = "R79" &SEC = "1" #&CDS_SEC = "1";
"A":   PN = "1"  !CDS_PN = "1";
"B":   PN = "2"  !CDS_PN = "2";
BODY = "Q_CAP","I122": LOCATION = "C93" #&CDS_LOCATION = "C93" &SEC = "1" #&CDS_SEC = "1";
"A":   PN = "1"  !CDS_PN = "1";
"B":   PN = "2"  !CDS_PN = "2";
BODY = "Q_CAP","I127": LOCATION = "C94" #&CDS_LOCATION = "C94" &SEC = "1" #&CDS_SEC = "1";
"A":   PN = "1"  !CDS_PN = "1";
"B":   PN = "2"  !CDS_PN = "2";
BODY = "Q_CAP","I130": LOCATION = "C95" #&CDS_LOCATION = "C95" &SEC = "1" #&CDS_SEC = "1";
"A":   PN = "1"  !CDS_PN = "1";
"B":   PN = "2"  !CDS_PN = "2";
BODY = "SCONN288_ADR50017P130CC","I178": LOCATION = "J25" #&CDS_LOCATION = "J25" &SEC = "3" #&CDS_SEC = "3";
"G1":   PN = "G1"  !CDS_PN = "G1";
"G2":   PN = "G2"  !CDS_PN = "G2";
"G3":   PN = "G3"  !CDS_PN = "G3";
"VIN_BULK0":   PN = "1"  !CDS_PN = "1";
"VIN_BULK1":   PN = "145"  !CDS_PN = "145";
"VIN_BULK2":   PN = "146"  !CDS_PN = "146";
"VSS0":   PN = "6"  !CDS_PN = "6";
"VSS1":   PN = "8"  !CDS_PN = "8";
"VSS2":   PN = "10"  !CDS_PN = "10";
"VSS3":   PN = "13"  !CDS_PN = "13";
"VSS4":   PN = "15"  !CDS_PN = "15";
"VSS5":   PN = "17"  !CDS_PN = "17";
"VSS6":   PN = "19"  !CDS_PN = "19";
"VSS7":   PN = "21"  !CDS_PN = "21";
"VSS8":   PN = "24"  !CDS_PN = "24";
"VSS9":   PN = "26"  !CDS_PN = "26";
"VSS10":   PN = "28"  !CDS_PN = "28";
"VSS11":   PN = "30"  !CDS_PN = "30";
"VSS12":   PN = "32"  !CDS_PN = "32";
"VSS13":   PN = "35"  !CDS_PN = "35";
"VSS14":   PN = "37"  !CDS_PN = "37";
"VSS15":   PN = "39"  !CDS_PN = "39";
"VSS16":   PN = "41"  !CDS_PN = "41";
"VSS17":   PN = "43"  !CDS_PN = "43";
"VSS18":   PN = "46"  !CDS_PN = "46";
"VSS19":   PN = "48"  !CDS_PN = "48";
"VSS20":   PN = "50"  !CDS_PN = "50";
"VSS21":   PN = "52"  !CDS_PN = "52";
"VSS22":   PN = "54"  !CDS_PN = "54";
"VSS23":   PN = "57"  !CDS_PN = "57";
"VSS24":   PN = "59"  !CDS_PN = "59";
"VSS25":   PN = "61"  !CDS_PN = "61";
"VSS26":   PN = "63"  !CDS_PN = "63";
"VSS27":   PN = "65"  !CDS_PN = "65";
"VSS28":   PN = "67"  !CDS_PN = "67";
"VSS29":   PN = "69"  !CDS_PN = "69";
"VSS30":   PN = "71"  !CDS_PN = "71";
"VSS31":   PN = "73"  !CDS_PN = "73";
"VSS32":   PN = "75"  !CDS_PN = "75";
"VSS33":   PN = "77"  !CDS_PN = "77";
"VSS34":   PN = "79"  !CDS_PN = "79";
"VSS35":   PN = "81"  !CDS_PN = "81";
"VSS36":   PN = "83"  !CDS_PN = "83";
"VSS37":   PN = "85"  !CDS_PN = "85";
"VSS38":   PN = "88"  !CDS_PN = "88";
"VSS39":   PN = "90"  !CDS_PN = "90";
"VSS40":   PN = "92"  !CDS_PN = "92";
"VSS41":   PN = "95"  !CDS_PN = "95";
"VSS42":   PN = "97"  !CDS_PN = "97";
"VSS43":   PN = "99"  !CDS_PN = "99";
"VSS44":   PN = "101"  !CDS_PN = "101";
"VSS45":   PN = "103"  !CDS_PN = "103";
"VSS46":   PN = "106"  !CDS_PN = "106";
"VSS47":   PN = "108"  !CDS_PN = "108";
"VSS48":   PN = "110"  !CDS_PN = "110";
"VSS49":   PN = "112"  !CDS_PN = "112";
"VSS50":   PN = "114"  !CDS_PN = "114";
"VSS51":   PN = "117"  !CDS_PN = "117";
"VSS52":   PN = "119"  !CDS_PN = "119";
"VSS53":   PN = "121"  !CDS_PN = "121";
"VSS54":   PN = "123"  !CDS_PN = "123";
"VSS55":   PN = "125"  !CDS_PN = "125";
"VSS56":   PN = "128"  !CDS_PN = "128";
"VSS57":   PN = "130"  !CDS_PN = "130";
"VSS58":   PN = "132"  !CDS_PN = "132";
"VSS59":   PN = "134"  !CDS_PN = "134";
"VSS60":   PN = "136"  !CDS_PN = "136";
"VSS61":   PN = "139"  !CDS_PN = "139";
"VSS62":   PN = "141"  !CDS_PN = "141";
"VSS63":   PN = "143"  !CDS_PN = "143";
"VSS64":   PN = "151"  !CDS_PN = "151";
"VSS65":   PN = "153"  !CDS_PN = "153";
"VSS66":   PN = "155"  !CDS_PN = "155";
"VSS67":   PN = "158"  !CDS_PN = "158";
"VSS68":   PN = "160"  !CDS_PN = "160";
"VSS69":   PN = "162"  !CDS_PN = "162";
"VSS70":   PN = "164"  !CDS_PN = "164";
"VSS71":   PN = "166"  !CDS_PN = "166";
"VSS72":   PN = "169"  !CDS_PN = "169";
"VSS73":   PN = "171"  !CDS_PN = "171";
"VSS74":   PN = "173"  !CDS_PN = "173";
"VSS75":   PN = "175"  !CDS_PN = "175";
"VSS76":   PN = "177"  !CDS_PN = "177";
"VSS77":   PN = "180"  !CDS_PN = "180";
"VSS78":   PN = "182"  !CDS_PN = "182";
"VSS79":   PN = "184"  !CDS_PN = "184";
"VSS80":   PN = "186"  !CDS_PN = "186";
"VSS81":   PN = "188"  !CDS_PN = "188";
"VSS82":   PN = "191"  !CDS_PN = "191";
"VSS83":   PN = "193"  !CDS_PN = "193";
"VSS84":   PN = "195"  !CDS_PN = "195";
"VSS85":   PN = "197"  !CDS_PN = "197";
"VSS86":   PN = "199"  !CDS_PN = "199";
"VSS87":   PN = "202"  !CDS_PN = "202";
"VSS88":   PN = "204"  !CDS_PN = "204";
"VSS89":   PN = "206"  !CDS_PN = "206";
"VSS90":   PN = "208"  !CDS_PN = "208";
"VSS91":   PN = "210"  !CDS_PN = "210";
"VSS92":   PN = "212"  !CDS_PN = "212";
"VSS93":   PN = "214"  !CDS_PN = "214";
"VSS94":   PN = "216"  !CDS_PN = "216";
"VSS95":   PN = "219"  !CDS_PN = "219";
"VSS96":   PN = "222"  !CDS_PN = "222";
"VSS97":   PN = "224"  !CDS_PN = "224";
"VSS98":   PN = "226"  !CDS_PN = "226";
"VSS99":   PN = "228"  !CDS_PN = "228";
"VSS100":   PN = "230"  !CDS_PN = "230";
"VSS101":   PN = "233"  !CDS_PN = "233";
"VSS102":   PN = "235"  !CDS_PN = "235";
"VSS103":   PN = "237"  !CDS_PN = "237";
"VSS104":   PN = "240"  !CDS_PN = "240";
"VSS105":   PN = "242"  !CDS_PN = "242";
"VSS106":   PN = "244"  !CDS_PN = "244";
"VSS107":   PN = "246"  !CDS_PN = "246";
"VSS108":   PN = "248"  !CDS_PN = "248";
"VSS109":   PN = "251"  !CDS_PN = "251";
"VSS110":   PN = "253"  !CDS_PN = "253";
"VSS111":   PN = "255"  !CDS_PN = "255";
"VSS112":   PN = "257"  !CDS_PN = "257";
"VSS113":   PN = "259"  !CDS_PN = "259";
"VSS114":   PN = "262"  !CDS_PN = "262";
"VSS115":   PN = "264"  !CDS_PN = "264";
"VSS116":   PN = "266"  !CDS_PN = "266";
"VSS117":   PN = "268"  !CDS_PN = "268";
"VSS118":   PN = "270"  !CDS_PN = "270";
"VSS119":   PN = "273"  !CDS_PN = "273";
"VSS120":   PN = "275"  !CDS_PN = "275";
"VSS121":   PN = "277"  !CDS_PN = "277";
"VSS122":   PN = "279"  !CDS_PN = "279";
"VSS123":   PN = "281"  !CDS_PN = "281";
"VSS124":   PN = "284"  !CDS_PN = "284";
"VSS125":   PN = "286"  !CDS_PN = "286";
"VSS126":   PN = "288"  !CDS_PN = "288";
BODY = "SCONN288_ADR50017P130CC","I180": LOCATION = "J25" #&CDS_LOCATION = "J25" &SEC = "1" #&CDS_SEC = "1";
"ALERT_N":   PN = "62"  !CDS_PN = "62";
"CA0_A":   PN = "66"  !CDS_PN = "66";
"CA0_B":   PN = "76"  !CDS_PN = "76";
"CA1_A":   PN = "211"  !CDS_PN = "211";
"CA1_B":   PN = "221"  !CDS_PN = "221";
"CA2_A":   PN = "68"  !CDS_PN = "68";
"CA2_B":   PN = "78"  !CDS_PN = "78";
"CA3_A":   PN = "213"  !CDS_PN = "213";
"CA3_B":   PN = "223"  !CDS_PN = "223";
"CA4_A":   PN = "70"  !CDS_PN = "70";
"CA4_B":   PN = "80"  !CDS_PN = "80";
"CA5_A":   PN = "215"  !CDS_PN = "215";
"CA5_B":   PN = "225"  !CDS_PN = "225";
"CA6_A":   PN = "72"  !CDS_PN = "72";
"CA6_B":   PN = "82"  !CDS_PN = "82";
"CB0_A":   PN = "51"  !CDS_PN = "51";
"CB0_B":   PN = "96"  !CDS_PN = "96";
"CB1_A":   PN = "53"  !CDS_PN = "53";
"CB1_B":   PN = "98"  !CDS_PN = "98";
"CB2_A":   PN = "196"  !CDS_PN = "196";
"CB2_B":   PN = "241"  !CDS_PN = "241";
"CB3_A":   PN = "198"  !CDS_PN = "198";
"CB3_B":   PN = "243"  !CDS_PN = "243";
"CB4_A":   PN = "58"  !CDS_PN = "58";
"CB4_B":   PN = "89"  !CDS_PN = "89";
"CB5_A":   PN = "60"  !CDS_PN = "60";
"CB5_B":   PN = "91"  !CDS_PN = "91";
"CB6_A":   PN = "203"  !CDS_PN = "203";
"CB6_B":   PN = "234"  !CDS_PN = "234";
"CB7_A":   PN = "205"  !CDS_PN = "205";
"CB7_B":   PN = "236"  !CDS_PN = "236";
"CK_C":   PN = "218"  !CDS_PN = "218";
"CK_T":   PN = "217"  !CDS_PN = "217";
"CS0_A_N":   PN = "64"  !CDS_PN = "64";
"CS0_B_N":   PN = "84"  !CDS_PN = "84";
"CS1_A_N":   PN = "209"  !CDS_PN = "209";
"CS1_B_N":   PN = "229"  !CDS_PN = "229";
"DQ0_A":   PN = "7"  !CDS_PN = "7";
"DQ0_B":   PN = "100"  !CDS_PN = "100";
"DQ1_A":   PN = "9"  !CDS_PN = "9";
"DQ1_B":   PN = "102"  !CDS_PN = "102";
"DQ2_A":   PN = "152"  !CDS_PN = "152";
"DQ2_B":   PN = "245"  !CDS_PN = "245";
"DQ3_A":   PN = "154"  !CDS_PN = "154";
"DQ3_B":   PN = "247"  !CDS_PN = "247";
"DQ4_A":   PN = "14"  !CDS_PN = "14";
"DQ4_B":   PN = "107"  !CDS_PN = "107";
"DQ5_A":   PN = "16"  !CDS_PN = "16";
"DQ5_B":   PN = "109"  !CDS_PN = "109";
"DQ6_A":   PN = "159"  !CDS_PN = "159";
"DQ6_B":   PN = "252"  !CDS_PN = "252";
"DQ7_A":   PN = "161"  !CDS_PN = "161";
"DQ7_B":   PN = "254"  !CDS_PN = "254";
"DQ8_A":   PN = "18"  !CDS_PN = "18";
"DQ8_B":   PN = "111"  !CDS_PN = "111";
"DQ9_A":   PN = "20"  !CDS_PN = "20";
"DQ9_B":   PN = "113"  !CDS_PN = "113";
"DQ10_A":   PN = "163"  !CDS_PN = "163";
"DQ10_B":   PN = "256"  !CDS_PN = "256";
"DQ11_A":   PN = "165"  !CDS_PN = "165";
"DQ11_B":   PN = "258"  !CDS_PN = "258";
"DQ12_A":   PN = "25"  !CDS_PN = "25";
"DQ12_B":   PN = "118"  !CDS_PN = "118";
"DQ13_A":   PN = "27"  !CDS_PN = "27";
"DQ13_B":   PN = "120"  !CDS_PN = "120";
"DQ14_A":   PN = "170"  !CDS_PN = "170";
"DQ14_B":   PN = "263"  !CDS_PN = "263";
"DQ15_A":   PN = "172"  !CDS_PN = "172";
"DQ15_B":   PN = "265"  !CDS_PN = "265";
"DQ16_A":   PN = "29"  !CDS_PN = "29";
"DQ16_B":   PN = "122"  !CDS_PN = "122";
"DQ17_A":   PN = "31"  !CDS_PN = "31";
"DQ17_B":   PN = "124"  !CDS_PN = "124";
"DQ18_A":   PN = "174"  !CDS_PN = "174";
"DQ18_B":   PN = "267"  !CDS_PN = "267";
"DQ19_A":   PN = "176"  !CDS_PN = "176";
"DQ19_B":   PN = "269"  !CDS_PN = "269";
"DQ20_A":   PN = "36"  !CDS_PN = "36";
"DQ20_B":   PN = "129"  !CDS_PN = "129";
"DQ21_A":   PN = "38"  !CDS_PN = "38";
"DQ21_B":   PN = "131"  !CDS_PN = "131";
"DQ22_A":   PN = "181"  !CDS_PN = "181";
"DQ22_B":   PN = "274"  !CDS_PN = "274";
"DQ23_A":   PN = "183"  !CDS_PN = "183";
"DQ23_B":   PN = "276"  !CDS_PN = "276";
"DQ24_A":   PN = "40"  !CDS_PN = "40";
"DQ24_B":   PN = "133"  !CDS_PN = "133";
"DQ25_A":   PN = "42"  !CDS_PN = "42";
"DQ25_B":   PN = "135"  !CDS_PN = "135";
"DQ26_A":   PN = "185"  !CDS_PN = "185";
"DQ26_B":   PN = "278"  !CDS_PN = "278";
"DQ27_A":   PN = "187"  !CDS_PN = "187";
"DQ27_B":   PN = "280"  !CDS_PN = "280";
"DQ28_A":   PN = "47"  !CDS_PN = "47";
"DQ28_B":   PN = "140"  !CDS_PN = "140";
"DQ29_A":   PN = "49"  !CDS_PN = "49";
"DQ29_B":   PN = "142"  !CDS_PN = "142";
"DQ30_A":   PN = "192"  !CDS_PN = "192";
"DQ30_B":   PN = "285"  !CDS_PN = "285";
"DQ31_A":   PN = "194"  !CDS_PN = "194";
"DQ31_B":   PN = "287"  !CDS_PN = "287";
"HSA":   PN = "148"  !CDS_PN = "148";
"HSCL":   PN = "4"  !CDS_PN = "4";
"HSDA":   PN = "5"  !CDS_PN = "5";
"LBD||RSP_A_N":   PN = "86"  !CDS_PN = "86";
"LBS||RSP_B_N":   PN = "87"  !CDS_PN = "87";
"PAR_A":   PN = "74"  !CDS_PN = "74";
"PAR_B":   PN = "227"  !CDS_PN = "227";
"PWR_GOOD||FAIL_N":   PN = "147"  !CDS_PN = "147";
"RESET_N":   PN = "207"  !CDS_PN = "207";
"RFU0":   PN = "2"  !CDS_PN = "2";
"RFU1":   PN = "144"  !CDS_PN = "144";
"RFU2":   PN = "149"  !CDS_PN = "149";
"RFU3":   PN = "150"  !CDS_PN = "150";
"RFU4":   PN = "220"  !CDS_PN = "220";
"RFU5":   PN = "231"  !CDS_PN = "231";
"RFU6":   PN = "232"  !CDS_PN = "232";
"VIN_MGMT":   PN = "3"  !CDS_PN = "3";
BODY = "SCONN288_ADR50017P130CC","I181": #LOCATION = "J25" !CDS_LOCATION = "J25" &SEC = "2" #&CDS_SEC = "2";
"DQS0_A_C":   PN = "12"  !CDS_PN = "12";
"DQS0_A_T":   PN = "11"  !CDS_PN = "11";
"DQS0_B_C":   PN = "105"  !CDS_PN = "105";
"DQS0_B_T":   PN = "104"  !CDS_PN = "104";
"DQS1_A_C":   PN = "23"  !CDS_PN = "23";
"DQS1_A_T":   PN = "22"  !CDS_PN = "22";
"DQS1_B_C":   PN = "116"  !CDS_PN = "116";
"DQS1_B_T":   PN = "115"  !CDS_PN = "115";
"DQS2_A_C":   PN = "34"  !CDS_PN = "34";
"DQS2_A_T":   PN = "33"  !CDS_PN = "33";
"DQS2_B_C":   PN = "127"  !CDS_PN = "127";
"DQS2_B_T":   PN = "126"  !CDS_PN = "126";
"DQS3_A_C":   PN = "45"  !CDS_PN = "45";
"DQS3_A_T":   PN = "44"  !CDS_PN = "44";
"DQS3_B_C":   PN = "138"  !CDS_PN = "138";
"DQS3_B_T":   PN = "137"  !CDS_PN = "137";
"DQS4_A_C":   PN = "56"  !CDS_PN = "56";
"DQS4_A_T":   PN = "55"  !CDS_PN = "55";
"DQS4_B_C":   PN = "238"  !CDS_PN = "238";
"DQS4_B_T":   PN = "239"  !CDS_PN = "239";
"DQS5_A_C||TDQS5_A_C||DQS5_A_T||TDQS5_A_T":   PN = "156"  !CDS_PN = "156";
"DQS5_A_T||TDQS5_A_T":   PN = "157"  !CDS_PN = "157";
"DQS5_B_C||TDQS5_B_C":   PN = "249"  !CDS_PN = "249";
"DQS5_B_T||TDQS5_B_T":   PN = "250"  !CDS_PN = "250";
"DQS6_A_C||TDQS6_A_C||DQS6_A_T||TDQS6_A_T":   PN = "167"  !CDS_PN = "167";
"DQS6_A_T||TDQS6_A_T":   PN = "168"  !CDS_PN = "168";
"DQS6_B_C||TDQS6_B_C":   PN = "260"  !CDS_PN = "260";
"DQS6_B_T||TDQS6_B_T":   PN = "261"  !CDS_PN = "261";
"DQS7_A_C||TDQS7_A_C":   PN = "178"  !CDS_PN = "178";
"DQS7_A_T||TDQS7_A_T":   PN = "179"  !CDS_PN = "179";
"DQS7_B_C||TDQS7_B_C":   PN = "271"  !CDS_PN = "271";
"DQS7_B_T||TDQS7_B_T":   PN = "272"  !CDS_PN = "272";
"DQS8_A_C||TDQS8_A_C":   PN = "189"  !CDS_PN = "189";
"DQS8_A_T||TDQS8_A_T":   PN = "190"  !CDS_PN = "190";
"DQS8_B_C||TDQS8_B_C":   PN = "282"  !CDS_PN = "282";
"DQS8_B_T||TDQS8_B_T":   PN = "283"  !CDS_PN = "283";
"DQS9_A_C||TDQS9_A_C":   PN = "200"  !CDS_PN = "200";
"DQS9_A_T||TDQS9_A_T":   PN = "201"  !CDS_PN = "201";
"DQS9_B_C||TDQS9_B_C":   PN = "94"  !CDS_PN = "94";
"DQS9_B_T||TDQS9_B_T||DBI4_B_N":   PN = "93"  !CDS_PN = "93";
BODY = "Q_RES","I183": LOCATION = "R3899" #&CDS_LOCATION = "R3899" &SEC = "1" #&CDS_SEC = "1";
"A":   PN = "1"  !CDS_PN = "1";
"B":   PN = "2"  !CDS_PN = "2";
DRAWING = "@s9s_mb_2u_lib.s9s_mb_2u(sch_1):page107";
BODY = "Q_RES","I2": LOCATION = "R78" #&CDS_LOCATION = "R78" &SEC = "1" #&CDS_SEC = "1";
"A":   PN = "1"  !CDS_PN = "1";
"B":   PN = "2"  !CDS_PN = "2";
BODY = "Q_CAP","I122": LOCATION = "C90" #&CDS_LOCATION = "C90" &SEC = "1" #&CDS_SEC = "1";
"A":   PN = "1"  !CDS_PN = "1";
"B":   PN = "2"  !CDS_PN = "2";
BODY = "Q_CAP","I126": LOCATION = "C91" #&CDS_LOCATION = "C91" &SEC = "1" #&CDS_SEC = "1";
"A":   PN = "1"  !CDS_PN = "1";
"B":   PN = "2"  !CDS_PN = "2";
BODY = "Q_CAP","I128": LOCATION = "C92" #&CDS_LOCATION = "C92" &SEC = "1" #&CDS_SEC = "1";
"A":   PN = "1"  !CDS_PN = "1";
"B":   PN = "2"  !CDS_PN = "2";
BODY = "SCONN288_ADR50017P087CC","I179": LOCATION = "J26" #&CDS_LOCATION = "J26" &SEC = "3" #&CDS_SEC = "3";
"G1":   PN = "G1"  !CDS_PN = "G1";
"G2":   PN = "G2"  !CDS_PN = "G2";
"G3":   PN = "G3"  !CDS_PN = "G3";
"VIN_BULK0":   PN = "1"  !CDS_PN = "1";
"VIN_BULK1":   PN = "145"  !CDS_PN = "145";
"VIN_BULK2":   PN = "146"  !CDS_PN = "146";
"VSS0":   PN = "6"  !CDS_PN = "6";
"VSS1":   PN = "8"  !CDS_PN = "8";
"VSS2":   PN = "10"  !CDS_PN = "10";
"VSS3":   PN = "13"  !CDS_PN = "13";
"VSS4":   PN = "15"  !CDS_PN = "15";
"VSS5":   PN = "17"  !CDS_PN = "17";
"VSS6":   PN = "19"  !CDS_PN = "19";
"VSS7":   PN = "21"  !CDS_PN = "21";
"VSS8":   PN = "24"  !CDS_PN = "24";
"VSS9":   PN = "26"  !CDS_PN = "26";
"VSS10":   PN = "28"  !CDS_PN = "28";
"VSS11":   PN = "30"  !CDS_PN = "30";
"VSS12":   PN = "32"  !CDS_PN = "32";
"VSS13":   PN = "35"  !CDS_PN = "35";
"VSS14":   PN = "37"  !CDS_PN = "37";
"VSS15":   PN = "39"  !CDS_PN = "39";
"VSS16":   PN = "41"  !CDS_PN = "41";
"VSS17":   PN = "43"  !CDS_PN = "43";
"VSS18":   PN = "46"  !CDS_PN = "46";
"VSS19":   PN = "48"  !CDS_PN = "48";
"VSS20":   PN = "50"  !CDS_PN = "50";
"VSS21":   PN = "52"  !CDS_PN = "52";
"VSS22":   PN = "54"  !CDS_PN = "54";
"VSS23":   PN = "57"  !CDS_PN = "57";
"VSS24":   PN = "59"  !CDS_PN = "59";
"VSS25":   PN = "61"  !CDS_PN = "61";
"VSS26":   PN = "63"  !CDS_PN = "63";
"VSS27":   PN = "65"  !CDS_PN = "65";
"VSS28":   PN = "67"  !CDS_PN = "67";
"VSS29":   PN = "69"  !CDS_PN = "69";
"VSS30":   PN = "71"  !CDS_PN = "71";
"VSS31":   PN = "73"  !CDS_PN = "73";
"VSS32":   PN = "75"  !CDS_PN = "75";
"VSS33":   PN = "77"  !CDS_PN = "77";
"VSS34":   PN = "79"  !CDS_PN = "79";
"VSS35":   PN = "81"  !CDS_PN = "81";
"VSS36":   PN = "83"  !CDS_PN = "83";
"VSS37":   PN = "85"  !CDS_PN = "85";
"VSS38":   PN = "88"  !CDS_PN = "88";
"VSS39":   PN = "90"  !CDS_PN = "90";
"VSS40":   PN = "92"  !CDS_PN = "92";
"VSS41":   PN = "95"  !CDS_PN = "95";
"VSS42":   PN = "97"  !CDS_PN = "97";
"VSS43":   PN = "99"  !CDS_PN = "99";
"VSS44":   PN = "101"  !CDS_PN = "101";
"VSS45":   PN = "103"  !CDS_PN = "103";
"VSS46":   PN = "106"  !CDS_PN = "106";
"VSS47":   PN = "108"  !CDS_PN = "108";
"VSS48":   PN = "110"  !CDS_PN = "110";
"VSS49":   PN = "112"  !CDS_PN = "112";
"VSS50":   PN = "114"  !CDS_PN = "114";
"VSS51":   PN = "117"  !CDS_PN = "117";
"VSS52":   PN = "119"  !CDS_PN = "119";
"VSS53":   PN = "121"  !CDS_PN = "121";
"VSS54":   PN = "123"  !CDS_PN = "123";
"VSS55":   PN = "125"  !CDS_PN = "125";
"VSS56":   PN = "128"  !CDS_PN = "128";
"VSS57":   PN = "130"  !CDS_PN = "130";
"VSS58":   PN = "132"  !CDS_PN = "132";
"VSS59":   PN = "134"  !CDS_PN = "134";
"VSS60":   PN = "136"  !CDS_PN = "136";
"VSS61":   PN = "139"  !CDS_PN = "139";
"VSS62":   PN = "141"  !CDS_PN = "141";
"VSS63":   PN = "143"  !CDS_PN = "143";
"VSS64":   PN = "151"  !CDS_PN = "151";
"VSS65":   PN = "153"  !CDS_PN = "153";
"VSS66":   PN = "155"  !CDS_PN = "155";
"VSS67":   PN = "158"  !CDS_PN = "158";
"VSS68":   PN = "160"  !CDS_PN = "160";
"VSS69":   PN = "162"  !CDS_PN = "162";
"VSS70":   PN = "164"  !CDS_PN = "164";
"VSS71":   PN = "166"  !CDS_PN = "166";
"VSS72":   PN = "169"  !CDS_PN = "169";
"VSS73":   PN = "171"  !CDS_PN = "171";
"VSS74":   PN = "173"  !CDS_PN = "173";
"VSS75":   PN = "175"  !CDS_PN = "175";
"VSS76":   PN = "177"  !CDS_PN = "177";
"VSS77":   PN = "180"  !CDS_PN = "180";
"VSS78":   PN = "182"  !CDS_PN = "182";
"VSS79":   PN = "184"  !CDS_PN = "184";
"VSS80":   PN = "186"  !CDS_PN = "186";
"VSS81":   PN = "188"  !CDS_PN = "188";
"VSS82":   PN = "191"  !CDS_PN = "191";
"VSS83":   PN = "193"  !CDS_PN = "193";
"VSS84":   PN = "195"  !CDS_PN = "195";
"VSS85":   PN = "197"  !CDS_PN = "197";
"VSS86":   PN = "199"  !CDS_PN = "199";
"VSS87":   PN = "202"  !CDS_PN = "202";
"VSS88":   PN = "204"  !CDS_PN = "204";
"VSS89":   PN = "206"  !CDS_PN = "206";
"VSS90":   PN = "208"  !CDS_PN = "208";
"VSS91":   PN = "210"  !CDS_PN = "210";
"VSS92":   PN = "212"  !CDS_PN = "212";
"VSS93":   PN = "214"  !CDS_PN = "214";
"VSS94":   PN = "216"  !CDS_PN = "216";
"VSS95":   PN = "219"  !CDS_PN = "219";
"VSS96":   PN = "222"  !CDS_PN = "222";
"VSS97":   PN = "224"  !CDS_PN = "224";
"VSS98":   PN = "226"  !CDS_PN = "226";
"VSS99":   PN = "228"  !CDS_PN = "228";
"VSS100":   PN = "230"  !CDS_PN = "230";
"VSS101":   PN = "233"  !CDS_PN = "233";
"VSS102":   PN = "235"  !CDS_PN = "235";
"VSS103":   PN = "237"  !CDS_PN = "237";
"VSS104":   PN = "240"  !CDS_PN = "240";
"VSS105":   PN = "242"  !CDS_PN = "242";
"VSS106":   PN = "244"  !CDS_PN = "244";
"VSS107":   PN = "246"  !CDS_PN = "246";
"VSS108":   PN = "248"  !CDS_PN = "248";
"VSS109":   PN = "251"  !CDS_PN = "251";
"VSS110":   PN = "253"  !CDS_PN = "253";
"VSS111":   PN = "255"  !CDS_PN = "255";
"VSS112":   PN = "257"  !CDS_PN = "257";
"VSS113":   PN = "259"  !CDS_PN = "259";
"VSS114":   PN = "262"  !CDS_PN = "262";
"VSS115":   PN = "264"  !CDS_PN = "264";
"VSS116":   PN = "266"  !CDS_PN = "266";
"VSS117":   PN = "268"  !CDS_PN = "268";
"VSS118":   PN = "270"  !CDS_PN = "270";
"VSS119":   PN = "273"  !CDS_PN = "273";
"VSS120":   PN = "275"  !CDS_PN = "275";
"VSS121":   PN = "277"  !CDS_PN = "277";
"VSS122":   PN = "279"  !CDS_PN = "279";
"VSS123":   PN = "281"  !CDS_PN = "281";
"VSS124":   PN = "284"  !CDS_PN = "284";
"VSS125":   PN = "286"  !CDS_PN = "286";
"VSS126":   PN = "288"  !CDS_PN = "288";
BODY = "SCONN288_ADR50017P087CC","I180": LOCATION = "J26" #&CDS_LOCATION = "J26" &SEC = "1" #&CDS_SEC = "1";
"ALERT_N":   PN = "62"  !CDS_PN = "62";
"CA0_A":   PN = "66"  !CDS_PN = "66";
"CA0_B":   PN = "76"  !CDS_PN = "76";
"CA1_A":   PN = "211"  !CDS_PN = "211";
"CA1_B":   PN = "221"  !CDS_PN = "221";
"CA2_A":   PN = "68"  !CDS_PN = "68";
"CA2_B":   PN = "78"  !CDS_PN = "78";
"CA3_A":   PN = "213"  !CDS_PN = "213";
"CA3_B":   PN = "223"  !CDS_PN = "223";
"CA4_A":   PN = "70"  !CDS_PN = "70";
"CA4_B":   PN = "80"  !CDS_PN = "80";
"CA5_A":   PN = "215"  !CDS_PN = "215";
"CA5_B":   PN = "225"  !CDS_PN = "225";
"CA6_A":   PN = "72"  !CDS_PN = "72";
"CA6_B":   PN = "82"  !CDS_PN = "82";
"CB0_A":   PN = "51"  !CDS_PN = "51";
"CB0_B":   PN = "96"  !CDS_PN = "96";
"CB1_A":   PN = "53"  !CDS_PN = "53";
"CB1_B":   PN = "98"  !CDS_PN = "98";
"CB2_A":   PN = "196"  !CDS_PN = "196";
"CB2_B":   PN = "241"  !CDS_PN = "241";
"CB3_A":   PN = "198"  !CDS_PN = "198";
"CB3_B":   PN = "243"  !CDS_PN = "243";
"CB4_A":   PN = "58"  !CDS_PN = "58";
"CB4_B":   PN = "89"  !CDS_PN = "89";
"CB5_A":   PN = "60"  !CDS_PN = "60";
"CB5_B":   PN = "91"  !CDS_PN = "91";
"CB6_A":   PN = "203"  !CDS_PN = "203";
"CB6_B":   PN = "234"  !CDS_PN = "234";
"CB7_A":   PN = "205"  !CDS_PN = "205";
"CB7_B":   PN = "236"  !CDS_PN = "236";
"CK_C":   PN = "218"  !CDS_PN = "218";
"CK_T":   PN = "217"  !CDS_PN = "217";
"CS0_A_N":   PN = "64"  !CDS_PN = "64";
"CS0_B_N":   PN = "84"  !CDS_PN = "84";
"CS1_A_N":   PN = "209"  !CDS_PN = "209";
"CS1_B_N":   PN = "229"  !CDS_PN = "229";
"DQ0_A":   PN = "7"  !CDS_PN = "7";
"DQ0_B":   PN = "100"  !CDS_PN = "100";
"DQ1_A":   PN = "9"  !CDS_PN = "9";
"DQ1_B":   PN = "102"  !CDS_PN = "102";
"DQ2_A":   PN = "152"  !CDS_PN = "152";
"DQ2_B":   PN = "245"  !CDS_PN = "245";
"DQ3_A":   PN = "154"  !CDS_PN = "154";
"DQ3_B":   PN = "247"  !CDS_PN = "247";
"DQ4_A":   PN = "14"  !CDS_PN = "14";
"DQ4_B":   PN = "107"  !CDS_PN = "107";
"DQ5_A":   PN = "16"  !CDS_PN = "16";
"DQ5_B":   PN = "109"  !CDS_PN = "109";
"DQ6_A":   PN = "159"  !CDS_PN = "159";
"DQ6_B":   PN = "252"  !CDS_PN = "252";
"DQ7_A":   PN = "161"  !CDS_PN = "161";
"DQ7_B":   PN = "254"  !CDS_PN = "254";
"DQ8_A":   PN = "18"  !CDS_PN = "18";
"DQ8_B":   PN = "111"  !CDS_PN = "111";
"DQ9_A":   PN = "20"  !CDS_PN = "20";
"DQ9_B":   PN = "113"  !CDS_PN = "113";
"DQ10_A":   PN = "163"  !CDS_PN = "163";
"DQ10_B":   PN = "256"  !CDS_PN = "256";
"DQ11_A":   PN = "165"  !CDS_PN = "165";
"DQ11_B":   PN = "258"  !CDS_PN = "258";
"DQ12_A":   PN = "25"  !CDS_PN = "25";
"DQ12_B":   PN = "118"  !CDS_PN = "118";
"DQ13_A":   PN = "27"  !CDS_PN = "27";
"DQ13_B":   PN = "120"  !CDS_PN = "120";
"DQ14_A":   PN = "170"  !CDS_PN = "170";
"DQ14_B":   PN = "263"  !CDS_PN = "263";
"DQ15_A":   PN = "172"  !CDS_PN = "172";
"DQ15_B":   PN = "265"  !CDS_PN = "265";
"DQ16_A":   PN = "29"  !CDS_PN = "29";
"DQ16_B":   PN = "122"  !CDS_PN = "122";
"DQ17_A":   PN = "31"  !CDS_PN = "31";
"DQ17_B":   PN = "124"  !CDS_PN = "124";
"DQ18_A":   PN = "174"  !CDS_PN = "174";
"DQ18_B":   PN = "267"  !CDS_PN = "267";
"DQ19_A":   PN = "176"  !CDS_PN = "176";
"DQ19_B":   PN = "269"  !CDS_PN = "269";
"DQ20_A":   PN = "36"  !CDS_PN = "36";
"DQ20_B":   PN = "129"  !CDS_PN = "129";
"DQ21_A":   PN = "38"  !CDS_PN = "38";
"DQ21_B":   PN = "131"  !CDS_PN = "131";
"DQ22_A":   PN = "181"  !CDS_PN = "181";
"DQ22_B":   PN = "274"  !CDS_PN = "274";
"DQ23_A":   PN = "183"  !CDS_PN = "183";
"DQ23_B":   PN = "276"  !CDS_PN = "276";
"DQ24_A":   PN = "40"  !CDS_PN = "40";
"DQ24_B":   PN = "133"  !CDS_PN = "133";
"DQ25_A":   PN = "42"  !CDS_PN = "42";
"DQ25_B":   PN = "135"  !CDS_PN = "135";
"DQ26_A":   PN = "185"  !CDS_PN = "185";
"DQ26_B":   PN = "278"  !CDS_PN = "278";
"DQ27_A":   PN = "187"  !CDS_PN = "187";
"DQ27_B":   PN = "280"  !CDS_PN = "280";
"DQ28_A":   PN = "47"  !CDS_PN = "47";
"DQ28_B":   PN = "140"  !CDS_PN = "140";
"DQ29_A":   PN = "49"  !CDS_PN = "49";
"DQ29_B":   PN = "142"  !CDS_PN = "142";
"DQ30_A":   PN = "192"  !CDS_PN = "192";
"DQ30_B":   PN = "285"  !CDS_PN = "285";
"DQ31_A":   PN = "194"  !CDS_PN = "194";
"DQ31_B":   PN = "287"  !CDS_PN = "287";
"HSA":   PN = "148"  !CDS_PN = "148";
"HSCL":   PN = "4"  !CDS_PN = "4";
"HSDA":   PN = "5"  !CDS_PN = "5";
"LBD||RSP_A_N":   PN = "86"  !CDS_PN = "86";
"LBS||RSP_B_N":   PN = "87"  !CDS_PN = "87";
"PAR_A":   PN = "74"  !CDS_PN = "74";
"PAR_B":   PN = "227"  !CDS_PN = "227";
"PWR_GOOD||FAIL_N":   PN = "147"  !CDS_PN = "147";
"RESET_N":   PN = "207"  !CDS_PN = "207";
"RFU0":   PN = "2"  !CDS_PN = "2";
"RFU1":   PN = "144"  !CDS_PN = "144";
"RFU2":   PN = "149"  !CDS_PN = "149";
"RFU3":   PN = "150"  !CDS_PN = "150";
"RFU4":   PN = "220"  !CDS_PN = "220";
"RFU5":   PN = "231"  !CDS_PN = "231";
"RFU6":   PN = "232"  !CDS_PN = "232";
"VIN_MGMT":   PN = "3"  !CDS_PN = "3";
BODY = "SCONN288_ADR50017P087CC","I181": #LOCATION = "J26" !CDS_LOCATION = "J26" &SEC = "2" #&CDS_SEC = "2";
"DQS0_A_C":   PN = "12"  !CDS_PN = "12";
"DQS0_A_T":   PN = "11"  !CDS_PN = "11";
"DQS0_B_C":   PN = "105"  !CDS_PN = "105";
"DQS0_B_T":   PN = "104"  !CDS_PN = "104";
"DQS1_A_C":   PN = "23"  !CDS_PN = "23";
"DQS1_A_T":   PN = "22"  !CDS_PN = "22";
"DQS1_B_C":   PN = "116"  !CDS_PN = "116";
"DQS1_B_T":   PN = "115"  !CDS_PN = "115";
"DQS2_A_C":   PN = "34"  !CDS_PN = "34";
"DQS2_A_T":   PN = "33"  !CDS_PN = "33";
"DQS2_B_C":   PN = "127"  !CDS_PN = "127";
"DQS2_B_T":   PN = "126"  !CDS_PN = "126";
"DQS3_A_C":   PN = "45"  !CDS_PN = "45";
"DQS3_A_T":   PN = "44"  !CDS_PN = "44";
"DQS3_B_C":   PN = "138"  !CDS_PN = "138";
"DQS3_B_T":   PN = "137"  !CDS_PN = "137";
"DQS4_A_C":   PN = "56"  !CDS_PN = "56";
"DQS4_A_T":   PN = "55"  !CDS_PN = "55";
"DQS4_B_C":   PN = "238"  !CDS_PN = "238";
"DQS4_B_T":   PN = "239"  !CDS_PN = "239";
"DQS5_A_C||TDQS5_A_C||DQS5_A_T||TDQS5_A_T":   PN = "156"  !CDS_PN = "156";
"DQS5_A_T||TDQS5_A_T":   PN = "157"  !CDS_PN = "157";
"DQS5_B_C||TDQS5_B_C":   PN = "249"  !CDS_PN = "249";
"DQS5_B_T||TDQS5_B_T":   PN = "250"  !CDS_PN = "250";
"DQS6_A_C||TDQS6_A_C||DQS6_A_T||TDQS6_A_T":   PN = "167"  !CDS_PN = "167";
"DQS6_A_T||TDQS6_A_T":   PN = "168"  !CDS_PN = "168";
"DQS6_B_C||TDQS6_B_C":   PN = "260"  !CDS_PN = "260";
"DQS6_B_T||TDQS6_B_T":   PN = "261"  !CDS_PN = "261";
"DQS7_A_C||TDQS7_A_C":   PN = "178"  !CDS_PN = "178";
"DQS7_A_T||TDQS7_A_T":   PN = "179"  !CDS_PN = "179";
"DQS7_B_C||TDQS7_B_C":   PN = "271"  !CDS_PN = "271";
"DQS7_B_T||TDQS7_B_T":   PN = "272"  !CDS_PN = "272";
"DQS8_A_C||TDQS8_A_C":   PN = "189"  !CDS_PN = "189";
"DQS8_A_T||TDQS8_A_T":   PN = "190"  !CDS_PN = "190";
"DQS8_B_C||TDQS8_B_C":   PN = "282"  !CDS_PN = "282";
"DQS8_B_T||TDQS8_B_T":   PN = "283"  !CDS_PN = "283";
"DQS9_A_C||TDQS9_A_C":   PN = "200"  !CDS_PN = "200";
"DQS9_A_T||TDQS9_A_T":   PN = "201"  !CDS_PN = "201";
"DQS9_B_C||TDQS9_B_C":   PN = "94"  !CDS_PN = "94";
"DQS9_B_T||TDQS9_B_T||DBI4_B_N":   PN = "93"  !CDS_PN = "93";
BODY = "Q_RES","I183": LOCATION = "R3900" #&CDS_LOCATION = "R3900" &SEC = "1" #&CDS_SEC = "1";
"A":   PN = "1"  !CDS_PN = "1";
"B":   PN = "2"  !CDS_PN = "2";
DRAWING = "@s9s_mb_2u_lib.s9s_mb_2u(sch_1):page108";
BODY = "Q_RES","I10": LOCATION = "R77" #&CDS_LOCATION = "R77" &SEC = "1" #&CDS_SEC = "1";
"A":   PN = "1"  !CDS_PN = "1";
"B":   PN = "2"  !CDS_PN = "2";
BODY = "Q_CAP","I121": LOCATION = "C87" #&CDS_LOCATION = "C87" &SEC = "1" #&CDS_SEC = "1";
"A":   PN = "1"  !CDS_PN = "1";
"B":   PN = "2"  !CDS_PN = "2";
BODY = "Q_CAP","I123": LOCATION = "C88" #&CDS_LOCATION = "C88" &SEC = "1" #&CDS_SEC = "1";
"A":   PN = "1"  !CDS_PN = "1";
"B":   PN = "2"  !CDS_PN = "2";
BODY = "Q_CAP","I160": LOCATION = "C89" #&CDS_LOCATION = "C89" &SEC = "1" #&CDS_SEC = "1";
"A":   PN = "1"  !CDS_PN = "1";
"B":   PN = "2"  !CDS_PN = "2";
BODY = "SCONN288_ADR50017P130CC","I178": LOCATION = "J27" #&CDS_LOCATION = "J27" &SEC = "3" #&CDS_SEC = "3";
"G1":   PN = "G1"  !CDS_PN = "G1";
"G2":   PN = "G2"  !CDS_PN = "G2";
"G3":   PN = "G3"  !CDS_PN = "G3";
"VIN_BULK0":   PN = "1"  !CDS_PN = "1";
"VIN_BULK1":   PN = "145"  !CDS_PN = "145";
"VIN_BULK2":   PN = "146"  !CDS_PN = "146";
"VSS0":   PN = "6"  !CDS_PN = "6";
"VSS1":   PN = "8"  !CDS_PN = "8";
"VSS2":   PN = "10"  !CDS_PN = "10";
"VSS3":   PN = "13"  !CDS_PN = "13";
"VSS4":   PN = "15"  !CDS_PN = "15";
"VSS5":   PN = "17"  !CDS_PN = "17";
"VSS6":   PN = "19"  !CDS_PN = "19";
"VSS7":   PN = "21"  !CDS_PN = "21";
"VSS8":   PN = "24"  !CDS_PN = "24";
"VSS9":   PN = "26"  !CDS_PN = "26";
"VSS10":   PN = "28"  !CDS_PN = "28";
"VSS11":   PN = "30"  !CDS_PN = "30";
"VSS12":   PN = "32"  !CDS_PN = "32";
"VSS13":   PN = "35"  !CDS_PN = "35";
"VSS14":   PN = "37"  !CDS_PN = "37";
"VSS15":   PN = "39"  !CDS_PN = "39";
"VSS16":   PN = "41"  !CDS_PN = "41";
"VSS17":   PN = "43"  !CDS_PN = "43";
"VSS18":   PN = "46"  !CDS_PN = "46";
"VSS19":   PN = "48"  !CDS_PN = "48";
"VSS20":   PN = "50"  !CDS_PN = "50";
"VSS21":   PN = "52"  !CDS_PN = "52";
"VSS22":   PN = "54"  !CDS_PN = "54";
"VSS23":   PN = "57"  !CDS_PN = "57";
"VSS24":   PN = "59"  !CDS_PN = "59";
"VSS25":   PN = "61"  !CDS_PN = "61";
"VSS26":   PN = "63"  !CDS_PN = "63";
"VSS27":   PN = "65"  !CDS_PN = "65";
"VSS28":   PN = "67"  !CDS_PN = "67";
"VSS29":   PN = "69"  !CDS_PN = "69";
"VSS30":   PN = "71"  !CDS_PN = "71";
"VSS31":   PN = "73"  !CDS_PN = "73";
"VSS32":   PN = "75"  !CDS_PN = "75";
"VSS33":   PN = "77"  !CDS_PN = "77";
"VSS34":   PN = "79"  !CDS_PN = "79";
"VSS35":   PN = "81"  !CDS_PN = "81";
"VSS36":   PN = "83"  !CDS_PN = "83";
"VSS37":   PN = "85"  !CDS_PN = "85";
"VSS38":   PN = "88"  !CDS_PN = "88";
"VSS39":   PN = "90"  !CDS_PN = "90";
"VSS40":   PN = "92"  !CDS_PN = "92";
"VSS41":   PN = "95"  !CDS_PN = "95";
"VSS42":   PN = "97"  !CDS_PN = "97";
"VSS43":   PN = "99"  !CDS_PN = "99";
"VSS44":   PN = "101"  !CDS_PN = "101";
"VSS45":   PN = "103"  !CDS_PN = "103";
"VSS46":   PN = "106"  !CDS_PN = "106";
"VSS47":   PN = "108"  !CDS_PN = "108";
"VSS48":   PN = "110"  !CDS_PN = "110";
"VSS49":   PN = "112"  !CDS_PN = "112";
"VSS50":   PN = "114"  !CDS_PN = "114";
"VSS51":   PN = "117"  !CDS_PN = "117";
"VSS52":   PN = "119"  !CDS_PN = "119";
"VSS53":   PN = "121"  !CDS_PN = "121";
"VSS54":   PN = "123"  !CDS_PN = "123";
"VSS55":   PN = "125"  !CDS_PN = "125";
"VSS56":   PN = "128"  !CDS_PN = "128";
"VSS57":   PN = "130"  !CDS_PN = "130";
"VSS58":   PN = "132"  !CDS_PN = "132";
"VSS59":   PN = "134"  !CDS_PN = "134";
"VSS60":   PN = "136"  !CDS_PN = "136";
"VSS61":   PN = "139"  !CDS_PN = "139";
"VSS62":   PN = "141"  !CDS_PN = "141";
"VSS63":   PN = "143"  !CDS_PN = "143";
"VSS64":   PN = "151"  !CDS_PN = "151";
"VSS65":   PN = "153"  !CDS_PN = "153";
"VSS66":   PN = "155"  !CDS_PN = "155";
"VSS67":   PN = "158"  !CDS_PN = "158";
"VSS68":   PN = "160"  !CDS_PN = "160";
"VSS69":   PN = "162"  !CDS_PN = "162";
"VSS70":   PN = "164"  !CDS_PN = "164";
"VSS71":   PN = "166"  !CDS_PN = "166";
"VSS72":   PN = "169"  !CDS_PN = "169";
"VSS73":   PN = "171"  !CDS_PN = "171";
"VSS74":   PN = "173"  !CDS_PN = "173";
"VSS75":   PN = "175"  !CDS_PN = "175";
"VSS76":   PN = "177"  !CDS_PN = "177";
"VSS77":   PN = "180"  !CDS_PN = "180";
"VSS78":   PN = "182"  !CDS_PN = "182";
"VSS79":   PN = "184"  !CDS_PN = "184";
"VSS80":   PN = "186"  !CDS_PN = "186";
"VSS81":   PN = "188"  !CDS_PN = "188";
"VSS82":   PN = "191"  !CDS_PN = "191";
"VSS83":   PN = "193"  !CDS_PN = "193";
"VSS84":   PN = "195"  !CDS_PN = "195";
"VSS85":   PN = "197"  !CDS_PN = "197";
"VSS86":   PN = "199"  !CDS_PN = "199";
"VSS87":   PN = "202"  !CDS_PN = "202";
"VSS88":   PN = "204"  !CDS_PN = "204";
"VSS89":   PN = "206"  !CDS_PN = "206";
"VSS90":   PN = "208"  !CDS_PN = "208";
"VSS91":   PN = "210"  !CDS_PN = "210";
"VSS92":   PN = "212"  !CDS_PN = "212";
"VSS93":   PN = "214"  !CDS_PN = "214";
"VSS94":   PN = "216"  !CDS_PN = "216";
"VSS95":   PN = "219"  !CDS_PN = "219";
"VSS96":   PN = "222"  !CDS_PN = "222";
"VSS97":   PN = "224"  !CDS_PN = "224";
"VSS98":   PN = "226"  !CDS_PN = "226";
"VSS99":   PN = "228"  !CDS_PN = "228";
"VSS100":   PN = "230"  !CDS_PN = "230";
"VSS101":   PN = "233"  !CDS_PN = "233";
"VSS102":   PN = "235"  !CDS_PN = "235";
"VSS103":   PN = "237"  !CDS_PN = "237";
"VSS104":   PN = "240"  !CDS_PN = "240";
"VSS105":   PN = "242"  !CDS_PN = "242";
"VSS106":   PN = "244"  !CDS_PN = "244";
"VSS107":   PN = "246"  !CDS_PN = "246";
"VSS108":   PN = "248"  !CDS_PN = "248";
"VSS109":   PN = "251"  !CDS_PN = "251";
"VSS110":   PN = "253"  !CDS_PN = "253";
"VSS111":   PN = "255"  !CDS_PN = "255";
"VSS112":   PN = "257"  !CDS_PN = "257";
"VSS113":   PN = "259"  !CDS_PN = "259";
"VSS114":   PN = "262"  !CDS_PN = "262";
"VSS115":   PN = "264"  !CDS_PN = "264";
"VSS116":   PN = "266"  !CDS_PN = "266";
"VSS117":   PN = "268"  !CDS_PN = "268";
"VSS118":   PN = "270"  !CDS_PN = "270";
"VSS119":   PN = "273"  !CDS_PN = "273";
"VSS120":   PN = "275"  !CDS_PN = "275";
"VSS121":   PN = "277"  !CDS_PN = "277";
"VSS122":   PN = "279"  !CDS_PN = "279";
"VSS123":   PN = "281"  !CDS_PN = "281";
"VSS124":   PN = "284"  !CDS_PN = "284";
"VSS125":   PN = "286"  !CDS_PN = "286";
"VSS126":   PN = "288"  !CDS_PN = "288";
BODY = "SCONN288_ADR50017P130CC","I179": LOCATION = "J27" #&CDS_LOCATION = "J27" &SEC = "1" #&CDS_SEC = "1";
"ALERT_N":   PN = "62"  !CDS_PN = "62";
"CA0_A":   PN = "66"  !CDS_PN = "66";
"CA0_B":   PN = "76"  !CDS_PN = "76";
"CA1_A":   PN = "211"  !CDS_PN = "211";
"CA1_B":   PN = "221"  !CDS_PN = "221";
"CA2_A":   PN = "68"  !CDS_PN = "68";
"CA2_B":   PN = "78"  !CDS_PN = "78";
"CA3_A":   PN = "213"  !CDS_PN = "213";
"CA3_B":   PN = "223"  !CDS_PN = "223";
"CA4_A":   PN = "70"  !CDS_PN = "70";
"CA4_B":   PN = "80"  !CDS_PN = "80";
"CA5_A":   PN = "215"  !CDS_PN = "215";
"CA5_B":   PN = "225"  !CDS_PN = "225";
"CA6_A":   PN = "72"  !CDS_PN = "72";
"CA6_B":   PN = "82"  !CDS_PN = "82";
"CB0_A":   PN = "51"  !CDS_PN = "51";
"CB0_B":   PN = "96"  !CDS_PN = "96";
"CB1_A":   PN = "53"  !CDS_PN = "53";
"CB1_B":   PN = "98"  !CDS_PN = "98";
"CB2_A":   PN = "196"  !CDS_PN = "196";
"CB2_B":   PN = "241"  !CDS_PN = "241";
"CB3_A":   PN = "198"  !CDS_PN = "198";
"CB3_B":   PN = "243"  !CDS_PN = "243";
"CB4_A":   PN = "58"  !CDS_PN = "58";
"CB4_B":   PN = "89"  !CDS_PN = "89";
"CB5_A":   PN = "60"  !CDS_PN = "60";
"CB5_B":   PN = "91"  !CDS_PN = "91";
"CB6_A":   PN = "203"  !CDS_PN = "203";
"CB6_B":   PN = "234"  !CDS_PN = "234";
"CB7_A":   PN = "205"  !CDS_PN = "205";
"CB7_B":   PN = "236"  !CDS_PN = "236";
"CK_C":   PN = "218"  !CDS_PN = "218";
"CK_T":   PN = "217"  !CDS_PN = "217";
"CS0_A_N":   PN = "64"  !CDS_PN = "64";
"CS0_B_N":   PN = "84"  !CDS_PN = "84";
"CS1_A_N":   PN = "209"  !CDS_PN = "209";
"CS1_B_N":   PN = "229"  !CDS_PN = "229";
"DQ0_A":   PN = "7"  !CDS_PN = "7";
"DQ0_B":   PN = "100"  !CDS_PN = "100";
"DQ1_A":   PN = "9"  !CDS_PN = "9";
"DQ1_B":   PN = "102"  !CDS_PN = "102";
"DQ2_A":   PN = "152"  !CDS_PN = "152";
"DQ2_B":   PN = "245"  !CDS_PN = "245";
"DQ3_A":   PN = "154"  !CDS_PN = "154";
"DQ3_B":   PN = "247"  !CDS_PN = "247";
"DQ4_A":   PN = "14"  !CDS_PN = "14";
"DQ4_B":   PN = "107"  !CDS_PN = "107";
"DQ5_A":   PN = "16"  !CDS_PN = "16";
"DQ5_B":   PN = "109"  !CDS_PN = "109";
"DQ6_A":   PN = "159"  !CDS_PN = "159";
"DQ6_B":   PN = "252"  !CDS_PN = "252";
"DQ7_A":   PN = "161"  !CDS_PN = "161";
"DQ7_B":   PN = "254"  !CDS_PN = "254";
"DQ8_A":   PN = "18"  !CDS_PN = "18";
"DQ8_B":   PN = "111"  !CDS_PN = "111";
"DQ9_A":   PN = "20"  !CDS_PN = "20";
"DQ9_B":   PN = "113"  !CDS_PN = "113";
"DQ10_A":   PN = "163"  !CDS_PN = "163";
"DQ10_B":   PN = "256"  !CDS_PN = "256";
"DQ11_A":   PN = "165"  !CDS_PN = "165";
"DQ11_B":   PN = "258"  !CDS_PN = "258";
"DQ12_A":   PN = "25"  !CDS_PN = "25";
"DQ12_B":   PN = "118"  !CDS_PN = "118";
"DQ13_A":   PN = "27"  !CDS_PN = "27";
"DQ13_B":   PN = "120"  !CDS_PN = "120";
"DQ14_A":   PN = "170"  !CDS_PN = "170";
"DQ14_B":   PN = "263"  !CDS_PN = "263";
"DQ15_A":   PN = "172"  !CDS_PN = "172";
"DQ15_B":   PN = "265"  !CDS_PN = "265";
"DQ16_A":   PN = "29"  !CDS_PN = "29";
"DQ16_B":   PN = "122"  !CDS_PN = "122";
"DQ17_A":   PN = "31"  !CDS_PN = "31";
"DQ17_B":   PN = "124"  !CDS_PN = "124";
"DQ18_A":   PN = "174"  !CDS_PN = "174";
"DQ18_B":   PN = "267"  !CDS_PN = "267";
"DQ19_A":   PN = "176"  !CDS_PN = "176";
"DQ19_B":   PN = "269"  !CDS_PN = "269";
"DQ20_A":   PN = "36"  !CDS_PN = "36";
"DQ20_B":   PN = "129"  !CDS_PN = "129";
"DQ21_A":   PN = "38"  !CDS_PN = "38";
"DQ21_B":   PN = "131"  !CDS_PN = "131";
"DQ22_A":   PN = "181"  !CDS_PN = "181";
"DQ22_B":   PN = "274"  !CDS_PN = "274";
"DQ23_A":   PN = "183"  !CDS_PN = "183";
"DQ23_B":   PN = "276"  !CDS_PN = "276";
"DQ24_A":   PN = "40"  !CDS_PN = "40";
"DQ24_B":   PN = "133"  !CDS_PN = "133";
"DQ25_A":   PN = "42"  !CDS_PN = "42";
"DQ25_B":   PN = "135"  !CDS_PN = "135";
"DQ26_A":   PN = "185"  !CDS_PN = "185";
"DQ26_B":   PN = "278"  !CDS_PN = "278";
"DQ27_A":   PN = "187"  !CDS_PN = "187";
"DQ27_B":   PN = "280"  !CDS_PN = "280";
"DQ28_A":   PN = "47"  !CDS_PN = "47";
"DQ28_B":   PN = "140"  !CDS_PN = "140";
"DQ29_A":   PN = "49"  !CDS_PN = "49";
"DQ29_B":   PN = "142"  !CDS_PN = "142";
"DQ30_A":   PN = "192"  !CDS_PN = "192";
"DQ30_B":   PN = "285"  !CDS_PN = "285";
"DQ31_A":   PN = "194"  !CDS_PN = "194";
"DQ31_B":   PN = "287"  !CDS_PN = "287";
"HSA":   PN = "148"  !CDS_PN = "148";
"HSCL":   PN = "4"  !CDS_PN = "4";
"HSDA":   PN = "5"  !CDS_PN = "5";
"LBD||RSP_A_N":   PN = "86"  !CDS_PN = "86";
"LBS||RSP_B_N":   PN = "87"  !CDS_PN = "87";
"PAR_A":   PN = "74"  !CDS_PN = "74";
"PAR_B":   PN = "227"  !CDS_PN = "227";
"PWR_GOOD||FAIL_N":   PN = "147"  !CDS_PN = "147";
"RESET_N":   PN = "207"  !CDS_PN = "207";
"RFU0":   PN = "2"  !CDS_PN = "2";
"RFU1":   PN = "144"  !CDS_PN = "144";
"RFU2":   PN = "149"  !CDS_PN = "149";
"RFU3":   PN = "150"  !CDS_PN = "150";
"RFU4":   PN = "220"  !CDS_PN = "220";
"RFU5":   PN = "231"  !CDS_PN = "231";
"RFU6":   PN = "232"  !CDS_PN = "232";
"VIN_MGMT":   PN = "3"  !CDS_PN = "3";
BODY = "SCONN288_ADR50017P130CC","I180": #LOCATION = "J27" !CDS_LOCATION = "J27" &SEC = "2" #&CDS_SEC = "2";
"DQS0_A_C":   PN = "12"  !CDS_PN = "12";
"DQS0_A_T":   PN = "11"  !CDS_PN = "11";
"DQS0_B_C":   PN = "105"  !CDS_PN = "105";
"DQS0_B_T":   PN = "104"  !CDS_PN = "104";
"DQS1_A_C":   PN = "23"  !CDS_PN = "23";
"DQS1_A_T":   PN = "22"  !CDS_PN = "22";
"DQS1_B_C":   PN = "116"  !CDS_PN = "116";
"DQS1_B_T":   PN = "115"  !CDS_PN = "115";
"DQS2_A_C":   PN = "34"  !CDS_PN = "34";
"DQS2_A_T":   PN = "33"  !CDS_PN = "33";
"DQS2_B_C":   PN = "127"  !CDS_PN = "127";
"DQS2_B_T":   PN = "126"  !CDS_PN = "126";
"DQS3_A_C":   PN = "45"  !CDS_PN = "45";
"DQS3_A_T":   PN = "44"  !CDS_PN = "44";
"DQS3_B_C":   PN = "138"  !CDS_PN = "138";
"DQS3_B_T":   PN = "137"  !CDS_PN = "137";
"DQS4_A_C":   PN = "56"  !CDS_PN = "56";
"DQS4_A_T":   PN = "55"  !CDS_PN = "55";
"DQS4_B_C":   PN = "238"  !CDS_PN = "238";
"DQS4_B_T":   PN = "239"  !CDS_PN = "239";
"DQS5_A_C||TDQS5_A_C||DQS5_A_T||TDQS5_A_T":   PN = "156"  !CDS_PN = "156";
"DQS5_A_T||TDQS5_A_T":   PN = "157"  !CDS_PN = "157";
"DQS5_B_C||TDQS5_B_C":   PN = "249"  !CDS_PN = "249";
"DQS5_B_T||TDQS5_B_T":   PN = "250"  !CDS_PN = "250";
"DQS6_A_C||TDQS6_A_C||DQS6_A_T||TDQS6_A_T":   PN = "167"  !CDS_PN = "167";
"DQS6_A_T||TDQS6_A_T":   PN = "168"  !CDS_PN = "168";
"DQS6_B_C||TDQS6_B_C":   PN = "260"  !CDS_PN = "260";
"DQS6_B_T||TDQS6_B_T":   PN = "261"  !CDS_PN = "261";
"DQS7_A_C||TDQS7_A_C":   PN = "178"  !CDS_PN = "178";
"DQS7_A_T||TDQS7_A_T":   PN = "179"  !CDS_PN = "179";
"DQS7_B_C||TDQS7_B_C":   PN = "271"  !CDS_PN = "271";
"DQS7_B_T||TDQS7_B_T":   PN = "272"  !CDS_PN = "272";
"DQS8_A_C||TDQS8_A_C":   PN = "189"  !CDS_PN = "189";
"DQS8_A_T||TDQS8_A_T":   PN = "190"  !CDS_PN = "190";
"DQS8_B_C||TDQS8_B_C":   PN = "282"  !CDS_PN = "282";
"DQS8_B_T||TDQS8_B_T":   PN = "283"  !CDS_PN = "283";
"DQS9_A_C||TDQS9_A_C":   PN = "200"  !CDS_PN = "200";
"DQS9_A_T||TDQS9_A_T":   PN = "201"  !CDS_PN = "201";
"DQS9_B_C||TDQS9_B_C":   PN = "94"  !CDS_PN = "94";
"DQS9_B_T||TDQS9_B_T||DBI4_B_N":   PN = "93"  !CDS_PN = "93";
BODY = "Q_RES","I182": LOCATION = "R3901" #&CDS_LOCATION = "R3901" &SEC = "1" #&CDS_SEC = "1";
"A":   PN = "1"  !CDS_PN = "1";
"B":   PN = "2"  !CDS_PN = "2";
DRAWING = "@s9s_mb_2u_lib.s9s_mb_2u(sch_1):page109";
BODY = "Q_RES","I46": LOCATION = "R76" #&CDS_LOCATION = "R76" &SEC = "1" #&CDS_SEC = "1";
"A":   PN = "1"  !CDS_PN = "1";
"B":   PN = "2"  !CDS_PN = "2";
BODY = "SCONN288_ADR50017P087CC","I47": LOCATION = "J28" #&CDS_LOCATION = "J28" &SEC = "1" #&CDS_SEC = "1";
"ALERT_N":   PN = "62"  !CDS_PN = "62";
"CA0_A":   PN = "66"  !CDS_PN = "66";
"CA0_B":   PN = "76"  !CDS_PN = "76";
"CA1_A":   PN = "211"  !CDS_PN = "211";
"CA1_B":   PN = "221"  !CDS_PN = "221";
"CA2_A":   PN = "68"  !CDS_PN = "68";
"CA2_B":   PN = "78"  !CDS_PN = "78";
"CA3_A":   PN = "213"  !CDS_PN = "213";
"CA3_B":   PN = "223"  !CDS_PN = "223";
"CA4_A":   PN = "70"  !CDS_PN = "70";
"CA4_B":   PN = "80"  !CDS_PN = "80";
"CA5_A":   PN = "215"  !CDS_PN = "215";
"CA5_B":   PN = "225"  !CDS_PN = "225";
"CA6_A":   PN = "72"  !CDS_PN = "72";
"CA6_B":   PN = "82"  !CDS_PN = "82";
"CB0_A":   PN = "51"  !CDS_PN = "51";
"CB0_B":   PN = "96"  !CDS_PN = "96";
"CB1_A":   PN = "53"  !CDS_PN = "53";
"CB1_B":   PN = "98"  !CDS_PN = "98";
"CB2_A":   PN = "196"  !CDS_PN = "196";
"CB2_B":   PN = "241"  !CDS_PN = "241";
"CB3_A":   PN = "198"  !CDS_PN = "198";
"CB3_B":   PN = "243"  !CDS_PN = "243";
"CB4_A":   PN = "58"  !CDS_PN = "58";
"CB4_B":   PN = "89"  !CDS_PN = "89";
"CB5_A":   PN = "60"  !CDS_PN = "60";
"CB5_B":   PN = "91"  !CDS_PN = "91";
"CB6_A":   PN = "203"  !CDS_PN = "203";
"CB6_B":   PN = "234"  !CDS_PN = "234";
"CB7_A":   PN = "205"  !CDS_PN = "205";
"CB7_B":   PN = "236"  !CDS_PN = "236";
"CK_C":   PN = "218"  !CDS_PN = "218";
"CK_T":   PN = "217"  !CDS_PN = "217";
"CS0_A_N":   PN = "64"  !CDS_PN = "64";
"CS0_B_N":   PN = "84"  !CDS_PN = "84";
"CS1_A_N":   PN = "209"  !CDS_PN = "209";
"CS1_B_N":   PN = "229"  !CDS_PN = "229";
"DQ0_A":   PN = "7"  !CDS_PN = "7";
"DQ0_B":   PN = "100"  !CDS_PN = "100";
"DQ1_A":   PN = "9"  !CDS_PN = "9";
"DQ1_B":   PN = "102"  !CDS_PN = "102";
"DQ2_A":   PN = "152"  !CDS_PN = "152";
"DQ2_B":   PN = "245"  !CDS_PN = "245";
"DQ3_A":   PN = "154"  !CDS_PN = "154";
"DQ3_B":   PN = "247"  !CDS_PN = "247";
"DQ4_A":   PN = "14"  !CDS_PN = "14";
"DQ4_B":   PN = "107"  !CDS_PN = "107";
"DQ5_A":   PN = "16"  !CDS_PN = "16";
"DQ5_B":   PN = "109"  !CDS_PN = "109";
"DQ6_A":   PN = "159"  !CDS_PN = "159";
"DQ6_B":   PN = "252"  !CDS_PN = "252";
"DQ7_A":   PN = "161"  !CDS_PN = "161";
"DQ7_B":   PN = "254"  !CDS_PN = "254";
"DQ8_A":   PN = "18"  !CDS_PN = "18";
"DQ8_B":   PN = "111"  !CDS_PN = "111";
"DQ9_A":   PN = "20"  !CDS_PN = "20";
"DQ9_B":   PN = "113"  !CDS_PN = "113";
"DQ10_A":   PN = "163"  !CDS_PN = "163";
"DQ10_B":   PN = "256"  !CDS_PN = "256";
"DQ11_A":   PN = "165"  !CDS_PN = "165";
"DQ11_B":   PN = "258"  !CDS_PN = "258";
"DQ12_A":   PN = "25"  !CDS_PN = "25";
"DQ12_B":   PN = "118"  !CDS_PN = "118";
"DQ13_A":   PN = "27"  !CDS_PN = "27";
"DQ13_B":   PN = "120"  !CDS_PN = "120";
"DQ14_A":   PN = "170"  !CDS_PN = "170";
"DQ14_B":   PN = "263"  !CDS_PN = "263";
"DQ15_A":   PN = "172"  !CDS_PN = "172";
"DQ15_B":   PN = "265"  !CDS_PN = "265";
"DQ16_A":   PN = "29"  !CDS_PN = "29";
"DQ16_B":   PN = "122"  !CDS_PN = "122";
"DQ17_A":   PN = "31"  !CDS_PN = "31";
"DQ17_B":   PN = "124"  !CDS_PN = "124";
"DQ18_A":   PN = "174"  !CDS_PN = "174";
"DQ18_B":   PN = "267"  !CDS_PN = "267";
"DQ19_A":   PN = "176"  !CDS_PN = "176";
"DQ19_B":   PN = "269"  !CDS_PN = "269";
"DQ20_A":   PN = "36"  !CDS_PN = "36";
"DQ20_B":   PN = "129"  !CDS_PN = "129";
"DQ21_A":   PN = "38"  !CDS_PN = "38";
"DQ21_B":   PN = "131"  !CDS_PN = "131";
"DQ22_A":   PN = "181"  !CDS_PN = "181";
"DQ22_B":   PN = "274"  !CDS_PN = "274";
"DQ23_A":   PN = "183"  !CDS_PN = "183";
"DQ23_B":   PN = "276"  !CDS_PN = "276";
"DQ24_A":   PN = "40"  !CDS_PN = "40";
"DQ24_B":   PN = "133"  !CDS_PN = "133";
"DQ25_A":   PN = "42"  !CDS_PN = "42";
"DQ25_B":   PN = "135"  !CDS_PN = "135";
"DQ26_A":   PN = "185"  !CDS_PN = "185";
"DQ26_B":   PN = "278"  !CDS_PN = "278";
"DQ27_A":   PN = "187"  !CDS_PN = "187";
"DQ27_B":   PN = "280"  !CDS_PN = "280";
"DQ28_A":   PN = "47"  !CDS_PN = "47";
"DQ28_B":   PN = "140"  !CDS_PN = "140";
"DQ29_A":   PN = "49"  !CDS_PN = "49";
"DQ29_B":   PN = "142"  !CDS_PN = "142";
"DQ30_A":   PN = "192"  !CDS_PN = "192";
"DQ30_B":   PN = "285"  !CDS_PN = "285";
"DQ31_A":   PN = "194"  !CDS_PN = "194";
"DQ31_B":   PN = "287"  !CDS_PN = "287";
"HSA":   PN = "148"  !CDS_PN = "148";
"HSCL":   PN = "4"  !CDS_PN = "4";
"HSDA":   PN = "5"  !CDS_PN = "5";
"LBD||RSP_A_N":   PN = "86"  !CDS_PN = "86";
"LBS||RSP_B_N":   PN = "87"  !CDS_PN = "87";
"PAR_A":   PN = "74"  !CDS_PN = "74";
"PAR_B":   PN = "227"  !CDS_PN = "227";
"PWR_GOOD||FAIL_N":   PN = "147"  !CDS_PN = "147";
"RESET_N":   PN = "207"  !CDS_PN = "207";
"RFU0":   PN = "2"  !CDS_PN = "2";
"RFU1":   PN = "144"  !CDS_PN = "144";
"RFU2":   PN = "149"  !CDS_PN = "149";
"RFU3":   PN = "150"  !CDS_PN = "150";
"RFU4":   PN = "220"  !CDS_PN = "220";
"RFU5":   PN = "231"  !CDS_PN = "231";
"RFU6":   PN = "232"  !CDS_PN = "232";
"VIN_MGMT":   PN = "3"  !CDS_PN = "3";
BODY = "Q_CAP","I121": LOCATION = "C84" #&CDS_LOCATION = "C84" &SEC = "1" #&CDS_SEC = "1";
"A":   PN = "1"  !CDS_PN = "1";
"B":   PN = "2"  !CDS_PN = "2";
BODY = "Q_CAP","I125": LOCATION = "C85" #&CDS_LOCATION = "C85" &SEC = "1" #&CDS_SEC = "1";
"A":   PN = "1"  !CDS_PN = "1";
"B":   PN = "2"  !CDS_PN = "2";
BODY = "Q_CAP","I128": LOCATION = "C86" #&CDS_LOCATION = "C86" &SEC = "1" #&CDS_SEC = "1";
"A":   PN = "1"  !CDS_PN = "1";
"B":   PN = "2"  !CDS_PN = "2";
BODY = "SCONN288_ADR50017P087CC","I176": LOCATION = "J28" #&CDS_LOCATION = "J28" &SEC = "3" #&CDS_SEC = "3";
"G1":   PN = "G1"  !CDS_PN = "G1";
"G2":   PN = "G2"  !CDS_PN = "G2";
"G3":   PN = "G3"  !CDS_PN = "G3";
"VIN_BULK0":   PN = "1"  !CDS_PN = "1";
"VIN_BULK1":   PN = "145"  !CDS_PN = "145";
"VIN_BULK2":   PN = "146"  !CDS_PN = "146";
"VSS0":   PN = "6"  !CDS_PN = "6";
"VSS1":   PN = "8"  !CDS_PN = "8";
"VSS2":   PN = "10"  !CDS_PN = "10";
"VSS3":   PN = "13"  !CDS_PN = "13";
"VSS4":   PN = "15"  !CDS_PN = "15";
"VSS5":   PN = "17"  !CDS_PN = "17";
"VSS6":   PN = "19"  !CDS_PN = "19";
"VSS7":   PN = "21"  !CDS_PN = "21";
"VSS8":   PN = "24"  !CDS_PN = "24";
"VSS9":   PN = "26"  !CDS_PN = "26";
"VSS10":   PN = "28"  !CDS_PN = "28";
"VSS11":   PN = "30"  !CDS_PN = "30";
"VSS12":   PN = "32"  !CDS_PN = "32";
"VSS13":   PN = "35"  !CDS_PN = "35";
"VSS14":   PN = "37"  !CDS_PN = "37";
"VSS15":   PN = "39"  !CDS_PN = "39";
"VSS16":   PN = "41"  !CDS_PN = "41";
"VSS17":   PN = "43"  !CDS_PN = "43";
"VSS18":   PN = "46"  !CDS_PN = "46";
"VSS19":   PN = "48"  !CDS_PN = "48";
"VSS20":   PN = "50"  !CDS_PN = "50";
"VSS21":   PN = "52"  !CDS_PN = "52";
"VSS22":   PN = "54"  !CDS_PN = "54";
"VSS23":   PN = "57"  !CDS_PN = "57";
"VSS24":   PN = "59"  !CDS_PN = "59";
"VSS25":   PN = "61"  !CDS_PN = "61";
"VSS26":   PN = "63"  !CDS_PN = "63";
"VSS27":   PN = "65"  !CDS_PN = "65";
"VSS28":   PN = "67"  !CDS_PN = "67";
"VSS29":   PN = "69"  !CDS_PN = "69";
"VSS30":   PN = "71"  !CDS_PN = "71";
"VSS31":   PN = "73"  !CDS_PN = "73";
"VSS32":   PN = "75"  !CDS_PN = "75";
"VSS33":   PN = "77"  !CDS_PN = "77";
"VSS34":   PN = "79"  !CDS_PN = "79";
"VSS35":   PN = "81"  !CDS_PN = "81";
"VSS36":   PN = "83"  !CDS_PN = "83";
"VSS37":   PN = "85"  !CDS_PN = "85";
"VSS38":   PN = "88"  !CDS_PN = "88";
"VSS39":   PN = "90"  !CDS_PN = "90";
"VSS40":   PN = "92"  !CDS_PN = "92";
"VSS41":   PN = "95"  !CDS_PN = "95";
"VSS42":   PN = "97"  !CDS_PN = "97";
"VSS43":   PN = "99"  !CDS_PN = "99";
"VSS44":   PN = "101"  !CDS_PN = "101";
"VSS45":   PN = "103"  !CDS_PN = "103";
"VSS46":   PN = "106"  !CDS_PN = "106";
"VSS47":   PN = "108"  !CDS_PN = "108";
"VSS48":   PN = "110"  !CDS_PN = "110";
"VSS49":   PN = "112"  !CDS_PN = "112";
"VSS50":   PN = "114"  !CDS_PN = "114";
"VSS51":   PN = "117"  !CDS_PN = "117";
"VSS52":   PN = "119"  !CDS_PN = "119";
"VSS53":   PN = "121"  !CDS_PN = "121";
"VSS54":   PN = "123"  !CDS_PN = "123";
"VSS55":   PN = "125"  !CDS_PN = "125";
"VSS56":   PN = "128"  !CDS_PN = "128";
"VSS57":   PN = "130"  !CDS_PN = "130";
"VSS58":   PN = "132"  !CDS_PN = "132";
"VSS59":   PN = "134"  !CDS_PN = "134";
"VSS60":   PN = "136"  !CDS_PN = "136";
"VSS61":   PN = "139"  !CDS_PN = "139";
"VSS62":   PN = "141"  !CDS_PN = "141";
"VSS63":   PN = "143"  !CDS_PN = "143";
"VSS64":   PN = "151"  !CDS_PN = "151";
"VSS65":   PN = "153"  !CDS_PN = "153";
"VSS66":   PN = "155"  !CDS_PN = "155";
"VSS67":   PN = "158"  !CDS_PN = "158";
"VSS68":   PN = "160"  !CDS_PN = "160";
"VSS69":   PN = "162"  !CDS_PN = "162";
"VSS70":   PN = "164"  !CDS_PN = "164";
"VSS71":   PN = "166"  !CDS_PN = "166";
"VSS72":   PN = "169"  !CDS_PN = "169";
"VSS73":   PN = "171"  !CDS_PN = "171";
"VSS74":   PN = "173"  !CDS_PN = "173";
"VSS75":   PN = "175"  !CDS_PN = "175";
"VSS76":   PN = "177"  !CDS_PN = "177";
"VSS77":   PN = "180"  !CDS_PN = "180";
"VSS78":   PN = "182"  !CDS_PN = "182";
"VSS79":   PN = "184"  !CDS_PN = "184";
"VSS80":   PN = "186"  !CDS_PN = "186";
"VSS81":   PN = "188"  !CDS_PN = "188";
"VSS82":   PN = "191"  !CDS_PN = "191";
"VSS83":   PN = "193"  !CDS_PN = "193";
"VSS84":   PN = "195"  !CDS_PN = "195";
"VSS85":   PN = "197"  !CDS_PN = "197";
"VSS86":   PN = "199"  !CDS_PN = "199";
"VSS87":   PN = "202"  !CDS_PN = "202";
"VSS88":   PN = "204"  !CDS_PN = "204";
"VSS89":   PN = "206"  !CDS_PN = "206";
"VSS90":   PN = "208"  !CDS_PN = "208";
"VSS91":   PN = "210"  !CDS_PN = "210";
"VSS92":   PN = "212"  !CDS_PN = "212";
"VSS93":   PN = "214"  !CDS_PN = "214";
"VSS94":   PN = "216"  !CDS_PN = "216";
"VSS95":   PN = "219"  !CDS_PN = "219";
"VSS96":   PN = "222"  !CDS_PN = "222";
"VSS97":   PN = "224"  !CDS_PN = "224";
"VSS98":   PN = "226"  !CDS_PN = "226";
"VSS99":   PN = "228"  !CDS_PN = "228";
"VSS100":   PN = "230"  !CDS_PN = "230";
"VSS101":   PN = "233"  !CDS_PN = "233";
"VSS102":   PN = "235"  !CDS_PN = "235";
"VSS103":   PN = "237"  !CDS_PN = "237";
"VSS104":   PN = "240"  !CDS_PN = "240";
"VSS105":   PN = "242"  !CDS_PN = "242";
"VSS106":   PN = "244"  !CDS_PN = "244";
"VSS107":   PN = "246"  !CDS_PN = "246";
"VSS108":   PN = "248"  !CDS_PN = "248";
"VSS109":   PN = "251"  !CDS_PN = "251";
"VSS110":   PN = "253"  !CDS_PN = "253";
"VSS111":   PN = "255"  !CDS_PN = "255";
"VSS112":   PN = "257"  !CDS_PN = "257";
"VSS113":   PN = "259"  !CDS_PN = "259";
"VSS114":   PN = "262"  !CDS_PN = "262";
"VSS115":   PN = "264"  !CDS_PN = "264";
"VSS116":   PN = "266"  !CDS_PN = "266";
"VSS117":   PN = "268"  !CDS_PN = "268";
"VSS118":   PN = "270"  !CDS_PN = "270";
"VSS119":   PN = "273"  !CDS_PN = "273";
"VSS120":   PN = "275"  !CDS_PN = "275";
"VSS121":   PN = "277"  !CDS_PN = "277";
"VSS122":   PN = "279"  !CDS_PN = "279";
"VSS123":   PN = "281"  !CDS_PN = "281";
"VSS124":   PN = "284"  !CDS_PN = "284";
"VSS125":   PN = "286"  !CDS_PN = "286";
"VSS126":   PN = "288"  !CDS_PN = "288";
BODY = "SCONN288_ADR50017P087CC","I178": #LOCATION = "J28" !CDS_LOCATION = "J28" &SEC = "2" #&CDS_SEC = "2";
"DQS0_A_C":   PN = "12"  !CDS_PN = "12";
"DQS0_A_T":   PN = "11"  !CDS_PN = "11";
"DQS0_B_C":   PN = "105"  !CDS_PN = "105";
"DQS0_B_T":   PN = "104"  !CDS_PN = "104";
"DQS1_A_C":   PN = "23"  !CDS_PN = "23";
"DQS1_A_T":   PN = "22"  !CDS_PN = "22";
"DQS1_B_C":   PN = "116"  !CDS_PN = "116";
"DQS1_B_T":   PN = "115"  !CDS_PN = "115";
"DQS2_A_C":   PN = "34"  !CDS_PN = "34";
"DQS2_A_T":   PN = "33"  !CDS_PN = "33";
"DQS2_B_C":   PN = "127"  !CDS_PN = "127";
"DQS2_B_T":   PN = "126"  !CDS_PN = "126";
"DQS3_A_C":   PN = "45"  !CDS_PN = "45";
"DQS3_A_T":   PN = "44"  !CDS_PN = "44";
"DQS3_B_C":   PN = "138"  !CDS_PN = "138";
"DQS3_B_T":   PN = "137"  !CDS_PN = "137";
"DQS4_A_C":   PN = "56"  !CDS_PN = "56";
"DQS4_A_T":   PN = "55"  !CDS_PN = "55";
"DQS4_B_C":   PN = "238"  !CDS_PN = "238";
"DQS4_B_T":   PN = "239"  !CDS_PN = "239";
"DQS5_A_C||TDQS5_A_C||DQS5_A_T||TDQS5_A_T":   PN = "156"  !CDS_PN = "156";
"DQS5_A_T||TDQS5_A_T":   PN = "157"  !CDS_PN = "157";
"DQS5_B_C||TDQS5_B_C":   PN = "249"  !CDS_PN = "249";
"DQS5_B_T||TDQS5_B_T":   PN = "250"  !CDS_PN = "250";
"DQS6_A_C||TDQS6_A_C||DQS6_A_T||TDQS6_A_T":   PN = "167"  !CDS_PN = "167";
"DQS6_A_T||TDQS6_A_T":   PN = "168"  !CDS_PN = "168";
"DQS6_B_C||TDQS6_B_C":   PN = "260"  !CDS_PN = "260";
"DQS6_B_T||TDQS6_B_T":   PN = "261"  !CDS_PN = "261";
"DQS7_A_C||TDQS7_A_C":   PN = "178"  !CDS_PN = "178";
"DQS7_A_T||TDQS7_A_T":   PN = "179"  !CDS_PN = "179";
"DQS7_B_C||TDQS7_B_C":   PN = "271"  !CDS_PN = "271";
"DQS7_B_T||TDQS7_B_T":   PN = "272"  !CDS_PN = "272";
"DQS8_A_C||TDQS8_A_C":   PN = "189"  !CDS_PN = "189";
"DQS8_A_T||TDQS8_A_T":   PN = "190"  !CDS_PN = "190";
"DQS8_B_C||TDQS8_B_C":   PN = "282"  !CDS_PN = "282";
"DQS8_B_T||TDQS8_B_T":   PN = "283"  !CDS_PN = "283";
"DQS9_A_C||TDQS9_A_C":   PN = "200"  !CDS_PN = "200";
"DQS9_A_T||TDQS9_A_T":   PN = "201"  !CDS_PN = "201";
"DQS9_B_C||TDQS9_B_C":   PN = "94"  !CDS_PN = "94";
"DQS9_B_T||TDQS9_B_T||DBI4_B_N":   PN = "93"  !CDS_PN = "93";
BODY = "Q_RES","I180": LOCATION = "R3902" #&CDS_LOCATION = "R3902" &SEC = "1" #&CDS_SEC = "1";
"A":   PN = "1"  !CDS_PN = "1";
"B":   PN = "2"  !CDS_PN = "2";
DRAWING = "@s9s_mb_2u_lib.s9s_mb_2u(sch_1):page110";
BODY = "Q_RES","I47": LOCATION = "R75" #&CDS_LOCATION = "R75" &SEC = "1" #&CDS_SEC = "1";
"A":   PN = "1"  !CDS_PN = "1";
"B":   PN = "2"  !CDS_PN = "2";
BODY = "Q_CAP","I120": LOCATION = "C81" #&CDS_LOCATION = "C81" &SEC = "1" #&CDS_SEC = "1";
"A":   PN = "1"  !CDS_PN = "1";
"B":   PN = "2"  !CDS_PN = "2";
BODY = "Q_CAP","I124": LOCATION = "C82" #&CDS_LOCATION = "C82" &SEC = "1" #&CDS_SEC = "1";
"A":   PN = "1"  !CDS_PN = "1";
"B":   PN = "2"  !CDS_PN = "2";
BODY = "Q_CAP","I126": LOCATION = "C83" #&CDS_LOCATION = "C83" &SEC = "1" #&CDS_SEC = "1";
"A":   PN = "1"  !CDS_PN = "1";
"B":   PN = "2"  !CDS_PN = "2";
BODY = "SCONN288_ADR50017P130CC","I178": LOCATION = "J29" #&CDS_LOCATION = "J29" &SEC = "3" #&CDS_SEC = "3";
"G1":   PN = "G1"  !CDS_PN = "G1";
"G2":   PN = "G2"  !CDS_PN = "G2";
"G3":   PN = "G3"  !CDS_PN = "G3";
"VIN_BULK0":   PN = "1"  !CDS_PN = "1";
"VIN_BULK1":   PN = "145"  !CDS_PN = "145";
"VIN_BULK2":   PN = "146"  !CDS_PN = "146";
"VSS0":   PN = "6"  !CDS_PN = "6";
"VSS1":   PN = "8"  !CDS_PN = "8";
"VSS2":   PN = "10"  !CDS_PN = "10";
"VSS3":   PN = "13"  !CDS_PN = "13";
"VSS4":   PN = "15"  !CDS_PN = "15";
"VSS5":   PN = "17"  !CDS_PN = "17";
"VSS6":   PN = "19"  !CDS_PN = "19";
"VSS7":   PN = "21"  !CDS_PN = "21";
"VSS8":   PN = "24"  !CDS_PN = "24";
"VSS9":   PN = "26"  !CDS_PN = "26";
"VSS10":   PN = "28"  !CDS_PN = "28";
"VSS11":   PN = "30"  !CDS_PN = "30";
"VSS12":   PN = "32"  !CDS_PN = "32";
"VSS13":   PN = "35"  !CDS_PN = "35";
"VSS14":   PN = "37"  !CDS_PN = "37";
"VSS15":   PN = "39"  !CDS_PN = "39";
"VSS16":   PN = "41"  !CDS_PN = "41";
"VSS17":   PN = "43"  !CDS_PN = "43";
"VSS18":   PN = "46"  !CDS_PN = "46";
"VSS19":   PN = "48"  !CDS_PN = "48";
"VSS20":   PN = "50"  !CDS_PN = "50";
"VSS21":   PN = "52"  !CDS_PN = "52";
"VSS22":   PN = "54"  !CDS_PN = "54";
"VSS23":   PN = "57"  !CDS_PN = "57";
"VSS24":   PN = "59"  !CDS_PN = "59";
"VSS25":   PN = "61"  !CDS_PN = "61";
"VSS26":   PN = "63"  !CDS_PN = "63";
"VSS27":   PN = "65"  !CDS_PN = "65";
"VSS28":   PN = "67"  !CDS_PN = "67";
"VSS29":   PN = "69"  !CDS_PN = "69";
"VSS30":   PN = "71"  !CDS_PN = "71";
"VSS31":   PN = "73"  !CDS_PN = "73";
"VSS32":   PN = "75"  !CDS_PN = "75";
"VSS33":   PN = "77"  !CDS_PN = "77";
"VSS34":   PN = "79"  !CDS_PN = "79";
"VSS35":   PN = "81"  !CDS_PN = "81";
"VSS36":   PN = "83"  !CDS_PN = "83";
"VSS37":   PN = "85"  !CDS_PN = "85";
"VSS38":   PN = "88"  !CDS_PN = "88";
"VSS39":   PN = "90"  !CDS_PN = "90";
"VSS40":   PN = "92"  !CDS_PN = "92";
"VSS41":   PN = "95"  !CDS_PN = "95";
"VSS42":   PN = "97"  !CDS_PN = "97";
"VSS43":   PN = "99"  !CDS_PN = "99";
"VSS44":   PN = "101"  !CDS_PN = "101";
"VSS45":   PN = "103"  !CDS_PN = "103";
"VSS46":   PN = "106"  !CDS_PN = "106";
"VSS47":   PN = "108"  !CDS_PN = "108";
"VSS48":   PN = "110"  !CDS_PN = "110";
"VSS49":   PN = "112"  !CDS_PN = "112";
"VSS50":   PN = "114"  !CDS_PN = "114";
"VSS51":   PN = "117"  !CDS_PN = "117";
"VSS52":   PN = "119"  !CDS_PN = "119";
"VSS53":   PN = "121"  !CDS_PN = "121";
"VSS54":   PN = "123"  !CDS_PN = "123";
"VSS55":   PN = "125"  !CDS_PN = "125";
"VSS56":   PN = "128"  !CDS_PN = "128";
"VSS57":   PN = "130"  !CDS_PN = "130";
"VSS58":   PN = "132"  !CDS_PN = "132";
"VSS59":   PN = "134"  !CDS_PN = "134";
"VSS60":   PN = "136"  !CDS_PN = "136";
"VSS61":   PN = "139"  !CDS_PN = "139";
"VSS62":   PN = "141"  !CDS_PN = "141";
"VSS63":   PN = "143"  !CDS_PN = "143";
"VSS64":   PN = "151"  !CDS_PN = "151";
"VSS65":   PN = "153"  !CDS_PN = "153";
"VSS66":   PN = "155"  !CDS_PN = "155";
"VSS67":   PN = "158"  !CDS_PN = "158";
"VSS68":   PN = "160"  !CDS_PN = "160";
"VSS69":   PN = "162"  !CDS_PN = "162";
"VSS70":   PN = "164"  !CDS_PN = "164";
"VSS71":   PN = "166"  !CDS_PN = "166";
"VSS72":   PN = "169"  !CDS_PN = "169";
"VSS73":   PN = "171"  !CDS_PN = "171";
"VSS74":   PN = "173"  !CDS_PN = "173";
"VSS75":   PN = "175"  !CDS_PN = "175";
"VSS76":   PN = "177"  !CDS_PN = "177";
"VSS77":   PN = "180"  !CDS_PN = "180";
"VSS78":   PN = "182"  !CDS_PN = "182";
"VSS79":   PN = "184"  !CDS_PN = "184";
"VSS80":   PN = "186"  !CDS_PN = "186";
"VSS81":   PN = "188"  !CDS_PN = "188";
"VSS82":   PN = "191"  !CDS_PN = "191";
"VSS83":   PN = "193"  !CDS_PN = "193";
"VSS84":   PN = "195"  !CDS_PN = "195";
"VSS85":   PN = "197"  !CDS_PN = "197";
"VSS86":   PN = "199"  !CDS_PN = "199";
"VSS87":   PN = "202"  !CDS_PN = "202";
"VSS88":   PN = "204"  !CDS_PN = "204";
"VSS89":   PN = "206"  !CDS_PN = "206";
"VSS90":   PN = "208"  !CDS_PN = "208";
"VSS91":   PN = "210"  !CDS_PN = "210";
"VSS92":   PN = "212"  !CDS_PN = "212";
"VSS93":   PN = "214"  !CDS_PN = "214";
"VSS94":   PN = "216"  !CDS_PN = "216";
"VSS95":   PN = "219"  !CDS_PN = "219";
"VSS96":   PN = "222"  !CDS_PN = "222";
"VSS97":   PN = "224"  !CDS_PN = "224";
"VSS98":   PN = "226"  !CDS_PN = "226";
"VSS99":   PN = "228"  !CDS_PN = "228";
"VSS100":   PN = "230"  !CDS_PN = "230";
"VSS101":   PN = "233"  !CDS_PN = "233";
"VSS102":   PN = "235"  !CDS_PN = "235";
"VSS103":   PN = "237"  !CDS_PN = "237";
"VSS104":   PN = "240"  !CDS_PN = "240";
"VSS105":   PN = "242"  !CDS_PN = "242";
"VSS106":   PN = "244"  !CDS_PN = "244";
"VSS107":   PN = "246"  !CDS_PN = "246";
"VSS108":   PN = "248"  !CDS_PN = "248";
"VSS109":   PN = "251"  !CDS_PN = "251";
"VSS110":   PN = "253"  !CDS_PN = "253";
"VSS111":   PN = "255"  !CDS_PN = "255";
"VSS112":   PN = "257"  !CDS_PN = "257";
"VSS113":   PN = "259"  !CDS_PN = "259";
"VSS114":   PN = "262"  !CDS_PN = "262";
"VSS115":   PN = "264"  !CDS_PN = "264";
"VSS116":   PN = "266"  !CDS_PN = "266";
"VSS117":   PN = "268"  !CDS_PN = "268";
"VSS118":   PN = "270"  !CDS_PN = "270";
"VSS119":   PN = "273"  !CDS_PN = "273";
"VSS120":   PN = "275"  !CDS_PN = "275";
"VSS121":   PN = "277"  !CDS_PN = "277";
"VSS122":   PN = "279"  !CDS_PN = "279";
"VSS123":   PN = "281"  !CDS_PN = "281";
"VSS124":   PN = "284"  !CDS_PN = "284";
"VSS125":   PN = "286"  !CDS_PN = "286";
"VSS126":   PN = "288"  !CDS_PN = "288";
BODY = "SCONN288_ADR50017P130CC","I179": LOCATION = "J29" #&CDS_LOCATION = "J29" &SEC = "1" #&CDS_SEC = "1";
"ALERT_N":   PN = "62"  !CDS_PN = "62";
"CA0_A":   PN = "66"  !CDS_PN = "66";
"CA0_B":   PN = "76"  !CDS_PN = "76";
"CA1_A":   PN = "211"  !CDS_PN = "211";
"CA1_B":   PN = "221"  !CDS_PN = "221";
"CA2_A":   PN = "68"  !CDS_PN = "68";
"CA2_B":   PN = "78"  !CDS_PN = "78";
"CA3_A":   PN = "213"  !CDS_PN = "213";
"CA3_B":   PN = "223"  !CDS_PN = "223";
"CA4_A":   PN = "70"  !CDS_PN = "70";
"CA4_B":   PN = "80"  !CDS_PN = "80";
"CA5_A":   PN = "215"  !CDS_PN = "215";
"CA5_B":   PN = "225"  !CDS_PN = "225";
"CA6_A":   PN = "72"  !CDS_PN = "72";
"CA6_B":   PN = "82"  !CDS_PN = "82";
"CB0_A":   PN = "51"  !CDS_PN = "51";
"CB0_B":   PN = "96"  !CDS_PN = "96";
"CB1_A":   PN = "53"  !CDS_PN = "53";
"CB1_B":   PN = "98"  !CDS_PN = "98";
"CB2_A":   PN = "196"  !CDS_PN = "196";
"CB2_B":   PN = "241"  !CDS_PN = "241";
"CB3_A":   PN = "198"  !CDS_PN = "198";
"CB3_B":   PN = "243"  !CDS_PN = "243";
"CB4_A":   PN = "58"  !CDS_PN = "58";
"CB4_B":   PN = "89"  !CDS_PN = "89";
"CB5_A":   PN = "60"  !CDS_PN = "60";
"CB5_B":   PN = "91"  !CDS_PN = "91";
"CB6_A":   PN = "203"  !CDS_PN = "203";
"CB6_B":   PN = "234"  !CDS_PN = "234";
"CB7_A":   PN = "205"  !CDS_PN = "205";
"CB7_B":   PN = "236"  !CDS_PN = "236";
"CK_C":   PN = "218"  !CDS_PN = "218";
"CK_T":   PN = "217"  !CDS_PN = "217";
"CS0_A_N":   PN = "64"  !CDS_PN = "64";
"CS0_B_N":   PN = "84"  !CDS_PN = "84";
"CS1_A_N":   PN = "209"  !CDS_PN = "209";
"CS1_B_N":   PN = "229"  !CDS_PN = "229";
"DQ0_A":   PN = "7"  !CDS_PN = "7";
"DQ0_B":   PN = "100"  !CDS_PN = "100";
"DQ1_A":   PN = "9"  !CDS_PN = "9";
"DQ1_B":   PN = "102"  !CDS_PN = "102";
"DQ2_A":   PN = "152"  !CDS_PN = "152";
"DQ2_B":   PN = "245"  !CDS_PN = "245";
"DQ3_A":   PN = "154"  !CDS_PN = "154";
"DQ3_B":   PN = "247"  !CDS_PN = "247";
"DQ4_A":   PN = "14"  !CDS_PN = "14";
"DQ4_B":   PN = "107"  !CDS_PN = "107";
"DQ5_A":   PN = "16"  !CDS_PN = "16";
"DQ5_B":   PN = "109"  !CDS_PN = "109";
"DQ6_A":   PN = "159"  !CDS_PN = "159";
"DQ6_B":   PN = "252"  !CDS_PN = "252";
"DQ7_A":   PN = "161"  !CDS_PN = "161";
"DQ7_B":   PN = "254"  !CDS_PN = "254";
"DQ8_A":   PN = "18"  !CDS_PN = "18";
"DQ8_B":   PN = "111"  !CDS_PN = "111";
"DQ9_A":   PN = "20"  !CDS_PN = "20";
"DQ9_B":   PN = "113"  !CDS_PN = "113";
"DQ10_A":   PN = "163"  !CDS_PN = "163";
"DQ10_B":   PN = "256"  !CDS_PN = "256";
"DQ11_A":   PN = "165"  !CDS_PN = "165";
"DQ11_B":   PN = "258"  !CDS_PN = "258";
"DQ12_A":   PN = "25"  !CDS_PN = "25";
"DQ12_B":   PN = "118"  !CDS_PN = "118";
"DQ13_A":   PN = "27"  !CDS_PN = "27";
"DQ13_B":   PN = "120"  !CDS_PN = "120";
"DQ14_A":   PN = "170"  !CDS_PN = "170";
"DQ14_B":   PN = "263"  !CDS_PN = "263";
"DQ15_A":   PN = "172"  !CDS_PN = "172";
"DQ15_B":   PN = "265"  !CDS_PN = "265";
"DQ16_A":   PN = "29"  !CDS_PN = "29";
"DQ16_B":   PN = "122"  !CDS_PN = "122";
"DQ17_A":   PN = "31"  !CDS_PN = "31";
"DQ17_B":   PN = "124"  !CDS_PN = "124";
"DQ18_A":   PN = "174"  !CDS_PN = "174";
"DQ18_B":   PN = "267"  !CDS_PN = "267";
"DQ19_A":   PN = "176"  !CDS_PN = "176";
"DQ19_B":   PN = "269"  !CDS_PN = "269";
"DQ20_A":   PN = "36"  !CDS_PN = "36";
"DQ20_B":   PN = "129"  !CDS_PN = "129";
"DQ21_A":   PN = "38"  !CDS_PN = "38";
"DQ21_B":   PN = "131"  !CDS_PN = "131";
"DQ22_A":   PN = "181"  !CDS_PN = "181";
"DQ22_B":   PN = "274"  !CDS_PN = "274";
"DQ23_A":   PN = "183"  !CDS_PN = "183";
"DQ23_B":   PN = "276"  !CDS_PN = "276";
"DQ24_A":   PN = "40"  !CDS_PN = "40";
"DQ24_B":   PN = "133"  !CDS_PN = "133";
"DQ25_A":   PN = "42"  !CDS_PN = "42";
"DQ25_B":   PN = "135"  !CDS_PN = "135";
"DQ26_A":   PN = "185"  !CDS_PN = "185";
"DQ26_B":   PN = "278"  !CDS_PN = "278";
"DQ27_A":   PN = "187"  !CDS_PN = "187";
"DQ27_B":   PN = "280"  !CDS_PN = "280";
"DQ28_A":   PN = "47"  !CDS_PN = "47";
"DQ28_B":   PN = "140"  !CDS_PN = "140";
"DQ29_A":   PN = "49"  !CDS_PN = "49";
"DQ29_B":   PN = "142"  !CDS_PN = "142";
"DQ30_A":   PN = "192"  !CDS_PN = "192";
"DQ30_B":   PN = "285"  !CDS_PN = "285";
"DQ31_A":   PN = "194"  !CDS_PN = "194";
"DQ31_B":   PN = "287"  !CDS_PN = "287";
"HSA":   PN = "148"  !CDS_PN = "148";
"HSCL":   PN = "4"  !CDS_PN = "4";
"HSDA":   PN = "5"  !CDS_PN = "5";
"LBD||RSP_A_N":   PN = "86"  !CDS_PN = "86";
"LBS||RSP_B_N":   PN = "87"  !CDS_PN = "87";
"PAR_A":   PN = "74"  !CDS_PN = "74";
"PAR_B":   PN = "227"  !CDS_PN = "227";
"PWR_GOOD||FAIL_N":   PN = "147"  !CDS_PN = "147";
"RESET_N":   PN = "207"  !CDS_PN = "207";
"RFU0":   PN = "2"  !CDS_PN = "2";
"RFU1":   PN = "144"  !CDS_PN = "144";
"RFU2":   PN = "149"  !CDS_PN = "149";
"RFU3":   PN = "150"  !CDS_PN = "150";
"RFU4":   PN = "220"  !CDS_PN = "220";
"RFU5":   PN = "231"  !CDS_PN = "231";
"RFU6":   PN = "232"  !CDS_PN = "232";
"VIN_MGMT":   PN = "3"  !CDS_PN = "3";
BODY = "SCONN288_ADR50017P130CC","I180": #LOCATION = "J29" !CDS_LOCATION = "J29" &SEC = "2" #&CDS_SEC = "2";
"DQS0_A_C":   PN = "12"  !CDS_PN = "12";
"DQS0_A_T":   PN = "11"  !CDS_PN = "11";
"DQS0_B_C":   PN = "105"  !CDS_PN = "105";
"DQS0_B_T":   PN = "104"  !CDS_PN = "104";
"DQS1_A_C":   PN = "23"  !CDS_PN = "23";
"DQS1_A_T":   PN = "22"  !CDS_PN = "22";
"DQS1_B_C":   PN = "116"  !CDS_PN = "116";
"DQS1_B_T":   PN = "115"  !CDS_PN = "115";
"DQS2_A_C":   PN = "34"  !CDS_PN = "34";
"DQS2_A_T":   PN = "33"  !CDS_PN = "33";
"DQS2_B_C":   PN = "127"  !CDS_PN = "127";
"DQS2_B_T":   PN = "126"  !CDS_PN = "126";
"DQS3_A_C":   PN = "45"  !CDS_PN = "45";
"DQS3_A_T":   PN = "44"  !CDS_PN = "44";
"DQS3_B_C":   PN = "138"  !CDS_PN = "138";
"DQS3_B_T":   PN = "137"  !CDS_PN = "137";
"DQS4_A_C":   PN = "56"  !CDS_PN = "56";
"DQS4_A_T":   PN = "55"  !CDS_PN = "55";
"DQS4_B_C":   PN = "238"  !CDS_PN = "238";
"DQS4_B_T":   PN = "239"  !CDS_PN = "239";
"DQS5_A_C||TDQS5_A_C||DQS5_A_T||TDQS5_A_T":   PN = "156"  !CDS_PN = "156";
"DQS5_A_T||TDQS5_A_T":   PN = "157"  !CDS_PN = "157";
"DQS5_B_C||TDQS5_B_C":   PN = "249"  !CDS_PN = "249";
"DQS5_B_T||TDQS5_B_T":   PN = "250"  !CDS_PN = "250";
"DQS6_A_C||TDQS6_A_C||DQS6_A_T||TDQS6_A_T":   PN = "167"  !CDS_PN = "167";
"DQS6_A_T||TDQS6_A_T":   PN = "168"  !CDS_PN = "168";
"DQS6_B_C||TDQS6_B_C":   PN = "260"  !CDS_PN = "260";
"DQS6_B_T||TDQS6_B_T":   PN = "261"  !CDS_PN = "261";
"DQS7_A_C||TDQS7_A_C":   PN = "178"  !CDS_PN = "178";
"DQS7_A_T||TDQS7_A_T":   PN = "179"  !CDS_PN = "179";
"DQS7_B_C||TDQS7_B_C":   PN = "271"  !CDS_PN = "271";
"DQS7_B_T||TDQS7_B_T":   PN = "272"  !CDS_PN = "272";
"DQS8_A_C||TDQS8_A_C":   PN = "189"  !CDS_PN = "189";
"DQS8_A_T||TDQS8_A_T":   PN = "190"  !CDS_PN = "190";
"DQS8_B_C||TDQS8_B_C":   PN = "282"  !CDS_PN = "282";
"DQS8_B_T||TDQS8_B_T":   PN = "283"  !CDS_PN = "283";
"DQS9_A_C||TDQS9_A_C":   PN = "200"  !CDS_PN = "200";
"DQS9_A_T||TDQS9_A_T":   PN = "201"  !CDS_PN = "201";
"DQS9_B_C||TDQS9_B_C":   PN = "94"  !CDS_PN = "94";
"DQS9_B_T||TDQS9_B_T||DBI4_B_N":   PN = "93"  !CDS_PN = "93";
BODY = "Q_RES","I182": LOCATION = "R3903" #&CDS_LOCATION = "R3903" &SEC = "1" #&CDS_SEC = "1";
"A":   PN = "1"  !CDS_PN = "1";
"B":   PN = "2"  !CDS_PN = "2";
DRAWING = "@s9s_mb_2u_lib.s9s_mb_2u(sch_1):page111";
BODY = "Q_RES","I5": LOCATION = "R74" #&CDS_LOCATION = "R74" &SEC = "1" #&CDS_SEC = "1";
"A":   PN = "1"  !CDS_PN = "1";
"B":   PN = "2"  !CDS_PN = "2";
BODY = "Q_CAP","I54": LOCATION = "C78" #&CDS_LOCATION = "C78" &SEC = "1" #&CDS_SEC = "1";
"A":   PN = "1"  !CDS_PN = "1";
"B":   PN = "2"  !CDS_PN = "2";
BODY = "Q_CAP","I56": LOCATION = "C79" #&CDS_LOCATION = "C79" &SEC = "1" #&CDS_SEC = "1";
"A":   PN = "1"  !CDS_PN = "1";
"B":   PN = "2"  !CDS_PN = "2";
BODY = "Q_CAP","I59": LOCATION = "C80" #&CDS_LOCATION = "C80" &SEC = "1" #&CDS_SEC = "1";
"A":   PN = "1"  !CDS_PN = "1";
"B":   PN = "2"  !CDS_PN = "2";
BODY = "SCONN288_ADR50017P087CC","I178": LOCATION = "J30" #&CDS_LOCATION = "J30" &SEC = "3" #&CDS_SEC = "3";
"G1":   PN = "G1"  !CDS_PN = "G1";
"G2":   PN = "G2"  !CDS_PN = "G2";
"G3":   PN = "G3"  !CDS_PN = "G3";
"VIN_BULK0":   PN = "1"  !CDS_PN = "1";
"VIN_BULK1":   PN = "145"  !CDS_PN = "145";
"VIN_BULK2":   PN = "146"  !CDS_PN = "146";
"VSS0":   PN = "6"  !CDS_PN = "6";
"VSS1":   PN = "8"  !CDS_PN = "8";
"VSS2":   PN = "10"  !CDS_PN = "10";
"VSS3":   PN = "13"  !CDS_PN = "13";
"VSS4":   PN = "15"  !CDS_PN = "15";
"VSS5":   PN = "17"  !CDS_PN = "17";
"VSS6":   PN = "19"  !CDS_PN = "19";
"VSS7":   PN = "21"  !CDS_PN = "21";
"VSS8":   PN = "24"  !CDS_PN = "24";
"VSS9":   PN = "26"  !CDS_PN = "26";
"VSS10":   PN = "28"  !CDS_PN = "28";
"VSS11":   PN = "30"  !CDS_PN = "30";
"VSS12":   PN = "32"  !CDS_PN = "32";
"VSS13":   PN = "35"  !CDS_PN = "35";
"VSS14":   PN = "37"  !CDS_PN = "37";
"VSS15":   PN = "39"  !CDS_PN = "39";
"VSS16":   PN = "41"  !CDS_PN = "41";
"VSS17":   PN = "43"  !CDS_PN = "43";
"VSS18":   PN = "46"  !CDS_PN = "46";
"VSS19":   PN = "48"  !CDS_PN = "48";
"VSS20":   PN = "50"  !CDS_PN = "50";
"VSS21":   PN = "52"  !CDS_PN = "52";
"VSS22":   PN = "54"  !CDS_PN = "54";
"VSS23":   PN = "57"  !CDS_PN = "57";
"VSS24":   PN = "59"  !CDS_PN = "59";
"VSS25":   PN = "61"  !CDS_PN = "61";
"VSS26":   PN = "63"  !CDS_PN = "63";
"VSS27":   PN = "65"  !CDS_PN = "65";
"VSS28":   PN = "67"  !CDS_PN = "67";
"VSS29":   PN = "69"  !CDS_PN = "69";
"VSS30":   PN = "71"  !CDS_PN = "71";
"VSS31":   PN = "73"  !CDS_PN = "73";
"VSS32":   PN = "75"  !CDS_PN = "75";
"VSS33":   PN = "77"  !CDS_PN = "77";
"VSS34":   PN = "79"  !CDS_PN = "79";
"VSS35":   PN = "81"  !CDS_PN = "81";
"VSS36":   PN = "83"  !CDS_PN = "83";
"VSS37":   PN = "85"  !CDS_PN = "85";
"VSS38":   PN = "88"  !CDS_PN = "88";
"VSS39":   PN = "90"  !CDS_PN = "90";
"VSS40":   PN = "92"  !CDS_PN = "92";
"VSS41":   PN = "95"  !CDS_PN = "95";
"VSS42":   PN = "97"  !CDS_PN = "97";
"VSS43":   PN = "99"  !CDS_PN = "99";
"VSS44":   PN = "101"  !CDS_PN = "101";
"VSS45":   PN = "103"  !CDS_PN = "103";
"VSS46":   PN = "106"  !CDS_PN = "106";
"VSS47":   PN = "108"  !CDS_PN = "108";
"VSS48":   PN = "110"  !CDS_PN = "110";
"VSS49":   PN = "112"  !CDS_PN = "112";
"VSS50":   PN = "114"  !CDS_PN = "114";
"VSS51":   PN = "117"  !CDS_PN = "117";
"VSS52":   PN = "119"  !CDS_PN = "119";
"VSS53":   PN = "121"  !CDS_PN = "121";
"VSS54":   PN = "123"  !CDS_PN = "123";
"VSS55":   PN = "125"  !CDS_PN = "125";
"VSS56":   PN = "128"  !CDS_PN = "128";
"VSS57":   PN = "130"  !CDS_PN = "130";
"VSS58":   PN = "132"  !CDS_PN = "132";
"VSS59":   PN = "134"  !CDS_PN = "134";
"VSS60":   PN = "136"  !CDS_PN = "136";
"VSS61":   PN = "139"  !CDS_PN = "139";
"VSS62":   PN = "141"  !CDS_PN = "141";
"VSS63":   PN = "143"  !CDS_PN = "143";
"VSS64":   PN = "151"  !CDS_PN = "151";
"VSS65":   PN = "153"  !CDS_PN = "153";
"VSS66":   PN = "155"  !CDS_PN = "155";
"VSS67":   PN = "158"  !CDS_PN = "158";
"VSS68":   PN = "160"  !CDS_PN = "160";
"VSS69":   PN = "162"  !CDS_PN = "162";
"VSS70":   PN = "164"  !CDS_PN = "164";
"VSS71":   PN = "166"  !CDS_PN = "166";
"VSS72":   PN = "169"  !CDS_PN = "169";
"VSS73":   PN = "171"  !CDS_PN = "171";
"VSS74":   PN = "173"  !CDS_PN = "173";
"VSS75":   PN = "175"  !CDS_PN = "175";
"VSS76":   PN = "177"  !CDS_PN = "177";
"VSS77":   PN = "180"  !CDS_PN = "180";
"VSS78":   PN = "182"  !CDS_PN = "182";
"VSS79":   PN = "184"  !CDS_PN = "184";
"VSS80":   PN = "186"  !CDS_PN = "186";
"VSS81":   PN = "188"  !CDS_PN = "188";
"VSS82":   PN = "191"  !CDS_PN = "191";
"VSS83":   PN = "193"  !CDS_PN = "193";
"VSS84":   PN = "195"  !CDS_PN = "195";
"VSS85":   PN = "197"  !CDS_PN = "197";
"VSS86":   PN = "199"  !CDS_PN = "199";
"VSS87":   PN = "202"  !CDS_PN = "202";
"VSS88":   PN = "204"  !CDS_PN = "204";
"VSS89":   PN = "206"  !CDS_PN = "206";
"VSS90":   PN = "208"  !CDS_PN = "208";
"VSS91":   PN = "210"  !CDS_PN = "210";
"VSS92":   PN = "212"  !CDS_PN = "212";
"VSS93":   PN = "214"  !CDS_PN = "214";
"VSS94":   PN = "216"  !CDS_PN = "216";
"VSS95":   PN = "219"  !CDS_PN = "219";
"VSS96":   PN = "222"  !CDS_PN = "222";
"VSS97":   PN = "224"  !CDS_PN = "224";
"VSS98":   PN = "226"  !CDS_PN = "226";
"VSS99":   PN = "228"  !CDS_PN = "228";
"VSS100":   PN = "230"  !CDS_PN = "230";
"VSS101":   PN = "233"  !CDS_PN = "233";
"VSS102":   PN = "235"  !CDS_PN = "235";
"VSS103":   PN = "237"  !CDS_PN = "237";
"VSS104":   PN = "240"  !CDS_PN = "240";
"VSS105":   PN = "242"  !CDS_PN = "242";
"VSS106":   PN = "244"  !CDS_PN = "244";
"VSS107":   PN = "246"  !CDS_PN = "246";
"VSS108":   PN = "248"  !CDS_PN = "248";
"VSS109":   PN = "251"  !CDS_PN = "251";
"VSS110":   PN = "253"  !CDS_PN = "253";
"VSS111":   PN = "255"  !CDS_PN = "255";
"VSS112":   PN = "257"  !CDS_PN = "257";
"VSS113":   PN = "259"  !CDS_PN = "259";
"VSS114":   PN = "262"  !CDS_PN = "262";
"VSS115":   PN = "264"  !CDS_PN = "264";
"VSS116":   PN = "266"  !CDS_PN = "266";
"VSS117":   PN = "268"  !CDS_PN = "268";
"VSS118":   PN = "270"  !CDS_PN = "270";
"VSS119":   PN = "273"  !CDS_PN = "273";
"VSS120":   PN = "275"  !CDS_PN = "275";
"VSS121":   PN = "277"  !CDS_PN = "277";
"VSS122":   PN = "279"  !CDS_PN = "279";
"VSS123":   PN = "281"  !CDS_PN = "281";
"VSS124":   PN = "284"  !CDS_PN = "284";
"VSS125":   PN = "286"  !CDS_PN = "286";
"VSS126":   PN = "288"  !CDS_PN = "288";
BODY = "SCONN288_ADR50017P087CC","I179": LOCATION = "J30" #&CDS_LOCATION = "J30" &SEC = "1" #&CDS_SEC = "1";
"ALERT_N":   PN = "62"  !CDS_PN = "62";
"CA0_A":   PN = "66"  !CDS_PN = "66";
"CA0_B":   PN = "76"  !CDS_PN = "76";
"CA1_A":   PN = "211"  !CDS_PN = "211";
"CA1_B":   PN = "221"  !CDS_PN = "221";
"CA2_A":   PN = "68"  !CDS_PN = "68";
"CA2_B":   PN = "78"  !CDS_PN = "78";
"CA3_A":   PN = "213"  !CDS_PN = "213";
"CA3_B":   PN = "223"  !CDS_PN = "223";
"CA4_A":   PN = "70"  !CDS_PN = "70";
"CA4_B":   PN = "80"  !CDS_PN = "80";
"CA5_A":   PN = "215"  !CDS_PN = "215";
"CA5_B":   PN = "225"  !CDS_PN = "225";
"CA6_A":   PN = "72"  !CDS_PN = "72";
"CA6_B":   PN = "82"  !CDS_PN = "82";
"CB0_A":   PN = "51"  !CDS_PN = "51";
"CB0_B":   PN = "96"  !CDS_PN = "96";
"CB1_A":   PN = "53"  !CDS_PN = "53";
"CB1_B":   PN = "98"  !CDS_PN = "98";
"CB2_A":   PN = "196"  !CDS_PN = "196";
"CB2_B":   PN = "241"  !CDS_PN = "241";
"CB3_A":   PN = "198"  !CDS_PN = "198";
"CB3_B":   PN = "243"  !CDS_PN = "243";
"CB4_A":   PN = "58"  !CDS_PN = "58";
"CB4_B":   PN = "89"  !CDS_PN = "89";
"CB5_A":   PN = "60"  !CDS_PN = "60";
"CB5_B":   PN = "91"  !CDS_PN = "91";
"CB6_A":   PN = "203"  !CDS_PN = "203";
"CB6_B":   PN = "234"  !CDS_PN = "234";
"CB7_A":   PN = "205"  !CDS_PN = "205";
"CB7_B":   PN = "236"  !CDS_PN = "236";
"CK_C":   PN = "218"  !CDS_PN = "218";
"CK_T":   PN = "217"  !CDS_PN = "217";
"CS0_A_N":   PN = "64"  !CDS_PN = "64";
"CS0_B_N":   PN = "84"  !CDS_PN = "84";
"CS1_A_N":   PN = "209"  !CDS_PN = "209";
"CS1_B_N":   PN = "229"  !CDS_PN = "229";
"DQ0_A":   PN = "7"  !CDS_PN = "7";
"DQ0_B":   PN = "100"  !CDS_PN = "100";
"DQ1_A":   PN = "9"  !CDS_PN = "9";
"DQ1_B":   PN = "102"  !CDS_PN = "102";
"DQ2_A":   PN = "152"  !CDS_PN = "152";
"DQ2_B":   PN = "245"  !CDS_PN = "245";
"DQ3_A":   PN = "154"  !CDS_PN = "154";
"DQ3_B":   PN = "247"  !CDS_PN = "247";
"DQ4_A":   PN = "14"  !CDS_PN = "14";
"DQ4_B":   PN = "107"  !CDS_PN = "107";
"DQ5_A":   PN = "16"  !CDS_PN = "16";
"DQ5_B":   PN = "109"  !CDS_PN = "109";
"DQ6_A":   PN = "159"  !CDS_PN = "159";
"DQ6_B":   PN = "252"  !CDS_PN = "252";
"DQ7_A":   PN = "161"  !CDS_PN = "161";
"DQ7_B":   PN = "254"  !CDS_PN = "254";
"DQ8_A":   PN = "18"  !CDS_PN = "18";
"DQ8_B":   PN = "111"  !CDS_PN = "111";
"DQ9_A":   PN = "20"  !CDS_PN = "20";
"DQ9_B":   PN = "113"  !CDS_PN = "113";
"DQ10_A":   PN = "163"  !CDS_PN = "163";
"DQ10_B":   PN = "256"  !CDS_PN = "256";
"DQ11_A":   PN = "165"  !CDS_PN = "165";
"DQ11_B":   PN = "258"  !CDS_PN = "258";
"DQ12_A":   PN = "25"  !CDS_PN = "25";
"DQ12_B":   PN = "118"  !CDS_PN = "118";
"DQ13_A":   PN = "27"  !CDS_PN = "27";
"DQ13_B":   PN = "120"  !CDS_PN = "120";
"DQ14_A":   PN = "170"  !CDS_PN = "170";
"DQ14_B":   PN = "263"  !CDS_PN = "263";
"DQ15_A":   PN = "172"  !CDS_PN = "172";
"DQ15_B":   PN = "265"  !CDS_PN = "265";
"DQ16_A":   PN = "29"  !CDS_PN = "29";
"DQ16_B":   PN = "122"  !CDS_PN = "122";
"DQ17_A":   PN = "31"  !CDS_PN = "31";
"DQ17_B":   PN = "124"  !CDS_PN = "124";
"DQ18_A":   PN = "174"  !CDS_PN = "174";
"DQ18_B":   PN = "267"  !CDS_PN = "267";
"DQ19_A":   PN = "176"  !CDS_PN = "176";
"DQ19_B":   PN = "269"  !CDS_PN = "269";
"DQ20_A":   PN = "36"  !CDS_PN = "36";
"DQ20_B":   PN = "129"  !CDS_PN = "129";
"DQ21_A":   PN = "38"  !CDS_PN = "38";
"DQ21_B":   PN = "131"  !CDS_PN = "131";
"DQ22_A":   PN = "181"  !CDS_PN = "181";
"DQ22_B":   PN = "274"  !CDS_PN = "274";
"DQ23_A":   PN = "183"  !CDS_PN = "183";
"DQ23_B":   PN = "276"  !CDS_PN = "276";
"DQ24_A":   PN = "40"  !CDS_PN = "40";
"DQ24_B":   PN = "133"  !CDS_PN = "133";
"DQ25_A":   PN = "42"  !CDS_PN = "42";
"DQ25_B":   PN = "135"  !CDS_PN = "135";
"DQ26_A":   PN = "185"  !CDS_PN = "185";
"DQ26_B":   PN = "278"  !CDS_PN = "278";
"DQ27_A":   PN = "187"  !CDS_PN = "187";
"DQ27_B":   PN = "280"  !CDS_PN = "280";
"DQ28_A":   PN = "47"  !CDS_PN = "47";
"DQ28_B":   PN = "140"  !CDS_PN = "140";
"DQ29_A":   PN = "49"  !CDS_PN = "49";
"DQ29_B":   PN = "142"  !CDS_PN = "142";
"DQ30_A":   PN = "192"  !CDS_PN = "192";
"DQ30_B":   PN = "285"  !CDS_PN = "285";
"DQ31_A":   PN = "194"  !CDS_PN = "194";
"DQ31_B":   PN = "287"  !CDS_PN = "287";
"HSA":   PN = "148"  !CDS_PN = "148";
"HSCL":   PN = "4"  !CDS_PN = "4";
"HSDA":   PN = "5"  !CDS_PN = "5";
"LBD||RSP_A_N":   PN = "86"  !CDS_PN = "86";
"LBS||RSP_B_N":   PN = "87"  !CDS_PN = "87";
"PAR_A":   PN = "74"  !CDS_PN = "74";
"PAR_B":   PN = "227"  !CDS_PN = "227";
"PWR_GOOD||FAIL_N":   PN = "147"  !CDS_PN = "147";
"RESET_N":   PN = "207"  !CDS_PN = "207";
"RFU0":   PN = "2"  !CDS_PN = "2";
"RFU1":   PN = "144"  !CDS_PN = "144";
"RFU2":   PN = "149"  !CDS_PN = "149";
"RFU3":   PN = "150"  !CDS_PN = "150";
"RFU4":   PN = "220"  !CDS_PN = "220";
"RFU5":   PN = "231"  !CDS_PN = "231";
"RFU6":   PN = "232"  !CDS_PN = "232";
"VIN_MGMT":   PN = "3"  !CDS_PN = "3";
BODY = "SCONN288_ADR50017P087CC","I180": #LOCATION = "J30" !CDS_LOCATION = "J30" &SEC = "2" #&CDS_SEC = "2";
"DQS0_A_C":   PN = "12"  !CDS_PN = "12";
"DQS0_A_T":   PN = "11"  !CDS_PN = "11";
"DQS0_B_C":   PN = "105"  !CDS_PN = "105";
"DQS0_B_T":   PN = "104"  !CDS_PN = "104";
"DQS1_A_C":   PN = "23"  !CDS_PN = "23";
"DQS1_A_T":   PN = "22"  !CDS_PN = "22";
"DQS1_B_C":   PN = "116"  !CDS_PN = "116";
"DQS1_B_T":   PN = "115"  !CDS_PN = "115";
"DQS2_A_C":   PN = "34"  !CDS_PN = "34";
"DQS2_A_T":   PN = "33"  !CDS_PN = "33";
"DQS2_B_C":   PN = "127"  !CDS_PN = "127";
"DQS2_B_T":   PN = "126"  !CDS_PN = "126";
"DQS3_A_C":   PN = "45"  !CDS_PN = "45";
"DQS3_A_T":   PN = "44"  !CDS_PN = "44";
"DQS3_B_C":   PN = "138"  !CDS_PN = "138";
"DQS3_B_T":   PN = "137"  !CDS_PN = "137";
"DQS4_A_C":   PN = "56"  !CDS_PN = "56";
"DQS4_A_T":   PN = "55"  !CDS_PN = "55";
"DQS4_B_C":   PN = "238"  !CDS_PN = "238";
"DQS4_B_T":   PN = "239"  !CDS_PN = "239";
"DQS5_A_C||TDQS5_A_C||DQS5_A_T||TDQS5_A_T":   PN = "156"  !CDS_PN = "156";
"DQS5_A_T||TDQS5_A_T":   PN = "157"  !CDS_PN = "157";
"DQS5_B_C||TDQS5_B_C":   PN = "249"  !CDS_PN = "249";
"DQS5_B_T||TDQS5_B_T":   PN = "250"  !CDS_PN = "250";
"DQS6_A_C||TDQS6_A_C||DQS6_A_T||TDQS6_A_T":   PN = "167"  !CDS_PN = "167";
"DQS6_A_T||TDQS6_A_T":   PN = "168"  !CDS_PN = "168";
"DQS6_B_C||TDQS6_B_C":   PN = "260"  !CDS_PN = "260";
"DQS6_B_T||TDQS6_B_T":   PN = "261"  !CDS_PN = "261";
"DQS7_A_C||TDQS7_A_C":   PN = "178"  !CDS_PN = "178";
"DQS7_A_T||TDQS7_A_T":   PN = "179"  !CDS_PN = "179";
"DQS7_B_C||TDQS7_B_C":   PN = "271"  !CDS_PN = "271";
"DQS7_B_T||TDQS7_B_T":   PN = "272"  !CDS_PN = "272";
"DQS8_A_C||TDQS8_A_C":   PN = "189"  !CDS_PN = "189";
"DQS8_A_T||TDQS8_A_T":   PN = "190"  !CDS_PN = "190";
"DQS8_B_C||TDQS8_B_C":   PN = "282"  !CDS_PN = "282";
"DQS8_B_T||TDQS8_B_T":   PN = "283"  !CDS_PN = "283";
"DQS9_A_C||TDQS9_A_C":   PN = "200"  !CDS_PN = "200";
"DQS9_A_T||TDQS9_A_T":   PN = "201"  !CDS_PN = "201";
"DQS9_B_C||TDQS9_B_C":   PN = "94"  !CDS_PN = "94";
"DQS9_B_T||TDQS9_B_T||DBI4_B_N":   PN = "93"  !CDS_PN = "93";
BODY = "Q_RES","I182": LOCATION = "R3904" #&CDS_LOCATION = "R3904" &SEC = "1" #&CDS_SEC = "1";
"A":   PN = "1"  !CDS_PN = "1";
"B":   PN = "2"  !CDS_PN = "2";
DRAWING = "@s9s_mb_2u_lib.s9s_mb_2u(sch_1):page112";
BODY = "Q_RES","I3": LOCATION = "R73" #&CDS_LOCATION = "R73" &SEC = "1" #&CDS_SEC = "1";
"A":   PN = "1"  !CDS_PN = "1";
"B":   PN = "2"  !CDS_PN = "2";
BODY = "Q_CAP","I124": LOCATION = "C75" #&CDS_LOCATION = "C75" &SEC = "1" #&CDS_SEC = "1";
"A":   PN = "1"  !CDS_PN = "1";
"B":   PN = "2"  !CDS_PN = "2";
BODY = "Q_CAP","I125": LOCATION = "C76" #&CDS_LOCATION = "C76" &SEC = "1" #&CDS_SEC = "1";
"A":   PN = "1"  !CDS_PN = "1";
"B":   PN = "2"  !CDS_PN = "2";
BODY = "Q_CAP","I126": LOCATION = "C77" #&CDS_LOCATION = "C77" &SEC = "1" #&CDS_SEC = "1";
"A":   PN = "1"  !CDS_PN = "1";
"B":   PN = "2"  !CDS_PN = "2";
BODY = "SCONN288_ADR50017P130CC","I178": LOCATION = "J31" #&CDS_LOCATION = "J31" &SEC = "3" #&CDS_SEC = "3";
"G1":   PN = "G1"  !CDS_PN = "G1";
"G2":   PN = "G2"  !CDS_PN = "G2";
"G3":   PN = "G3"  !CDS_PN = "G3";
"VIN_BULK0":   PN = "1"  !CDS_PN = "1";
"VIN_BULK1":   PN = "145"  !CDS_PN = "145";
"VIN_BULK2":   PN = "146"  !CDS_PN = "146";
"VSS0":   PN = "6"  !CDS_PN = "6";
"VSS1":   PN = "8"  !CDS_PN = "8";
"VSS2":   PN = "10"  !CDS_PN = "10";
"VSS3":   PN = "13"  !CDS_PN = "13";
"VSS4":   PN = "15"  !CDS_PN = "15";
"VSS5":   PN = "17"  !CDS_PN = "17";
"VSS6":   PN = "19"  !CDS_PN = "19";
"VSS7":   PN = "21"  !CDS_PN = "21";
"VSS8":   PN = "24"  !CDS_PN = "24";
"VSS9":   PN = "26"  !CDS_PN = "26";
"VSS10":   PN = "28"  !CDS_PN = "28";
"VSS11":   PN = "30"  !CDS_PN = "30";
"VSS12":   PN = "32"  !CDS_PN = "32";
"VSS13":   PN = "35"  !CDS_PN = "35";
"VSS14":   PN = "37"  !CDS_PN = "37";
"VSS15":   PN = "39"  !CDS_PN = "39";
"VSS16":   PN = "41"  !CDS_PN = "41";
"VSS17":   PN = "43"  !CDS_PN = "43";
"VSS18":   PN = "46"  !CDS_PN = "46";
"VSS19":   PN = "48"  !CDS_PN = "48";
"VSS20":   PN = "50"  !CDS_PN = "50";
"VSS21":   PN = "52"  !CDS_PN = "52";
"VSS22":   PN = "54"  !CDS_PN = "54";
"VSS23":   PN = "57"  !CDS_PN = "57";
"VSS24":   PN = "59"  !CDS_PN = "59";
"VSS25":   PN = "61"  !CDS_PN = "61";
"VSS26":   PN = "63"  !CDS_PN = "63";
"VSS27":   PN = "65"  !CDS_PN = "65";
"VSS28":   PN = "67"  !CDS_PN = "67";
"VSS29":   PN = "69"  !CDS_PN = "69";
"VSS30":   PN = "71"  !CDS_PN = "71";
"VSS31":   PN = "73"  !CDS_PN = "73";
"VSS32":   PN = "75"  !CDS_PN = "75";
"VSS33":   PN = "77"  !CDS_PN = "77";
"VSS34":   PN = "79"  !CDS_PN = "79";
"VSS35":   PN = "81"  !CDS_PN = "81";
"VSS36":   PN = "83"  !CDS_PN = "83";
"VSS37":   PN = "85"  !CDS_PN = "85";
"VSS38":   PN = "88"  !CDS_PN = "88";
"VSS39":   PN = "90"  !CDS_PN = "90";
"VSS40":   PN = "92"  !CDS_PN = "92";
"VSS41":   PN = "95"  !CDS_PN = "95";
"VSS42":   PN = "97"  !CDS_PN = "97";
"VSS43":   PN = "99"  !CDS_PN = "99";
"VSS44":   PN = "101"  !CDS_PN = "101";
"VSS45":   PN = "103"  !CDS_PN = "103";
"VSS46":   PN = "106"  !CDS_PN = "106";
"VSS47":   PN = "108"  !CDS_PN = "108";
"VSS48":   PN = "110"  !CDS_PN = "110";
"VSS49":   PN = "112"  !CDS_PN = "112";
"VSS50":   PN = "114"  !CDS_PN = "114";
"VSS51":   PN = "117"  !CDS_PN = "117";
"VSS52":   PN = "119"  !CDS_PN = "119";
"VSS53":   PN = "121"  !CDS_PN = "121";
"VSS54":   PN = "123"  !CDS_PN = "123";
"VSS55":   PN = "125"  !CDS_PN = "125";
"VSS56":   PN = "128"  !CDS_PN = "128";
"VSS57":   PN = "130"  !CDS_PN = "130";
"VSS58":   PN = "132"  !CDS_PN = "132";
"VSS59":   PN = "134"  !CDS_PN = "134";
"VSS60":   PN = "136"  !CDS_PN = "136";
"VSS61":   PN = "139"  !CDS_PN = "139";
"VSS62":   PN = "141"  !CDS_PN = "141";
"VSS63":   PN = "143"  !CDS_PN = "143";
"VSS64":   PN = "151"  !CDS_PN = "151";
"VSS65":   PN = "153"  !CDS_PN = "153";
"VSS66":   PN = "155"  !CDS_PN = "155";
"VSS67":   PN = "158"  !CDS_PN = "158";
"VSS68":   PN = "160"  !CDS_PN = "160";
"VSS69":   PN = "162"  !CDS_PN = "162";
"VSS70":   PN = "164"  !CDS_PN = "164";
"VSS71":   PN = "166"  !CDS_PN = "166";
"VSS72":   PN = "169"  !CDS_PN = "169";
"VSS73":   PN = "171"  !CDS_PN = "171";
"VSS74":   PN = "173"  !CDS_PN = "173";
"VSS75":   PN = "175"  !CDS_PN = "175";
"VSS76":   PN = "177"  !CDS_PN = "177";
"VSS77":   PN = "180"  !CDS_PN = "180";
"VSS78":   PN = "182"  !CDS_PN = "182";
"VSS79":   PN = "184"  !CDS_PN = "184";
"VSS80":   PN = "186"  !CDS_PN = "186";
"VSS81":   PN = "188"  !CDS_PN = "188";
"VSS82":   PN = "191"  !CDS_PN = "191";
"VSS83":   PN = "193"  !CDS_PN = "193";
"VSS84":   PN = "195"  !CDS_PN = "195";
"VSS85":   PN = "197"  !CDS_PN = "197";
"VSS86":   PN = "199"  !CDS_PN = "199";
"VSS87":   PN = "202"  !CDS_PN = "202";
"VSS88":   PN = "204"  !CDS_PN = "204";
"VSS89":   PN = "206"  !CDS_PN = "206";
"VSS90":   PN = "208"  !CDS_PN = "208";
"VSS91":   PN = "210"  !CDS_PN = "210";
"VSS92":   PN = "212"  !CDS_PN = "212";
"VSS93":   PN = "214"  !CDS_PN = "214";
"VSS94":   PN = "216"  !CDS_PN = "216";
"VSS95":   PN = "219"  !CDS_PN = "219";
"VSS96":   PN = "222"  !CDS_PN = "222";
"VSS97":   PN = "224"  !CDS_PN = "224";
"VSS98":   PN = "226"  !CDS_PN = "226";
"VSS99":   PN = "228"  !CDS_PN = "228";
"VSS100":   PN = "230"  !CDS_PN = "230";
"VSS101":   PN = "233"  !CDS_PN = "233";
"VSS102":   PN = "235"  !CDS_PN = "235";
"VSS103":   PN = "237"  !CDS_PN = "237";
"VSS104":   PN = "240"  !CDS_PN = "240";
"VSS105":   PN = "242"  !CDS_PN = "242";
"VSS106":   PN = "244"  !CDS_PN = "244";
"VSS107":   PN = "246"  !CDS_PN = "246";
"VSS108":   PN = "248"  !CDS_PN = "248";
"VSS109":   PN = "251"  !CDS_PN = "251";
"VSS110":   PN = "253"  !CDS_PN = "253";
"VSS111":   PN = "255"  !CDS_PN = "255";
"VSS112":   PN = "257"  !CDS_PN = "257";
"VSS113":   PN = "259"  !CDS_PN = "259";
"VSS114":   PN = "262"  !CDS_PN = "262";
"VSS115":   PN = "264"  !CDS_PN = "264";
"VSS116":   PN = "266"  !CDS_PN = "266";
"VSS117":   PN = "268"  !CDS_PN = "268";
"VSS118":   PN = "270"  !CDS_PN = "270";
"VSS119":   PN = "273"  !CDS_PN = "273";
"VSS120":   PN = "275"  !CDS_PN = "275";
"VSS121":   PN = "277"  !CDS_PN = "277";
"VSS122":   PN = "279"  !CDS_PN = "279";
"VSS123":   PN = "281"  !CDS_PN = "281";
"VSS124":   PN = "284"  !CDS_PN = "284";
"VSS125":   PN = "286"  !CDS_PN = "286";
"VSS126":   PN = "288"  !CDS_PN = "288";
BODY = "SCONN288_ADR50017P130CC","I180": LOCATION = "J31" #&CDS_LOCATION = "J31" &SEC = "1" #&CDS_SEC = "1";
"ALERT_N":   PN = "62"  !CDS_PN = "62";
"CA0_A":   PN = "66"  !CDS_PN = "66";
"CA0_B":   PN = "76"  !CDS_PN = "76";
"CA1_A":   PN = "211"  !CDS_PN = "211";
"CA1_B":   PN = "221"  !CDS_PN = "221";
"CA2_A":   PN = "68"  !CDS_PN = "68";
"CA2_B":   PN = "78"  !CDS_PN = "78";
"CA3_A":   PN = "213"  !CDS_PN = "213";
"CA3_B":   PN = "223"  !CDS_PN = "223";
"CA4_A":   PN = "70"  !CDS_PN = "70";
"CA4_B":   PN = "80"  !CDS_PN = "80";
"CA5_A":   PN = "215"  !CDS_PN = "215";
"CA5_B":   PN = "225"  !CDS_PN = "225";
"CA6_A":   PN = "72"  !CDS_PN = "72";
"CA6_B":   PN = "82"  !CDS_PN = "82";
"CB0_A":   PN = "51"  !CDS_PN = "51";
"CB0_B":   PN = "96"  !CDS_PN = "96";
"CB1_A":   PN = "53"  !CDS_PN = "53";
"CB1_B":   PN = "98"  !CDS_PN = "98";
"CB2_A":   PN = "196"  !CDS_PN = "196";
"CB2_B":   PN = "241"  !CDS_PN = "241";
"CB3_A":   PN = "198"  !CDS_PN = "198";
"CB3_B":   PN = "243"  !CDS_PN = "243";
"CB4_A":   PN = "58"  !CDS_PN = "58";
"CB4_B":   PN = "89"  !CDS_PN = "89";
"CB5_A":   PN = "60"  !CDS_PN = "60";
"CB5_B":   PN = "91"  !CDS_PN = "91";
"CB6_A":   PN = "203"  !CDS_PN = "203";
"CB6_B":   PN = "234"  !CDS_PN = "234";
"CB7_A":   PN = "205"  !CDS_PN = "205";
"CB7_B":   PN = "236"  !CDS_PN = "236";
"CK_C":   PN = "218"  !CDS_PN = "218";
"CK_T":   PN = "217"  !CDS_PN = "217";
"CS0_A_N":   PN = "64"  !CDS_PN = "64";
"CS0_B_N":   PN = "84"  !CDS_PN = "84";
"CS1_A_N":   PN = "209"  !CDS_PN = "209";
"CS1_B_N":   PN = "229"  !CDS_PN = "229";
"DQ0_A":   PN = "7"  !CDS_PN = "7";
"DQ0_B":   PN = "100"  !CDS_PN = "100";
"DQ1_A":   PN = "9"  !CDS_PN = "9";
"DQ1_B":   PN = "102"  !CDS_PN = "102";
"DQ2_A":   PN = "152"  !CDS_PN = "152";
"DQ2_B":   PN = "245"  !CDS_PN = "245";
"DQ3_A":   PN = "154"  !CDS_PN = "154";
"DQ3_B":   PN = "247"  !CDS_PN = "247";
"DQ4_A":   PN = "14"  !CDS_PN = "14";
"DQ4_B":   PN = "107"  !CDS_PN = "107";
"DQ5_A":   PN = "16"  !CDS_PN = "16";
"DQ5_B":   PN = "109"  !CDS_PN = "109";
"DQ6_A":   PN = "159"  !CDS_PN = "159";
"DQ6_B":   PN = "252"  !CDS_PN = "252";
"DQ7_A":   PN = "161"  !CDS_PN = "161";
"DQ7_B":   PN = "254"  !CDS_PN = "254";
"DQ8_A":   PN = "18"  !CDS_PN = "18";
"DQ8_B":   PN = "111"  !CDS_PN = "111";
"DQ9_A":   PN = "20"  !CDS_PN = "20";
"DQ9_B":   PN = "113"  !CDS_PN = "113";
"DQ10_A":   PN = "163"  !CDS_PN = "163";
"DQ10_B":   PN = "256"  !CDS_PN = "256";
"DQ11_A":   PN = "165"  !CDS_PN = "165";
"DQ11_B":   PN = "258"  !CDS_PN = "258";
"DQ12_A":   PN = "25"  !CDS_PN = "25";
"DQ12_B":   PN = "118"  !CDS_PN = "118";
"DQ13_A":   PN = "27"  !CDS_PN = "27";
"DQ13_B":   PN = "120"  !CDS_PN = "120";
"DQ14_A":   PN = "170"  !CDS_PN = "170";
"DQ14_B":   PN = "263"  !CDS_PN = "263";
"DQ15_A":   PN = "172"  !CDS_PN = "172";
"DQ15_B":   PN = "265"  !CDS_PN = "265";
"DQ16_A":   PN = "29"  !CDS_PN = "29";
"DQ16_B":   PN = "122"  !CDS_PN = "122";
"DQ17_A":   PN = "31"  !CDS_PN = "31";
"DQ17_B":   PN = "124"  !CDS_PN = "124";
"DQ18_A":   PN = "174"  !CDS_PN = "174";
"DQ18_B":   PN = "267"  !CDS_PN = "267";
"DQ19_A":   PN = "176"  !CDS_PN = "176";
"DQ19_B":   PN = "269"  !CDS_PN = "269";
"DQ20_A":   PN = "36"  !CDS_PN = "36";
"DQ20_B":   PN = "129"  !CDS_PN = "129";
"DQ21_A":   PN = "38"  !CDS_PN = "38";
"DQ21_B":   PN = "131"  !CDS_PN = "131";
"DQ22_A":   PN = "181"  !CDS_PN = "181";
"DQ22_B":   PN = "274"  !CDS_PN = "274";
"DQ23_A":   PN = "183"  !CDS_PN = "183";
"DQ23_B":   PN = "276"  !CDS_PN = "276";
"DQ24_A":   PN = "40"  !CDS_PN = "40";
"DQ24_B":   PN = "133"  !CDS_PN = "133";
"DQ25_A":   PN = "42"  !CDS_PN = "42";
"DQ25_B":   PN = "135"  !CDS_PN = "135";
"DQ26_A":   PN = "185"  !CDS_PN = "185";
"DQ26_B":   PN = "278"  !CDS_PN = "278";
"DQ27_A":   PN = "187"  !CDS_PN = "187";
"DQ27_B":   PN = "280"  !CDS_PN = "280";
"DQ28_A":   PN = "47"  !CDS_PN = "47";
"DQ28_B":   PN = "140"  !CDS_PN = "140";
"DQ29_A":   PN = "49"  !CDS_PN = "49";
"DQ29_B":   PN = "142"  !CDS_PN = "142";
"DQ30_A":   PN = "192"  !CDS_PN = "192";
"DQ30_B":   PN = "285"  !CDS_PN = "285";
"DQ31_A":   PN = "194"  !CDS_PN = "194";
"DQ31_B":   PN = "287"  !CDS_PN = "287";
"HSA":   PN = "148"  !CDS_PN = "148";
"HSCL":   PN = "4"  !CDS_PN = "4";
"HSDA":   PN = "5"  !CDS_PN = "5";
"LBD||RSP_A_N":   PN = "86"  !CDS_PN = "86";
"LBS||RSP_B_N":   PN = "87"  !CDS_PN = "87";
"PAR_A":   PN = "74"  !CDS_PN = "74";
"PAR_B":   PN = "227"  !CDS_PN = "227";
"PWR_GOOD||FAIL_N":   PN = "147"  !CDS_PN = "147";
"RESET_N":   PN = "207"  !CDS_PN = "207";
"RFU0":   PN = "2"  !CDS_PN = "2";
"RFU1":   PN = "144"  !CDS_PN = "144";
"RFU2":   PN = "149"  !CDS_PN = "149";
"RFU3":   PN = "150"  !CDS_PN = "150";
"RFU4":   PN = "220"  !CDS_PN = "220";
"RFU5":   PN = "231"  !CDS_PN = "231";
"RFU6":   PN = "232"  !CDS_PN = "232";
"VIN_MGMT":   PN = "3"  !CDS_PN = "3";
BODY = "SCONN288_ADR50017P130CC","I181": #LOCATION = "J31" !CDS_LOCATION = "J31" &SEC = "2" #&CDS_SEC = "2";
"DQS0_A_C":   PN = "12"  !CDS_PN = "12";
"DQS0_A_T":   PN = "11"  !CDS_PN = "11";
"DQS0_B_C":   PN = "105"  !CDS_PN = "105";
"DQS0_B_T":   PN = "104"  !CDS_PN = "104";
"DQS1_A_C":   PN = "23"  !CDS_PN = "23";
"DQS1_A_T":   PN = "22"  !CDS_PN = "22";
"DQS1_B_C":   PN = "116"  !CDS_PN = "116";
"DQS1_B_T":   PN = "115"  !CDS_PN = "115";
"DQS2_A_C":   PN = "34"  !CDS_PN = "34";
"DQS2_A_T":   PN = "33"  !CDS_PN = "33";
"DQS2_B_C":   PN = "127"  !CDS_PN = "127";
"DQS2_B_T":   PN = "126"  !CDS_PN = "126";
"DQS3_A_C":   PN = "45"  !CDS_PN = "45";
"DQS3_A_T":   PN = "44"  !CDS_PN = "44";
"DQS3_B_C":   PN = "138"  !CDS_PN = "138";
"DQS3_B_T":   PN = "137"  !CDS_PN = "137";
"DQS4_A_C":   PN = "56"  !CDS_PN = "56";
"DQS4_A_T":   PN = "55"  !CDS_PN = "55";
"DQS4_B_C":   PN = "238"  !CDS_PN = "238";
"DQS4_B_T":   PN = "239"  !CDS_PN = "239";
"DQS5_A_C||TDQS5_A_C||DQS5_A_T||TDQS5_A_T":   PN = "156"  !CDS_PN = "156";
"DQS5_A_T||TDQS5_A_T":   PN = "157"  !CDS_PN = "157";
"DQS5_B_C||TDQS5_B_C":   PN = "249"  !CDS_PN = "249";
"DQS5_B_T||TDQS5_B_T":   PN = "250"  !CDS_PN = "250";
"DQS6_A_C||TDQS6_A_C||DQS6_A_T||TDQS6_A_T":   PN = "167"  !CDS_PN = "167";
"DQS6_A_T||TDQS6_A_T":   PN = "168"  !CDS_PN = "168";
"DQS6_B_C||TDQS6_B_C":   PN = "260"  !CDS_PN = "260";
"DQS6_B_T||TDQS6_B_T":   PN = "261"  !CDS_PN = "261";
"DQS7_A_C||TDQS7_A_C":   PN = "178"  !CDS_PN = "178";
"DQS7_A_T||TDQS7_A_T":   PN = "179"  !CDS_PN = "179";
"DQS7_B_C||TDQS7_B_C":   PN = "271"  !CDS_PN = "271";
"DQS7_B_T||TDQS7_B_T":   PN = "272"  !CDS_PN = "272";
"DQS8_A_C||TDQS8_A_C":   PN = "189"  !CDS_PN = "189";
"DQS8_A_T||TDQS8_A_T":   PN = "190"  !CDS_PN = "190";
"DQS8_B_C||TDQS8_B_C":   PN = "282"  !CDS_PN = "282";
"DQS8_B_T||TDQS8_B_T":   PN = "283"  !CDS_PN = "283";
"DQS9_A_C||TDQS9_A_C":   PN = "200"  !CDS_PN = "200";
"DQS9_A_T||TDQS9_A_T":   PN = "201"  !CDS_PN = "201";
"DQS9_B_C||TDQS9_B_C":   PN = "94"  !CDS_PN = "94";
"DQS9_B_T||TDQS9_B_T||DBI4_B_N":   PN = "93"  !CDS_PN = "93";
BODY = "Q_RES","I183": LOCATION = "R3905" #&CDS_LOCATION = "R3905" &SEC = "1" #&CDS_SEC = "1";
"A":   PN = "1"  !CDS_PN = "1";
"B":   PN = "2"  !CDS_PN = "2";
DRAWING = "@s9s_mb_2u_lib.s9s_mb_2u(sch_1):page113";
BODY = "Q_RES","I2": LOCATION = "R72" #&CDS_LOCATION = "R72" &SEC = "1" #&CDS_SEC = "1";
"A":   PN = "1"  !CDS_PN = "1";
"B":   PN = "2"  !CDS_PN = "2";
BODY = "Q_CAP","I116": LOCATION = "C72" #&CDS_LOCATION = "C72" &SEC = "1" #&CDS_SEC = "1";
"A":   PN = "1"  !CDS_PN = "1";
"B":   PN = "2"  !CDS_PN = "2";
BODY = "Q_CAP","I120": LOCATION = "C73" #&CDS_LOCATION = "C73" &SEC = "1" #&CDS_SEC = "1";
"A":   PN = "1"  !CDS_PN = "1";
"B":   PN = "2"  !CDS_PN = "2";
BODY = "Q_CAP","I122": LOCATION = "C74" #&CDS_LOCATION = "C74" &SEC = "1" #&CDS_SEC = "1";
"A":   PN = "1"  !CDS_PN = "1";
"B":   PN = "2"  !CDS_PN = "2";
BODY = "SCONN288_ADR50017P087CC","I177": LOCATION = "J32" #&CDS_LOCATION = "J32" &SEC = "3" #&CDS_SEC = "3";
"G1":   PN = "G1"  !CDS_PN = "G1";
"G2":   PN = "G2"  !CDS_PN = "G2";
"G3":   PN = "G3"  !CDS_PN = "G3";
"VIN_BULK0":   PN = "1"  !CDS_PN = "1";
"VIN_BULK1":   PN = "145"  !CDS_PN = "145";
"VIN_BULK2":   PN = "146"  !CDS_PN = "146";
"VSS0":   PN = "6"  !CDS_PN = "6";
"VSS1":   PN = "8"  !CDS_PN = "8";
"VSS2":   PN = "10"  !CDS_PN = "10";
"VSS3":   PN = "13"  !CDS_PN = "13";
"VSS4":   PN = "15"  !CDS_PN = "15";
"VSS5":   PN = "17"  !CDS_PN = "17";
"VSS6":   PN = "19"  !CDS_PN = "19";
"VSS7":   PN = "21"  !CDS_PN = "21";
"VSS8":   PN = "24"  !CDS_PN = "24";
"VSS9":   PN = "26"  !CDS_PN = "26";
"VSS10":   PN = "28"  !CDS_PN = "28";
"VSS11":   PN = "30"  !CDS_PN = "30";
"VSS12":   PN = "32"  !CDS_PN = "32";
"VSS13":   PN = "35"  !CDS_PN = "35";
"VSS14":   PN = "37"  !CDS_PN = "37";
"VSS15":   PN = "39"  !CDS_PN = "39";
"VSS16":   PN = "41"  !CDS_PN = "41";
"VSS17":   PN = "43"  !CDS_PN = "43";
"VSS18":   PN = "46"  !CDS_PN = "46";
"VSS19":   PN = "48"  !CDS_PN = "48";
"VSS20":   PN = "50"  !CDS_PN = "50";
"VSS21":   PN = "52"  !CDS_PN = "52";
"VSS22":   PN = "54"  !CDS_PN = "54";
"VSS23":   PN = "57"  !CDS_PN = "57";
"VSS24":   PN = "59"  !CDS_PN = "59";
"VSS25":   PN = "61"  !CDS_PN = "61";
"VSS26":   PN = "63"  !CDS_PN = "63";
"VSS27":   PN = "65"  !CDS_PN = "65";
"VSS28":   PN = "67"  !CDS_PN = "67";
"VSS29":   PN = "69"  !CDS_PN = "69";
"VSS30":   PN = "71"  !CDS_PN = "71";
"VSS31":   PN = "73"  !CDS_PN = "73";
"VSS32":   PN = "75"  !CDS_PN = "75";
"VSS33":   PN = "77"  !CDS_PN = "77";
"VSS34":   PN = "79"  !CDS_PN = "79";
"VSS35":   PN = "81"  !CDS_PN = "81";
"VSS36":   PN = "83"  !CDS_PN = "83";
"VSS37":   PN = "85"  !CDS_PN = "85";
"VSS38":   PN = "88"  !CDS_PN = "88";
"VSS39":   PN = "90"  !CDS_PN = "90";
"VSS40":   PN = "92"  !CDS_PN = "92";
"VSS41":   PN = "95"  !CDS_PN = "95";
"VSS42":   PN = "97"  !CDS_PN = "97";
"VSS43":   PN = "99"  !CDS_PN = "99";
"VSS44":   PN = "101"  !CDS_PN = "101";
"VSS45":   PN = "103"  !CDS_PN = "103";
"VSS46":   PN = "106"  !CDS_PN = "106";
"VSS47":   PN = "108"  !CDS_PN = "108";
"VSS48":   PN = "110"  !CDS_PN = "110";
"VSS49":   PN = "112"  !CDS_PN = "112";
"VSS50":   PN = "114"  !CDS_PN = "114";
"VSS51":   PN = "117"  !CDS_PN = "117";
"VSS52":   PN = "119"  !CDS_PN = "119";
"VSS53":   PN = "121"  !CDS_PN = "121";
"VSS54":   PN = "123"  !CDS_PN = "123";
"VSS55":   PN = "125"  !CDS_PN = "125";
"VSS56":   PN = "128"  !CDS_PN = "128";
"VSS57":   PN = "130"  !CDS_PN = "130";
"VSS58":   PN = "132"  !CDS_PN = "132";
"VSS59":   PN = "134"  !CDS_PN = "134";
"VSS60":   PN = "136"  !CDS_PN = "136";
"VSS61":   PN = "139"  !CDS_PN = "139";
"VSS62":   PN = "141"  !CDS_PN = "141";
"VSS63":   PN = "143"  !CDS_PN = "143";
"VSS64":   PN = "151"  !CDS_PN = "151";
"VSS65":   PN = "153"  !CDS_PN = "153";
"VSS66":   PN = "155"  !CDS_PN = "155";
"VSS67":   PN = "158"  !CDS_PN = "158";
"VSS68":   PN = "160"  !CDS_PN = "160";
"VSS69":   PN = "162"  !CDS_PN = "162";
"VSS70":   PN = "164"  !CDS_PN = "164";
"VSS71":   PN = "166"  !CDS_PN = "166";
"VSS72":   PN = "169"  !CDS_PN = "169";
"VSS73":   PN = "171"  !CDS_PN = "171";
"VSS74":   PN = "173"  !CDS_PN = "173";
"VSS75":   PN = "175"  !CDS_PN = "175";
"VSS76":   PN = "177"  !CDS_PN = "177";
"VSS77":   PN = "180"  !CDS_PN = "180";
"VSS78":   PN = "182"  !CDS_PN = "182";
"VSS79":   PN = "184"  !CDS_PN = "184";
"VSS80":   PN = "186"  !CDS_PN = "186";
"VSS81":   PN = "188"  !CDS_PN = "188";
"VSS82":   PN = "191"  !CDS_PN = "191";
"VSS83":   PN = "193"  !CDS_PN = "193";
"VSS84":   PN = "195"  !CDS_PN = "195";
"VSS85":   PN = "197"  !CDS_PN = "197";
"VSS86":   PN = "199"  !CDS_PN = "199";
"VSS87":   PN = "202"  !CDS_PN = "202";
"VSS88":   PN = "204"  !CDS_PN = "204";
"VSS89":   PN = "206"  !CDS_PN = "206";
"VSS90":   PN = "208"  !CDS_PN = "208";
"VSS91":   PN = "210"  !CDS_PN = "210";
"VSS92":   PN = "212"  !CDS_PN = "212";
"VSS93":   PN = "214"  !CDS_PN = "214";
"VSS94":   PN = "216"  !CDS_PN = "216";
"VSS95":   PN = "219"  !CDS_PN = "219";
"VSS96":   PN = "222"  !CDS_PN = "222";
"VSS97":   PN = "224"  !CDS_PN = "224";
"VSS98":   PN = "226"  !CDS_PN = "226";
"VSS99":   PN = "228"  !CDS_PN = "228";
"VSS100":   PN = "230"  !CDS_PN = "230";
"VSS101":   PN = "233"  !CDS_PN = "233";
"VSS102":   PN = "235"  !CDS_PN = "235";
"VSS103":   PN = "237"  !CDS_PN = "237";
"VSS104":   PN = "240"  !CDS_PN = "240";
"VSS105":   PN = "242"  !CDS_PN = "242";
"VSS106":   PN = "244"  !CDS_PN = "244";
"VSS107":   PN = "246"  !CDS_PN = "246";
"VSS108":   PN = "248"  !CDS_PN = "248";
"VSS109":   PN = "251"  !CDS_PN = "251";
"VSS110":   PN = "253"  !CDS_PN = "253";
"VSS111":   PN = "255"  !CDS_PN = "255";
"VSS112":   PN = "257"  !CDS_PN = "257";
"VSS113":   PN = "259"  !CDS_PN = "259";
"VSS114":   PN = "262"  !CDS_PN = "262";
"VSS115":   PN = "264"  !CDS_PN = "264";
"VSS116":   PN = "266"  !CDS_PN = "266";
"VSS117":   PN = "268"  !CDS_PN = "268";
"VSS118":   PN = "270"  !CDS_PN = "270";
"VSS119":   PN = "273"  !CDS_PN = "273";
"VSS120":   PN = "275"  !CDS_PN = "275";
"VSS121":   PN = "277"  !CDS_PN = "277";
"VSS122":   PN = "279"  !CDS_PN = "279";
"VSS123":   PN = "281"  !CDS_PN = "281";
"VSS124":   PN = "284"  !CDS_PN = "284";
"VSS125":   PN = "286"  !CDS_PN = "286";
"VSS126":   PN = "288"  !CDS_PN = "288";
BODY = "SCONN288_ADR50017P087CC","I179": LOCATION = "J32" #&CDS_LOCATION = "J32" &SEC = "1" #&CDS_SEC = "1";
"ALERT_N":   PN = "62"  !CDS_PN = "62";
"CA0_A":   PN = "66"  !CDS_PN = "66";
"CA0_B":   PN = "76"  !CDS_PN = "76";
"CA1_A":   PN = "211"  !CDS_PN = "211";
"CA1_B":   PN = "221"  !CDS_PN = "221";
"CA2_A":   PN = "68"  !CDS_PN = "68";
"CA2_B":   PN = "78"  !CDS_PN = "78";
"CA3_A":   PN = "213"  !CDS_PN = "213";
"CA3_B":   PN = "223"  !CDS_PN = "223";
"CA4_A":   PN = "70"  !CDS_PN = "70";
"CA4_B":   PN = "80"  !CDS_PN = "80";
"CA5_A":   PN = "215"  !CDS_PN = "215";
"CA5_B":   PN = "225"  !CDS_PN = "225";
"CA6_A":   PN = "72"  !CDS_PN = "72";
"CA6_B":   PN = "82"  !CDS_PN = "82";
"CB0_A":   PN = "51"  !CDS_PN = "51";
"CB0_B":   PN = "96"  !CDS_PN = "96";
"CB1_A":   PN = "53"  !CDS_PN = "53";
"CB1_B":   PN = "98"  !CDS_PN = "98";
"CB2_A":   PN = "196"  !CDS_PN = "196";
"CB2_B":   PN = "241"  !CDS_PN = "241";
"CB3_A":   PN = "198"  !CDS_PN = "198";
"CB3_B":   PN = "243"  !CDS_PN = "243";
"CB4_A":   PN = "58"  !CDS_PN = "58";
"CB4_B":   PN = "89"  !CDS_PN = "89";
"CB5_A":   PN = "60"  !CDS_PN = "60";
"CB5_B":   PN = "91"  !CDS_PN = "91";
"CB6_A":   PN = "203"  !CDS_PN = "203";
"CB6_B":   PN = "234"  !CDS_PN = "234";
"CB7_A":   PN = "205"  !CDS_PN = "205";
"CB7_B":   PN = "236"  !CDS_PN = "236";
"CK_C":   PN = "218"  !CDS_PN = "218";
"CK_T":   PN = "217"  !CDS_PN = "217";
"CS0_A_N":   PN = "64"  !CDS_PN = "64";
"CS0_B_N":   PN = "84"  !CDS_PN = "84";
"CS1_A_N":   PN = "209"  !CDS_PN = "209";
"CS1_B_N":   PN = "229"  !CDS_PN = "229";
"DQ0_A":   PN = "7"  !CDS_PN = "7";
"DQ0_B":   PN = "100"  !CDS_PN = "100";
"DQ1_A":   PN = "9"  !CDS_PN = "9";
"DQ1_B":   PN = "102"  !CDS_PN = "102";
"DQ2_A":   PN = "152"  !CDS_PN = "152";
"DQ2_B":   PN = "245"  !CDS_PN = "245";
"DQ3_A":   PN = "154"  !CDS_PN = "154";
"DQ3_B":   PN = "247"  !CDS_PN = "247";
"DQ4_A":   PN = "14"  !CDS_PN = "14";
"DQ4_B":   PN = "107"  !CDS_PN = "107";
"DQ5_A":   PN = "16"  !CDS_PN = "16";
"DQ5_B":   PN = "109"  !CDS_PN = "109";
"DQ6_A":   PN = "159"  !CDS_PN = "159";
"DQ6_B":   PN = "252"  !CDS_PN = "252";
"DQ7_A":   PN = "161"  !CDS_PN = "161";
"DQ7_B":   PN = "254"  !CDS_PN = "254";
"DQ8_A":   PN = "18"  !CDS_PN = "18";
"DQ8_B":   PN = "111"  !CDS_PN = "111";
"DQ9_A":   PN = "20"  !CDS_PN = "20";
"DQ9_B":   PN = "113"  !CDS_PN = "113";
"DQ10_A":   PN = "163"  !CDS_PN = "163";
"DQ10_B":   PN = "256"  !CDS_PN = "256";
"DQ11_A":   PN = "165"  !CDS_PN = "165";
"DQ11_B":   PN = "258"  !CDS_PN = "258";
"DQ12_A":   PN = "25"  !CDS_PN = "25";
"DQ12_B":   PN = "118"  !CDS_PN = "118";
"DQ13_A":   PN = "27"  !CDS_PN = "27";
"DQ13_B":   PN = "120"  !CDS_PN = "120";
"DQ14_A":   PN = "170"  !CDS_PN = "170";
"DQ14_B":   PN = "263"  !CDS_PN = "263";
"DQ15_A":   PN = "172"  !CDS_PN = "172";
"DQ15_B":   PN = "265"  !CDS_PN = "265";
"DQ16_A":   PN = "29"  !CDS_PN = "29";
"DQ16_B":   PN = "122"  !CDS_PN = "122";
"DQ17_A":   PN = "31"  !CDS_PN = "31";
"DQ17_B":   PN = "124"  !CDS_PN = "124";
"DQ18_A":   PN = "174"  !CDS_PN = "174";
"DQ18_B":   PN = "267"  !CDS_PN = "267";
"DQ19_A":   PN = "176"  !CDS_PN = "176";
"DQ19_B":   PN = "269"  !CDS_PN = "269";
"DQ20_A":   PN = "36"  !CDS_PN = "36";
"DQ20_B":   PN = "129"  !CDS_PN = "129";
"DQ21_A":   PN = "38"  !CDS_PN = "38";
"DQ21_B":   PN = "131"  !CDS_PN = "131";
"DQ22_A":   PN = "181"  !CDS_PN = "181";
"DQ22_B":   PN = "274"  !CDS_PN = "274";
"DQ23_A":   PN = "183"  !CDS_PN = "183";
"DQ23_B":   PN = "276"  !CDS_PN = "276";
"DQ24_A":   PN = "40"  !CDS_PN = "40";
"DQ24_B":   PN = "133"  !CDS_PN = "133";
"DQ25_A":   PN = "42"  !CDS_PN = "42";
"DQ25_B":   PN = "135"  !CDS_PN = "135";
"DQ26_A":   PN = "185"  !CDS_PN = "185";
"DQ26_B":   PN = "278"  !CDS_PN = "278";
"DQ27_A":   PN = "187"  !CDS_PN = "187";
"DQ27_B":   PN = "280"  !CDS_PN = "280";
"DQ28_A":   PN = "47"  !CDS_PN = "47";
"DQ28_B":   PN = "140"  !CDS_PN = "140";
"DQ29_A":   PN = "49"  !CDS_PN = "49";
"DQ29_B":   PN = "142"  !CDS_PN = "142";
"DQ30_A":   PN = "192"  !CDS_PN = "192";
"DQ30_B":   PN = "285"  !CDS_PN = "285";
"DQ31_A":   PN = "194"  !CDS_PN = "194";
"DQ31_B":   PN = "287"  !CDS_PN = "287";
"HSA":   PN = "148"  !CDS_PN = "148";
"HSCL":   PN = "4"  !CDS_PN = "4";
"HSDA":   PN = "5"  !CDS_PN = "5";
"LBD||RSP_A_N":   PN = "86"  !CDS_PN = "86";
"LBS||RSP_B_N":   PN = "87"  !CDS_PN = "87";
"PAR_A":   PN = "74"  !CDS_PN = "74";
"PAR_B":   PN = "227"  !CDS_PN = "227";
"PWR_GOOD||FAIL_N":   PN = "147"  !CDS_PN = "147";
"RESET_N":   PN = "207"  !CDS_PN = "207";
"RFU0":   PN = "2"  !CDS_PN = "2";
"RFU1":   PN = "144"  !CDS_PN = "144";
"RFU2":   PN = "149"  !CDS_PN = "149";
"RFU3":   PN = "150"  !CDS_PN = "150";
"RFU4":   PN = "220"  !CDS_PN = "220";
"RFU5":   PN = "231"  !CDS_PN = "231";
"RFU6":   PN = "232"  !CDS_PN = "232";
"VIN_MGMT":   PN = "3"  !CDS_PN = "3";
BODY = "SCONN288_ADR50017P087CC","I180": #LOCATION = "J32" !CDS_LOCATION = "J32" &SEC = "2" #&CDS_SEC = "2";
"DQS0_A_C":   PN = "12"  !CDS_PN = "12";
"DQS0_A_T":   PN = "11"  !CDS_PN = "11";
"DQS0_B_C":   PN = "105"  !CDS_PN = "105";
"DQS0_B_T":   PN = "104"  !CDS_PN = "104";
"DQS1_A_C":   PN = "23"  !CDS_PN = "23";
"DQS1_A_T":   PN = "22"  !CDS_PN = "22";
"DQS1_B_C":   PN = "116"  !CDS_PN = "116";
"DQS1_B_T":   PN = "115"  !CDS_PN = "115";
"DQS2_A_C":   PN = "34"  !CDS_PN = "34";
"DQS2_A_T":   PN = "33"  !CDS_PN = "33";
"DQS2_B_C":   PN = "127"  !CDS_PN = "127";
"DQS2_B_T":   PN = "126"  !CDS_PN = "126";
"DQS3_A_C":   PN = "45"  !CDS_PN = "45";
"DQS3_A_T":   PN = "44"  !CDS_PN = "44";
"DQS3_B_C":   PN = "138"  !CDS_PN = "138";
"DQS3_B_T":   PN = "137"  !CDS_PN = "137";
"DQS4_A_C":   PN = "56"  !CDS_PN = "56";
"DQS4_A_T":   PN = "55"  !CDS_PN = "55";
"DQS4_B_C":   PN = "238"  !CDS_PN = "238";
"DQS4_B_T":   PN = "239"  !CDS_PN = "239";
"DQS5_A_C||TDQS5_A_C||DQS5_A_T||TDQS5_A_T":   PN = "156"  !CDS_PN = "156";
"DQS5_A_T||TDQS5_A_T":   PN = "157"  !CDS_PN = "157";
"DQS5_B_C||TDQS5_B_C":   PN = "249"  !CDS_PN = "249";
"DQS5_B_T||TDQS5_B_T":   PN = "250"  !CDS_PN = "250";
"DQS6_A_C||TDQS6_A_C||DQS6_A_T||TDQS6_A_T":   PN = "167"  !CDS_PN = "167";
"DQS6_A_T||TDQS6_A_T":   PN = "168"  !CDS_PN = "168";
"DQS6_B_C||TDQS6_B_C":   PN = "260"  !CDS_PN = "260";
"DQS6_B_T||TDQS6_B_T":   PN = "261"  !CDS_PN = "261";
"DQS7_A_C||TDQS7_A_C":   PN = "178"  !CDS_PN = "178";
"DQS7_A_T||TDQS7_A_T":   PN = "179"  !CDS_PN = "179";
"DQS7_B_C||TDQS7_B_C":   PN = "271"  !CDS_PN = "271";
"DQS7_B_T||TDQS7_B_T":   PN = "272"  !CDS_PN = "272";
"DQS8_A_C||TDQS8_A_C":   PN = "189"  !CDS_PN = "189";
"DQS8_A_T||TDQS8_A_T":   PN = "190"  !CDS_PN = "190";
"DQS8_B_C||TDQS8_B_C":   PN = "282"  !CDS_PN = "282";
"DQS8_B_T||TDQS8_B_T":   PN = "283"  !CDS_PN = "283";
"DQS9_A_C||TDQS9_A_C":   PN = "200"  !CDS_PN = "200";
"DQS9_A_T||TDQS9_A_T":   PN = "201"  !CDS_PN = "201";
"DQS9_B_C||TDQS9_B_C":   PN = "94"  !CDS_PN = "94";
"DQS9_B_T||TDQS9_B_T||DBI4_B_N":   PN = "93"  !CDS_PN = "93";
BODY = "Q_RES","I182": LOCATION = "R3906" #&CDS_LOCATION = "R3906" &SEC = "1" #&CDS_SEC = "1";
"A":   PN = "1"  !CDS_PN = "1";
"B":   PN = "2"  !CDS_PN = "2";
DRAWING = "@s9s_mb_2u_lib.s9s_mb_2u(sch_1):page114";
BODY = "Q_RES","I59": LOCATION = "R906" #&CDS_LOCATION = "R906" &SEC = "1" #&CDS_SEC = "1";
"A":   PN = "1"  !CDS_PN = "1";
"B":   PN = "2"  !CDS_PN = "2";
BODY = "Q_RES","I61": LOCATION = "R2736" #&CDS_LOCATION = "R2736" &SEC = "1" #&CDS_SEC = "1";
"A":   PN = "1"  !CDS_PN = "1";
"B":   PN = "2"  !CDS_PN = "2";
BODY = "Q_RES","I63": LOCATION = "R902" #&CDS_LOCATION = "R902" &SEC = "1" #&CDS_SEC = "1";
"A":   PN = "1"  !CDS_PN = "1";
"B":   PN = "2"  !CDS_PN = "2";
BODY = "Q_RES","I17": LOCATION = "R2735" #&CDS_LOCATION = "R2735" &SEC = "1" #&CDS_SEC = "1";
"A":   PN = "1"  !CDS_PN = "1";
"B":   PN = "2"  !CDS_PN = "2";
BODY = "Q_RES","I18": LOCATION = "R2734" #&CDS_LOCATION = "R2734" &SEC = "1" #&CDS_SEC = "1";
"A":   PN = "1"  !CDS_PN = "1";
"B":   PN = "2"  !CDS_PN = "2";
BODY = "Q_RES","I19": LOCATION = "R890" #&CDS_LOCATION = "R890" &SEC = "1" #&CDS_SEC = "1";
"A":   PN = "1"  !CDS_PN = "1";
"B":   PN = "2"  !CDS_PN = "2";
BODY = "Q_RES","I20": LOCATION = "R889" #&CDS_LOCATION = "R889" &SEC = "1" #&CDS_SEC = "1";
"A":   PN = "1"  !CDS_PN = "1";
"B":   PN = "2"  !CDS_PN = "2";
BODY = "Q_RES","I21": LOCATION = "R2733" #&CDS_LOCATION = "R2733" &SEC = "1" #&CDS_SEC = "1";
"A":   PN = "1"  !CDS_PN = "1";
"B":   PN = "2"  !CDS_PN = "2";
BODY = "Q_RES","I23": LOCATION = "R886" #&CDS_LOCATION = "R886" &SEC = "1" #&CDS_SEC = "1";
"A":   PN = "1"  !CDS_PN = "1";
"B":   PN = "2"  !CDS_PN = "2";
BODY = "Q_RES","I24": LOCATION = "R885" #&CDS_LOCATION = "R885" &SEC = "1" #&CDS_SEC = "1";
"A":   PN = "1"  !CDS_PN = "1";
"B":   PN = "2"  !CDS_PN = "2";
BODY = "Q_RES","I26": LOCATION = "R884" #&CDS_LOCATION = "R884" &SEC = "1" #&CDS_SEC = "1";
"A":   PN = "1"  !CDS_PN = "1";
"B":   PN = "2"  !CDS_PN = "2";
BODY = "Q_RES","I28": LOCATION = "R2729" #&CDS_LOCATION = "R2729" &SEC = "1" #&CDS_SEC = "1";
"A":   PN = "1"  !CDS_PN = "1";
"B":   PN = "2"  !CDS_PN = "2";
BODY = "Q_RES","I29": LOCATION = "R880" #&CDS_LOCATION = "R880" &SEC = "1" #&CDS_SEC = "1";
"A":   PN = "1"  !CDS_PN = "1";
"B":   PN = "2"  !CDS_PN = "2";
BODY = "Q_RES","I57": LOCATION = "R908" #&CDS_LOCATION = "R908" &SEC = "1" #&CDS_SEC = "1";
"A":   PN = "1"  !CDS_PN = "1";
"B":   PN = "2"  !CDS_PN = "2";
BODY = "Q_RES","I58": LOCATION = "R907" #&CDS_LOCATION = "R907" &SEC = "1" #&CDS_SEC = "1";
"A":   PN = "1"  !CDS_PN = "1";
"B":   PN = "2"  !CDS_PN = "2";
BODY = "Q_RES","I60": LOCATION = "R905" #&CDS_LOCATION = "R905" &SEC = "1" #&CDS_SEC = "1";
"A":   PN = "1"  !CDS_PN = "1";
"B":   PN = "2"  !CDS_PN = "2";
BODY = "Q_RES","I62": LOCATION = "R903" #&CDS_LOCATION = "R903" &SEC = "1" #&CDS_SEC = "1";
"A":   PN = "1"  !CDS_PN = "1";
"B":   PN = "2"  !CDS_PN = "2";
BODY = "Q_RES","I64": LOCATION = "R901" #&CDS_LOCATION = "R901" &SEC = "1" #&CDS_SEC = "1";
"A":   PN = "1"  !CDS_PN = "1";
"B":   PN = "2"  !CDS_PN = "2";
BODY = "Q_RES","I66": LOCATION = "R900" #&CDS_LOCATION = "R900" &SEC = "1" #&CDS_SEC = "1";
"A":   PN = "1"  !CDS_PN = "1";
"B":   PN = "2"  !CDS_PN = "2";
BODY = "Q_RES","I67": LOCATION = "R897" #&CDS_LOCATION = "R897" &SEC = "1" #&CDS_SEC = "1";
"A":   PN = "1"  !CDS_PN = "1";
"B":   PN = "2"  !CDS_PN = "2";
BODY = "Q_RES","I69": LOCATION = "R896" #&CDS_LOCATION = "R896" &SEC = "1" #&CDS_SEC = "1";
"A":   PN = "1"  !CDS_PN = "1";
"B":   PN = "2"  !CDS_PN = "2";
BODY = "Q_RES","I22": LOCATION = "R2732" #&CDS_LOCATION = "R2732" &SEC = "1" #&CDS_SEC = "1";
"A":   PN = "1"  !CDS_PN = "1";
"B":   PN = "2"  !CDS_PN = "2";
BODY = "Q_RES","I25": LOCATION = "R2731" #&CDS_LOCATION = "R2731" &SEC = "1" #&CDS_SEC = "1";
"A":   PN = "1"  !CDS_PN = "1";
"B":   PN = "2"  !CDS_PN = "2";
BODY = "Q_RES","I27": LOCATION = "R2730" #&CDS_LOCATION = "R2730" &SEC = "1" #&CDS_SEC = "1";
"A":   PN = "1"  !CDS_PN = "1";
"B":   PN = "2"  !CDS_PN = "2";
BODY = "Q_RES","I30": LOCATION = "R2728" #&CDS_LOCATION = "R2728" &SEC = "1" #&CDS_SEC = "1";
"A":   PN = "1"  !CDS_PN = "1";
"B":   PN = "2"  !CDS_PN = "2";
BODY = "Q_RES","I31": LOCATION = "R2727" #&CDS_LOCATION = "R2727" &SEC = "1" #&CDS_SEC = "1";
"A":   PN = "1"  !CDS_PN = "1";
"B":   PN = "2"  !CDS_PN = "2";
BODY = "Q_RES","I32": LOCATION = "R2726" #&CDS_LOCATION = "R2726" &SEC = "1" #&CDS_SEC = "1";
"A":   PN = "1"  !CDS_PN = "1";
"B":   PN = "2"  !CDS_PN = "2";
BODY = "Q_RES","I65": LOCATION = "R899" #&CDS_LOCATION = "R899" &SEC = "1" #&CDS_SEC = "1";
"A":   PN = "1"  !CDS_PN = "1";
"B":   PN = "2"  !CDS_PN = "2";
BODY = "Q_RES","I68": LOCATION = "R898" #&CDS_LOCATION = "R898" &SEC = "1" #&CDS_SEC = "1";
"A":   PN = "1"  !CDS_PN = "1";
"B":   PN = "2"  !CDS_PN = "2";
BODY = "Q_RES","I77": LOCATION = "R895" #&CDS_LOCATION = "R895" &SEC = "1" #&CDS_SEC = "1";
"A":   PN = "1"  !CDS_PN = "1";
"B":   PN = "2"  !CDS_PN = "2";
BODY = "Q_RES","I78": LOCATION = "R894" #&CDS_LOCATION = "R894" &SEC = "1" #&CDS_SEC = "1";
"A":   PN = "1"  !CDS_PN = "1";
"B":   PN = "2"  !CDS_PN = "2";
BODY = "Q_RES","I79": LOCATION = "R893" #&CDS_LOCATION = "R893" &SEC = "1" #&CDS_SEC = "1";
"A":   PN = "1"  !CDS_PN = "1";
"B":   PN = "2"  !CDS_PN = "2";
DRAWING = "@s9s_mb_2u_lib.s9s_mb_2u(sch_1):page115";
BODY = "Q_RES","I46": LOCATION = "R2490" #&CDS_LOCATION = "R2490" &SEC = "1" #&CDS_SEC = "1";
"A":   PN = "1"  !CDS_PN = "1";
"B":   PN = "2"  !CDS_PN = "2";
BODY = "Q_RES","I9": LOCATION = "R2497" #&CDS_LOCATION = "R2497" &SEC = "1" #&CDS_SEC = "1";
"A":   PN = "1"  !CDS_PN = "1";
"B":   PN = "2"  !CDS_PN = "2";
BODY = "Q_RES","I11": LOCATION = "R947" #&CDS_LOCATION = "R947" &SEC = "1" #&CDS_SEC = "1";
"A":   PN = "1"  !CDS_PN = "1";
"B":   PN = "2"  !CDS_PN = "2";
BODY = "Q_RES","I12": LOCATION = "R2496" #&CDS_LOCATION = "R2496" &SEC = "1" #&CDS_SEC = "1";
"A":   PN = "1"  !CDS_PN = "1";
"B":   PN = "2"  !CDS_PN = "2";
BODY = "Q_RES","I14": LOCATION = "R946" #&CDS_LOCATION = "R946" &SEC = "1" #&CDS_SEC = "1";
"A":   PN = "1"  !CDS_PN = "1";
"B":   PN = "2"  !CDS_PN = "2";
BODY = "Q_RES","I16": LOCATION = "R945" #&CDS_LOCATION = "R945" &SEC = "1" #&CDS_SEC = "1";
"A":   PN = "1"  !CDS_PN = "1";
"B":   PN = "2"  !CDS_PN = "2";
BODY = "Q_RES","I17": LOCATION = "R2495" #&CDS_LOCATION = "R2495" &SEC = "1" #&CDS_SEC = "1";
"A":   PN = "1"  !CDS_PN = "1";
"B":   PN = "2"  !CDS_PN = "2";
BODY = "Q_RES","I19": LOCATION = "R944" #&CDS_LOCATION = "R944" &SEC = "1" #&CDS_SEC = "1";
"A":   PN = "1"  !CDS_PN = "1";
"B":   PN = "2"  !CDS_PN = "2";
BODY = "SCHOTTKY_12","I22": LOCATION = "D49" #&CDS_LOCATION = "D49" &SEC = "1" #&CDS_SEC = "1";
"A":   PN = "1"  !CDS_PN = "1";
"C":   PN = "2"  !CDS_PN = "2";
BODY = "SCHOTTKY_12","I25": LOCATION = "D48" #&CDS_LOCATION = "D48" &SEC = "1" #&CDS_SEC = "1";
"A":   PN = "1"  !CDS_PN = "1";
"C":   PN = "2"  !CDS_PN = "2";
BODY = "SCHOTTKY_12","I27": LOCATION = "D47" #&CDS_LOCATION = "D47" &SEC = "1" #&CDS_SEC = "1";
"A":   PN = "1"  !CDS_PN = "1";
"C":   PN = "2"  !CDS_PN = "2";
BODY = "Q_RES","I38": LOCATION = "R2493" #&CDS_LOCATION = "R2493" &SEC = "1" #&CDS_SEC = "1";
"A":   PN = "1"  !CDS_PN = "1";
"B":   PN = "2"  !CDS_PN = "2";
BODY = "Q_RES","I42": LOCATION = "R2491" #&CDS_LOCATION = "R2491" &SEC = "1" #&CDS_SEC = "1";
"A":   PN = "1"  !CDS_PN = "1";
"B":   PN = "2"  !CDS_PN = "2";
BODY = "Q_RES","I45": LOCATION = "R941" #&CDS_LOCATION = "R941" &SEC = "1" #&CDS_SEC = "1";
"A":   PN = "1"  !CDS_PN = "1";
"B":   PN = "2"  !CDS_PN = "2";
BODY = "Q_RES","I48": LOCATION = "R940" #&CDS_LOCATION = "R940" &SEC = "1" #&CDS_SEC = "1";
"A":   PN = "1"  !CDS_PN = "1";
"B":   PN = "2"  !CDS_PN = "2";
BODY = "SCHOTTKY_12","I54": LOCATION = "D43" #&CDS_LOCATION = "D43" &SEC = "1" #&CDS_SEC = "1";
"A":   PN = "1"  !CDS_PN = "1";
"C":   PN = "2"  !CDS_PN = "2";
BODY = "SCHOTTKY_12","I59": LOCATION = "D42" #&CDS_LOCATION = "D42" &SEC = "1" #&CDS_SEC = "1";
"A":   PN = "1"  !CDS_PN = "1";
"C":   PN = "2"  !CDS_PN = "2";
BODY = "Q_RES","I18": LOCATION = "R2494" #&CDS_LOCATION = "R2494" &SEC = "1" #&CDS_SEC = "1";
"A":   PN = "1"  !CDS_PN = "1";
"B":   PN = "2"  !CDS_PN = "2";
BODY = "SCHOTTKY_12","I29": LOCATION = "D46" #&CDS_LOCATION = "D46" &SEC = "1" #&CDS_SEC = "1";
"A":   PN = "1"  !CDS_PN = "1";
"C":   PN = "2"  !CDS_PN = "2";
BODY = "Q_RES","I37": LOCATION = "R943" #&CDS_LOCATION = "R943" &SEC = "1" #&CDS_SEC = "1";
"A":   PN = "1"  !CDS_PN = "1";
"B":   PN = "2"  !CDS_PN = "2";
BODY = "Q_RES","I40": LOCATION = "R942" #&CDS_LOCATION = "R942" &SEC = "1" #&CDS_SEC = "1";
"A":   PN = "1"  !CDS_PN = "1";
"B":   PN = "2"  !CDS_PN = "2";
BODY = "Q_RES","I41": LOCATION = "R2492" #&CDS_LOCATION = "R2492" &SEC = "1" #&CDS_SEC = "1";
"A":   PN = "1"  !CDS_PN = "1";
"B":   PN = "2"  !CDS_PN = "2";
BODY = "SCHOTTKY_12","I50": LOCATION = "D45" #&CDS_LOCATION = "D45" &SEC = "1" #&CDS_SEC = "1";
"A":   PN = "1"  !CDS_PN = "1";
"C":   PN = "2"  !CDS_PN = "2";
BODY = "SCHOTTKY_12","I52": LOCATION = "D44" #&CDS_LOCATION = "D44" &SEC = "1" #&CDS_SEC = "1";
"A":   PN = "1"  !CDS_PN = "1";
"C":   PN = "2"  !CDS_PN = "2";
BODY = "Q_RES","I65": #LOCATION = "R2505" !CDS_LOCATION = "R2505" &SEC = "1" #&CDS_SEC = "1";
"A":   PN = "1"  !CDS_PN = "1";
"B":   PN = "2"  !CDS_PN = "2";
BODY = "Q_RES","I66": #LOCATION = "R2504" !CDS_LOCATION = "R2504" &SEC = "1" #&CDS_SEC = "1";
"A":   PN = "1"  !CDS_PN = "1";
"B":   PN = "2"  !CDS_PN = "2";
BODY = "Q_RES","I67": #LOCATION = "R2503" !CDS_LOCATION = "R2503" &SEC = "1" #&CDS_SEC = "1";
"A":   PN = "1"  !CDS_PN = "1";
"B":   PN = "2"  !CDS_PN = "2";
BODY = "Q_RES","I68": #LOCATION = "R2502" !CDS_LOCATION = "R2502" &SEC = "1" #&CDS_SEC = "1";
"A":   PN = "1"  !CDS_PN = "1";
"B":   PN = "2"  !CDS_PN = "2";
BODY = "Q_RES","I69": #LOCATION = "R2501" !CDS_LOCATION = "R2501" &SEC = "1" #&CDS_SEC = "1";
"A":   PN = "1"  !CDS_PN = "1";
"B":   PN = "2"  !CDS_PN = "2";
BODY = "Q_RES","I70": #LOCATION = "R2500" !CDS_LOCATION = "R2500" &SEC = "1" #&CDS_SEC = "1";
"A":   PN = "1"  !CDS_PN = "1";
"B":   PN = "2"  !CDS_PN = "2";
BODY = "Q_RES","I71": #LOCATION = "R2499" !CDS_LOCATION = "R2499" &SEC = "1" #&CDS_SEC = "1";
"A":   PN = "1"  !CDS_PN = "1";
"B":   PN = "2"  !CDS_PN = "2";
BODY = "Q_RES","I72": #LOCATION = "R2498" !CDS_LOCATION = "R2498" &SEC = "1" #&CDS_SEC = "1";
"A":   PN = "1"  !CDS_PN = "1";
"B":   PN = "2"  !CDS_PN = "2";
DRAWING = "@s9s_mb_2u_lib.s9s_mb_2u(sch_1):page117";
BODY = "Q_RES","I9": LOCATION = "R1240" #&CDS_LOCATION = "R1240" &SEC = "1" #&CDS_SEC = "1";
"A":   PN = "1"  !CDS_PN = "1";
"B":   PN = "2"  !CDS_PN = "2";
BODY = "Q_RES","I10": LOCATION = "R3023" #&CDS_LOCATION = "R3023" &SEC = "1" #&CDS_SEC = "1";
"A":   PN = "1"  !CDS_PN = "1";
"B":   PN = "2"  !CDS_PN = "2";
BODY = "Q_RES","I13": LOCATION = "R1242" #&CDS_LOCATION = "R1242" &SEC = "1" #&CDS_SEC = "1";
"A":   PN = "1"  !CDS_PN = "1";
"B":   PN = "2"  !CDS_PN = "2";
BODY = "Q_RES","I16": LOCATION = "R1244" #&CDS_LOCATION = "R1244" &SEC = "1" #&CDS_SEC = "1";
"A":   PN = "1"  !CDS_PN = "1";
"B":   PN = "2"  !CDS_PN = "2";
BODY = "Q_RES","I17": LOCATION = "R1241" #&CDS_LOCATION = "R1241" &SEC = "1" #&CDS_SEC = "1";
"A":   PN = "1"  !CDS_PN = "1";
"B":   PN = "2"  !CDS_PN = "2";
BODY = "Q_RES","I19": LOCATION = "R1243" #&CDS_LOCATION = "R1243" &SEC = "1" #&CDS_SEC = "1";
"A":   PN = "1"  !CDS_PN = "1";
"B":   PN = "2"  !CDS_PN = "2";
DRAWING = "@s9s_mb_2u_lib.s9s_mb_2u(sch_1):page118";
BODY = "Q_RES","I23": LOCATION = "R297" #&CDS_LOCATION = "R297" &SEC = "1" #&CDS_SEC = "1";
"A":   PN = "1"  !CDS_PN = "1";
"B":   PN = "2"  !CDS_PN = "2";
BODY = "Q_RES","I63": LOCATION = "R299" #&CDS_LOCATION = "R299" &SEC = "1" #&CDS_SEC = "1";
"A":   PN = "1"  !CDS_PN = "1";
"B":   PN = "2"  !CDS_PN = "2";
BODY = "Q_RES","I65": LOCATION = "R296" #&CDS_LOCATION = "R296" &SEC = "1" #&CDS_SEC = "1";
"A":   PN = "1"  !CDS_PN = "1";
"B":   PN = "2"  !CDS_PN = "2";
BODY = "Q_RES","I67": LOCATION = "R298" #&CDS_LOCATION = "R298" &SEC = "1" #&CDS_SEC = "1";
"A":   PN = "1"  !CDS_PN = "1";
"B":   PN = "2"  !CDS_PN = "2";
BODY = "Q_RES","I73": LOCATION = "R301" #&CDS_LOCATION = "R301" &SEC = "1" #&CDS_SEC = "1";
"A":   PN = "1"  !CDS_PN = "1";
"B":   PN = "2"  !CDS_PN = "2";
BODY = "Q_RES","I76": LOCATION = "R303" #&CDS_LOCATION = "R303" &SEC = "1" #&CDS_SEC = "1";
"A":   PN = "1"  !CDS_PN = "1";
"B":   PN = "2"  !CDS_PN = "2";
BODY = "Q_RES","I92": LOCATION = "R315" #&CDS_LOCATION = "R315" &SEC = "1" #&CDS_SEC = "1";
"A":   PN = "1"  !CDS_PN = "1";
"B":   PN = "2"  !CDS_PN = "2";
BODY = "Q_RES","I101": #LOCATION = "R302" !CDS_LOCATION = "R302" &SEC = "1" #&CDS_SEC = "1";
"A":   PN = "1"  !CDS_PN = "1";
"B":   PN = "2"  !CDS_PN = "2";
BODY = "Q_RES","I102": #LOCATION = "R304" !CDS_LOCATION = "R304" &SEC = "1" #&CDS_SEC = "1";
"A":   PN = "1"  !CDS_PN = "1";
"B":   PN = "2"  !CDS_PN = "2";
DRAWING = "@s9s_mb_2u_lib.s9s_mb_2u(sch_1):page119";
BODY = "Q_RES","I53": LOCATION = "R282" #&CDS_LOCATION = "R282" &SEC = "1" #&CDS_SEC = "1";
"A":   PN = "1"  !CDS_PN = "1";
"B":   PN = "2"  !CDS_PN = "2";
BODY = "Q_RES","I54": LOCATION = "R279" #&CDS_LOCATION = "R279" &SEC = "1" #&CDS_SEC = "1";
"A":   PN = "1"  !CDS_PN = "1";
"B":   PN = "2"  !CDS_PN = "2";
BODY = "Q_RES","I57": LOCATION = "R280" #&CDS_LOCATION = "R280" &SEC = "1" #&CDS_SEC = "1";
"A":   PN = "1"  !CDS_PN = "1";
"B":   PN = "2"  !CDS_PN = "2";
BODY = "Q_RES","I58": LOCATION = "R281" #&CDS_LOCATION = "R281" &SEC = "1" #&CDS_SEC = "1";
"A":   PN = "1"  !CDS_PN = "1";
"B":   PN = "2"  !CDS_PN = "2";
BODY = "Q_RES","I61": LOCATION = "R278" #&CDS_LOCATION = "R278" &SEC = "1" #&CDS_SEC = "1";
"A":   PN = "1"  !CDS_PN = "1";
"B":   PN = "2"  !CDS_PN = "2";
BODY = "Q_RES","I62": LOCATION = "R277" #&CDS_LOCATION = "R277" &SEC = "1" #&CDS_SEC = "1";
"A":   PN = "1"  !CDS_PN = "1";
"B":   PN = "2"  !CDS_PN = "2";
BODY = "Q_RES","I66": LOCATION = "R276" #&CDS_LOCATION = "R276" &SEC = "1" #&CDS_SEC = "1";
"A":   PN = "1"  !CDS_PN = "1";
"B":   PN = "2"  !CDS_PN = "2";
BODY = "Q_RES","I68": LOCATION = "R275" #&CDS_LOCATION = "R275" &SEC = "1" #&CDS_SEC = "1";
"A":   PN = "1"  !CDS_PN = "1";
"B":   PN = "2"  !CDS_PN = "2";
BODY = "Q_RES","I71": LOCATION = "R294" #&CDS_LOCATION = "R294" &SEC = "1" #&CDS_SEC = "1";
"A":   PN = "1"  !CDS_PN = "1";
"B":   PN = "2"  !CDS_PN = "2";
BODY = "Q_RES","I72": LOCATION = "R295" #&CDS_LOCATION = "R295" &SEC = "1" #&CDS_SEC = "1";
"A":   PN = "1"  !CDS_PN = "1";
"B":   PN = "2"  !CDS_PN = "2";
BODY = "Q_RES","I88": LOCATION = "R274" #&CDS_LOCATION = "R274" &SEC = "1" #&CDS_SEC = "1";
"A":   PN = "1"  !CDS_PN = "1";
"B":   PN = "2"  !CDS_PN = "2";
BODY = "Q_RES","I89": LOCATION = "R273" #&CDS_LOCATION = "R273" &SEC = "1" #&CDS_SEC = "1";
"A":   PN = "1"  !CDS_PN = "1";
"B":   PN = "2"  !CDS_PN = "2";
BODY = "Q_RES","I90": LOCATION = "R272" #&CDS_LOCATION = "R272" &SEC = "1" #&CDS_SEC = "1";
"A":   PN = "1"  !CDS_PN = "1";
"B":   PN = "2"  !CDS_PN = "2";
BODY = "Q_RES","I92": LOCATION = "R271" #&CDS_LOCATION = "R271" &SEC = "1" #&CDS_SEC = "1";
"A":   PN = "1"  !CDS_PN = "1";
"B":   PN = "2"  !CDS_PN = "2";
BODY = "Q_RES","I93": LOCATION = "R270" #&CDS_LOCATION = "R270" &SEC = "1" #&CDS_SEC = "1";
"A":   PN = "1"  !CDS_PN = "1";
"B":   PN = "2"  !CDS_PN = "2";
BODY = "Q_RES","I94": LOCATION = "R268" #&CDS_LOCATION = "R268" &SEC = "1" #&CDS_SEC = "1";
"A":   PN = "1"  !CDS_PN = "1";
"B":   PN = "2"  !CDS_PN = "2";
BODY = "Q_RES","I95": LOCATION = "R267" #&CDS_LOCATION = "R267" &SEC = "1" #&CDS_SEC = "1";
"A":   PN = "1"  !CDS_PN = "1";
"B":   PN = "2"  !CDS_PN = "2";
BODY = "Q_RES","I96": LOCATION = "R266" #&CDS_LOCATION = "R266" &SEC = "1" #&CDS_SEC = "1";
"A":   PN = "1"  !CDS_PN = "1";
"B":   PN = "2"  !CDS_PN = "2";
BODY = "Q_RES","I97": LOCATION = "R265" #&CDS_LOCATION = "R265" &SEC = "1" #&CDS_SEC = "1";
"A":   PN = "1"  !CDS_PN = "1";
"B":   PN = "2"  !CDS_PN = "2";
BODY = "Q_RES","I98": LOCATION = "R264" #&CDS_LOCATION = "R264" &SEC = "1" #&CDS_SEC = "1";
"A":   PN = "1"  !CDS_PN = "1";
"B":   PN = "2"  !CDS_PN = "2";
BODY = "Q_RES","I100": LOCATION = "R262" #&CDS_LOCATION = "R262" &SEC = "1" #&CDS_SEC = "1";
"A":   PN = "1"  !CDS_PN = "1";
"B":   PN = "2"  !CDS_PN = "2";
BODY = "Q_RES","I101": LOCATION = "R261" #&CDS_LOCATION = "R261" &SEC = "1" #&CDS_SEC = "1";
"A":   PN = "1"  !CDS_PN = "1";
"B":   PN = "2"  !CDS_PN = "2";
BODY = "Q_RES","I116": LOCATION = "R291" #&CDS_LOCATION = "R291" &SEC = "1" #&CDS_SEC = "1";
"A":   PN = "1"  !CDS_PN = "1";
"B":   PN = "2"  !CDS_PN = "2";
BODY = "Q_RES","I125": LOCATION = "R263" #&CDS_LOCATION = "R263" &SEC = "1" #&CDS_SEC = "1";
"A":   PN = "1"  !CDS_PN = "1";
"B":   PN = "2"  !CDS_PN = "2";
BODY = "Q_RES","I135": LOCATION = "R290" #&CDS_LOCATION = "R290" &SEC = "1" #&CDS_SEC = "1";
"A":   PN = "1"  !CDS_PN = "1";
"B":   PN = "2"  !CDS_PN = "2";
BODY = "Q_RES","I136": LOCATION = "R1009" #&CDS_LOCATION = "R1009" &SEC = "1" #&CDS_SEC = "1";
"A":   PN = "1"  !CDS_PN = "1";
"B":   PN = "2"  !CDS_PN = "2";
BODY = "Q_RES","I139": LOCATION = "R1008" #&CDS_LOCATION = "R1008" &SEC = "1" #&CDS_SEC = "1";
"A":   PN = "1"  !CDS_PN = "1";
"B":   PN = "2"  !CDS_PN = "2";
BODY = "Q_RES","I147": LOCATION = "R283" #&CDS_LOCATION = "R283" &SEC = "1" #&CDS_SEC = "1";
"A":   PN = "1"  !CDS_PN = "1";
"B":   PN = "2"  !CDS_PN = "2";
BODY = "Q_RES","I148": LOCATION = "R284" #&CDS_LOCATION = "R284" &SEC = "1" #&CDS_SEC = "1";
"A":   PN = "1"  !CDS_PN = "1";
"B":   PN = "2"  !CDS_PN = "2";
BODY = "Q_RES","I150": LOCATION = "R285" #&CDS_LOCATION = "R285" &SEC = "1" #&CDS_SEC = "1";
"A":   PN = "1"  !CDS_PN = "1";
"B":   PN = "2"  !CDS_PN = "2";
BODY = "Q_RES","I151": LOCATION = "R286" #&CDS_LOCATION = "R286" &SEC = "1" #&CDS_SEC = "1";
"A":   PN = "1"  !CDS_PN = "1";
"B":   PN = "2"  !CDS_PN = "2";
BODY = "Q_RES","I152": LOCATION = "R287" #&CDS_LOCATION = "R287" &SEC = "1" #&CDS_SEC = "1";
"A":   PN = "1"  !CDS_PN = "1";
"B":   PN = "2"  !CDS_PN = "2";
BODY = "Q_RES","I156": LOCATION = "R1232" #&CDS_LOCATION = "R1232" &SEC = "1" #&CDS_SEC = "1";
"A":   PN = "1"  !CDS_PN = "1";
"B":   PN = "2"  !CDS_PN = "2";
BODY = "Q_RES","I158": LOCATION = "R1233" #&CDS_LOCATION = "R1233" &SEC = "1" #&CDS_SEC = "1";
"A":   PN = "1"  !CDS_PN = "1";
"B":   PN = "2"  !CDS_PN = "2";
BODY = "Q_RES","I160": LOCATION = "R1237" #&CDS_LOCATION = "R1237" &SEC = "1" #&CDS_SEC = "1";
"A":   PN = "1"  !CDS_PN = "1";
"B":   PN = "2"  !CDS_PN = "2";
BODY = "Q_RES","I161": LOCATION = "R1238" #&CDS_LOCATION = "R1238" &SEC = "1" #&CDS_SEC = "1";
"A":   PN = "1"  !CDS_PN = "1";
"B":   PN = "2"  !CDS_PN = "2";
BODY = "Q_RES","I163": LOCATION = "R1239" #&CDS_LOCATION = "R1239" &SEC = "1" #&CDS_SEC = "1";
"A":   PN = "1"  !CDS_PN = "1";
"B":   PN = "2"  !CDS_PN = "2";
BODY = "Q_RES","I169": LOCATION = "R1229" #&CDS_LOCATION = "R1229" &SEC = "1" #&CDS_SEC = "1";
"A":   PN = "1"  !CDS_PN = "1";
"B":   PN = "2"  !CDS_PN = "2";
BODY = "Q_RES","I170": LOCATION = "R1230" #&CDS_LOCATION = "R1230" &SEC = "1" #&CDS_SEC = "1";
"A":   PN = "1"  !CDS_PN = "1";
"B":   PN = "2"  !CDS_PN = "2";
BODY = "Q_RES","I172": LOCATION = "R3024" #&CDS_LOCATION = "R3024" &SEC = "1" #&CDS_SEC = "1";
"A":   PN = "1"  !CDS_PN = "1";
"B":   PN = "2"  !CDS_PN = "2";
BODY = "Q_RES","I176": LOCATION = "R1235" #&CDS_LOCATION = "R1235" &SEC = "1" #&CDS_SEC = "1";
"A":   PN = "1"  !CDS_PN = "1";
"B":   PN = "2"  !CDS_PN = "2";
BODY = "Q_RES","I177": LOCATION = "R1236" #&CDS_LOCATION = "R1236" &SEC = "1" #&CDS_SEC = "1";
"A":   PN = "1"  !CDS_PN = "1";
"B":   PN = "2"  !CDS_PN = "2";
BODY = "Q_RES","I196": LOCATION = "R292" #&CDS_LOCATION = "R292" &SEC = "1" #&CDS_SEC = "1";
"A":   PN = "1"  !CDS_PN = "1";
"B":   PN = "2"  !CDS_PN = "2";
BODY = "Q_RES","I211": #LOCATION = "R293" !CDS_LOCATION = "R293" &SEC = "1" #&CDS_SEC = "1";
"A":   PN = "1"  !CDS_PN = "1";
"B":   PN = "2"  !CDS_PN = "2";
BODY = "Q_RES","I215": LOCATION = "R4262" #&CDS_LOCATION = "R4262" &SEC = "1" #&CDS_SEC = "1";
"A":   PN = "1"  !CDS_PN = "1";
"B":   PN = "2"  !CDS_PN = "2";
BODY = "Q_RES","I216": LOCATION = "R4263" #&CDS_LOCATION = "R4263" &SEC = "1" #&CDS_SEC = "1";
"A":   PN = "1"  !CDS_PN = "1";
"B":   PN = "2"  !CDS_PN = "2";
BODY = "Q_RES","I219": LOCATION = "R4260" #&CDS_LOCATION = "R4260" &SEC = "1" #&CDS_SEC = "1";
"A":   PN = "1"  !CDS_PN = "1";
"B":   PN = "2"  !CDS_PN = "2";
BODY = "Q_RES","I220": LOCATION = "R4261" #&CDS_LOCATION = "R4261" &SEC = "1" #&CDS_SEC = "1";
"A":   PN = "1"  !CDS_PN = "1";
"B":   PN = "2"  !CDS_PN = "2";
BODY = "Q_RES","I224": #LOCATION = "R288" !CDS_LOCATION = "R288" &SEC = "1" #&CDS_SEC = "1";
"A":   PN = "1"  !CDS_PN = "1";
"B":   PN = "2"  !CDS_PN = "2";
BODY = "Q_RES","I225": #LOCATION = "R289" !CDS_LOCATION = "R289" &SEC = "1" #&CDS_SEC = "1";
"A":   PN = "1"  !CDS_PN = "1";
"B":   PN = "2"  !CDS_PN = "2";
DRAWING = "@s9s_mb_2u_lib.s9s_mb_2u(sch_1):page120";
BODY = "Q_RES","I27": LOCATION = "R249" #&CDS_LOCATION = "R249" &SEC = "1" #&CDS_SEC = "1";
"A":   PN = "1"  !CDS_PN = "1";
"B":   PN = "2"  !CDS_PN = "2";
BODY = "Q_RES","I28": LOCATION = "R251" #&CDS_LOCATION = "R251" &SEC = "1" #&CDS_SEC = "1";
"A":   PN = "1"  !CDS_PN = "1";
"B":   PN = "2"  !CDS_PN = "2";
BODY = "Q_RES","I29": LOCATION = "R250" #&CDS_LOCATION = "R250" &SEC = "1" #&CDS_SEC = "1";
"A":   PN = "1"  !CDS_PN = "1";
"B":   PN = "2"  !CDS_PN = "2";
BODY = "Q_RES","I30": LOCATION = "R252" #&CDS_LOCATION = "R252" &SEC = "1" #&CDS_SEC = "1";
"A":   PN = "1"  !CDS_PN = "1";
"B":   PN = "2"  !CDS_PN = "2";
BODY = "Q_RES","I31": LOCATION = "R253" #&CDS_LOCATION = "R253" &SEC = "1" #&CDS_SEC = "1";
"A":   PN = "1"  !CDS_PN = "1";
"B":   PN = "2"  !CDS_PN = "2";
BODY = "Q_RES","I32": LOCATION = "R254" #&CDS_LOCATION = "R254" &SEC = "1" #&CDS_SEC = "1";
"A":   PN = "1"  !CDS_PN = "1";
"B":   PN = "2"  !CDS_PN = "2";
BODY = "Q_RES","I42": LOCATION = "R255" #&CDS_LOCATION = "R255" &SEC = "1" #&CDS_SEC = "1";
"A":   PN = "1"  !CDS_PN = "1";
"B":   PN = "2"  !CDS_PN = "2";
BODY = "Q_RES","I43": LOCATION = "R257" #&CDS_LOCATION = "R257" &SEC = "1" #&CDS_SEC = "1";
"A":   PN = "1"  !CDS_PN = "1";
"B":   PN = "2"  !CDS_PN = "2";
BODY = "Q_RES","I44": LOCATION = "R258" #&CDS_LOCATION = "R258" &SEC = "1" #&CDS_SEC = "1";
"A":   PN = "1"  !CDS_PN = "1";
"B":   PN = "2"  !CDS_PN = "2";
BODY = "Q_RES","I45": LOCATION = "R259" #&CDS_LOCATION = "R259" &SEC = "1" #&CDS_SEC = "1";
"A":   PN = "1"  !CDS_PN = "1";
"B":   PN = "2"  !CDS_PN = "2";
BODY = "Q_RES","I46": LOCATION = "R260" #&CDS_LOCATION = "R260" &SEC = "1" #&CDS_SEC = "1";
"A":   PN = "1"  !CDS_PN = "1";
"B":   PN = "2"  !CDS_PN = "2";
BODY = "Q_RES","I48": LOCATION = "R256" #&CDS_LOCATION = "R256" &SEC = "1" #&CDS_SEC = "1";
"A":   PN = "1"  !CDS_PN = "1";
"B":   PN = "2"  !CDS_PN = "2";
BODY = "Q_RES","I61": LOCATION = "R1391" #&CDS_LOCATION = "R1391" &SEC = "1" #&CDS_SEC = "1";
"A":   PN = "1"  !CDS_PN = "1";
"B":   PN = "2"  !CDS_PN = "2";
BODY = "Q_RES","I62": LOCATION = "R1392" #&CDS_LOCATION = "R1392" &SEC = "1" #&CDS_SEC = "1";
"A":   PN = "1"  !CDS_PN = "1";
"B":   PN = "2"  !CDS_PN = "2";
BODY = "Q_RES","I66": LOCATION = "R1393" #&CDS_LOCATION = "R1393" &SEC = "1" #&CDS_SEC = "1";
"A":   PN = "1"  !CDS_PN = "1";
"B":   PN = "2"  !CDS_PN = "2";
BODY = "Q_RES","I67": LOCATION = "R1394" #&CDS_LOCATION = "R1394" &SEC = "1" #&CDS_SEC = "1";
"A":   PN = "1"  !CDS_PN = "1";
"B":   PN = "2"  !CDS_PN = "2";
DRAWING = "@s9s_mb_2u_lib.s9s_mb_2u(sch_1):page123";
BODY = "Q_RES","I8": #LOCATION = "R206" !CDS_LOCATION = "R206" &SEC = "1" #&CDS_SEC = "1";
"A":   PN = "1"  !CDS_PN = "1";
"B":   PN = "2"  !CDS_PN = "2";
BODY = "Q_RES","I4": LOCATION = "R188" #&CDS_LOCATION = "R188" &SEC = "1" #&CDS_SEC = "1";
"A":   PN = "1"  !CDS_PN = "1";
"B":   PN = "2"  !CDS_PN = "2";
BODY = "Q_RES","I5": LOCATION = "R196" #&CDS_LOCATION = "R196" &SEC = "1" #&CDS_SEC = "1";
"A":   PN = "1"  !CDS_PN = "1";
"B":   PN = "2"  !CDS_PN = "2";
BODY = "Q_RES","I6": LOCATION = "R195" #&CDS_LOCATION = "R195" &SEC = "1" #&CDS_SEC = "1";
"A":   PN = "1"  !CDS_PN = "1";
"B":   PN = "2"  !CDS_PN = "2";
BODY = "Q_RES","I7": #LOCATION = "R202" !CDS_LOCATION = "R202" &SEC = "1" #&CDS_SEC = "1";
"A":   PN = "1"  !CDS_PN = "1";
"B":   PN = "2"  !CDS_PN = "2";
BODY = "Q_RES","I10": #LOCATION = "R205" !CDS_LOCATION = "R205" &SEC = "1" #&CDS_SEC = "1";
"A":   PN = "1"  !CDS_PN = "1";
"B":   PN = "2"  !CDS_PN = "2";
BODY = "BC847BPN","I11": #LOCATION = "Q140" !CDS_LOCATION = "Q140" &SEC = "2" #&CDS_SEC = "2";
"B2":   PN = "5"  !CDS_PN = "5";
"C2":   PN = "3"  !CDS_PN = "3";
"E2":   PN = "4"  !CDS_PN = "4";
BODY = "BC847BPN","I12": #LOCATION = "Q141" !CDS_LOCATION = "Q141" &SEC = "2" #&CDS_SEC = "2";
"B2":   PN = "5"  !CDS_PN = "5";
"C2":   PN = "3"  !CDS_PN = "3";
"E2":   PN = "4"  !CDS_PN = "4";
BODY = "Q_RES","I14": LOCATION = "R4410" #&CDS_LOCATION = "R4410" &SEC = "1" #&CDS_SEC = "1";
"A":   PN = "1"  !CDS_PN = "1";
"B":   PN = "2"  !CDS_PN = "2";
BODY = "Q_RES","I15": LOCATION = "R4409" #&CDS_LOCATION = "R4409" &SEC = "1" #&CDS_SEC = "1";
"A":   PN = "1"  !CDS_PN = "1";
"B":   PN = "2"  !CDS_PN = "2";
BODY = "BC847BPN","I16": #LOCATION = "Q140" !CDS_LOCATION = "Q140" &SEC = "1" #&CDS_SEC = "1";
"B1":   PN = "2"  !CDS_PN = "2";
"C1":   PN = "6"  !CDS_PN = "6";
"E1":   PN = "1"  !CDS_PN = "1";
BODY = "BC847BPN","I18": #LOCATION = "Q141" !CDS_LOCATION = "Q141" &SEC = "1" #&CDS_SEC = "1";
"B1":   PN = "2"  !CDS_PN = "2";
"C1":   PN = "6"  !CDS_PN = "6";
"E1":   PN = "1"  !CDS_PN = "1";
BODY = "Q_RES","I19": #LOCATION = "R200" !CDS_LOCATION = "R200" &SEC = "1" #&CDS_SEC = "1";
"A":   PN = "1"  !CDS_PN = "1";
"B":   PN = "2"  !CDS_PN = "2";
BODY = "Q_RES","I23": #LOCATION = "R198" !CDS_LOCATION = "R198" &SEC = "1" #&CDS_SEC = "1";
"A":   PN = "1"  !CDS_PN = "1";
"B":   PN = "2"  !CDS_PN = "2";
BODY = "Q_RES","I27": #LOCATION = "R197" !CDS_LOCATION = "R197" &SEC = "1" #&CDS_SEC = "1";
"A":   PN = "1"  !CDS_PN = "1";
"B":   PN = "2"  !CDS_PN = "2";
BODY = "Q_RES","I29": LOCATION = "R4412" #&CDS_LOCATION = "R4412" &SEC = "1" #&CDS_SEC = "1";
"A":   PN = "1"  !CDS_PN = "1";
"B":   PN = "2"  !CDS_PN = "2";
BODY = "Q_RES","I31": LOCATION = "R4414" #&CDS_LOCATION = "R4414" &SEC = "1" #&CDS_SEC = "1";
"A":   PN = "1"  !CDS_PN = "1";
"B":   PN = "2"  !CDS_PN = "2";
BODY = "Q_RES","I32": LOCATION = "R4411" #&CDS_LOCATION = "R4411" &SEC = "1" #&CDS_SEC = "1";
"A":   PN = "1"  !CDS_PN = "1";
"B":   PN = "2"  !CDS_PN = "2";
BODY = "Q_RES","I33": LOCATION = "R4413" #&CDS_LOCATION = "R4413" &SEC = "1" #&CDS_SEC = "1";
"A":   PN = "1"  !CDS_PN = "1";
"B":   PN = "2"  !CDS_PN = "2";
DRAWING = "@s9s_mb_2u_lib.s9s_mb_2u(sch_1):page124";
BODY = "Q_RES","I17": LOCATION = "R160" #&CDS_LOCATION = "R160" &SEC = "1" #&CDS_SEC = "1";
"A":   PN = "1"  !CDS_PN = "1";
"B":   PN = "2"  !CDS_PN = "2";
BODY = "Q_RES","I19": LOCATION = "R162" #&CDS_LOCATION = "R162" &SEC = "1" #&CDS_SEC = "1";
"A":   PN = "1"  !CDS_PN = "1";
"B":   PN = "2"  !CDS_PN = "2";
BODY = "Q_RES","I26": LOCATION = "R164" #&CDS_LOCATION = "R164" &SEC = "1" #&CDS_SEC = "1";
"A":   PN = "1"  !CDS_PN = "1";
"B":   PN = "2"  !CDS_PN = "2";
BODY = "Q_RES","I33": LOCATION = "R166" #&CDS_LOCATION = "R166" &SEC = "1" #&CDS_SEC = "1";
"A":   PN = "1"  !CDS_PN = "1";
"B":   PN = "2"  !CDS_PN = "2";
BODY = "Q_RES","I43": LOCATION = "R168" #&CDS_LOCATION = "R168" &SEC = "1" #&CDS_SEC = "1";
"A":   PN = "1"  !CDS_PN = "1";
"B":   PN = "2"  !CDS_PN = "2";
BODY = "Q_RES","I52": LOCATION = "R171" #&CDS_LOCATION = "R171" &SEC = "1" #&CDS_SEC = "1";
"A":   PN = "1"  !CDS_PN = "1";
"B":   PN = "2"  !CDS_PN = "2";
BODY = "Q_RES","I60": LOCATION = "R185" #&CDS_LOCATION = "R185" &SEC = "1" #&CDS_SEC = "1";
"A":   PN = "1"  !CDS_PN = "1";
"B":   PN = "2"  !CDS_PN = "2";
BODY = "Q_RES","I62": LOCATION = "R183" #&CDS_LOCATION = "R183" &SEC = "1" #&CDS_SEC = "1";
"A":   PN = "1"  !CDS_PN = "1";
"B":   PN = "2"  !CDS_PN = "2";
BODY = "Q_RES","I68": LOCATION = "R181" #&CDS_LOCATION = "R181" &SEC = "1" #&CDS_SEC = "1";
"A":   PN = "1"  !CDS_PN = "1";
"B":   PN = "2"  !CDS_PN = "2";
BODY = "Q_RES","I70": LOCATION = "R179" #&CDS_LOCATION = "R179" &SEC = "1" #&CDS_SEC = "1";
"A":   PN = "1"  !CDS_PN = "1";
"B":   PN = "2"  !CDS_PN = "2";
BODY = "Q_RES","I72": LOCATION = "R177" #&CDS_LOCATION = "R177" &SEC = "1" #&CDS_SEC = "1";
"A":   PN = "1"  !CDS_PN = "1";
"B":   PN = "2"  !CDS_PN = "2";
BODY = "Q_RES","I76": #LOCATION = "R175" !CDS_LOCATION = "R175" &SEC = "1" #&CDS_SEC = "1";
"A":   PN = "1"  !CDS_PN = "1";
"B":   PN = "2"  !CDS_PN = "2";
BODY = "Q_RES","I77": #LOCATION = "R184" !CDS_LOCATION = "R184" &SEC = "1" #&CDS_SEC = "1";
"A":   PN = "1"  !CDS_PN = "1";
"B":   PN = "2"  !CDS_PN = "2";
BODY = "Q_RES","I78": #LOCATION = "R186" !CDS_LOCATION = "R186" &SEC = "1" #&CDS_SEC = "1";
"A":   PN = "1"  !CDS_PN = "1";
"B":   PN = "2"  !CDS_PN = "2";
BODY = "Q_RES","I79": LOCATION = "R4298" #&CDS_LOCATION = "R4298" &SEC = "1" #&CDS_SEC = "1";
"A":   PN = "1"  !CDS_PN = "1";
"B":   PN = "2"  !CDS_PN = "2";
BODY = "Q_RES","I82": LOCATION = "R4297" #&CDS_LOCATION = "R4297" &SEC = "1" #&CDS_SEC = "1";
"A":   PN = "1"  !CDS_PN = "1";
"B":   PN = "2"  !CDS_PN = "2";
BODY = "Q_RES","I85": LOCATION = "R4296" #&CDS_LOCATION = "R4296" &SEC = "1" #&CDS_SEC = "1";
"A":   PN = "1"  !CDS_PN = "1";
"B":   PN = "2"  !CDS_PN = "2";
BODY = "Q_RES","I87": LOCATION = "R4295" #&CDS_LOCATION = "R4295" &SEC = "1" #&CDS_SEC = "1";
"A":   PN = "1"  !CDS_PN = "1";
"B":   PN = "2"  !CDS_PN = "2";
DRAWING = "@s9s_mb_2u_lib.s9s_mb_2u(sch_1):page125";
BODY = "Q_RES","I3": LOCATION = "R132" #&CDS_LOCATION = "R132" &SEC = "1" #&CDS_SEC = "1";
"A":   PN = "1"  !CDS_PN = "1";
"B":   PN = "2"  !CDS_PN = "2";
BODY = "Q_RES","I5": LOCATION = "R130" #&CDS_LOCATION = "R130" &SEC = "1" #&CDS_SEC = "1";
"A":   PN = "1"  !CDS_PN = "1";
"B":   PN = "2"  !CDS_PN = "2";
BODY = "Q_RES","I7": LOCATION = "R128" #&CDS_LOCATION = "R128" &SEC = "1" #&CDS_SEC = "1";
"A":   PN = "1"  !CDS_PN = "1";
"B":   PN = "2"  !CDS_PN = "2";
BODY = "Q_RES","I13": LOCATION = "R126" #&CDS_LOCATION = "R126" &SEC = "1" #&CDS_SEC = "1";
"A":   PN = "1"  !CDS_PN = "1";
"B":   PN = "2"  !CDS_PN = "2";
BODY = "Q_RES","I15": LOCATION = "R124" #&CDS_LOCATION = "R124" &SEC = "1" #&CDS_SEC = "1";
"A":   PN = "1"  !CDS_PN = "1";
"B":   PN = "2"  !CDS_PN = "2";
BODY = "Q_RES","I17": LOCATION = "R122" #&CDS_LOCATION = "R122" &SEC = "1" #&CDS_SEC = "1";
"A":   PN = "1"  !CDS_PN = "1";
"B":   PN = "2"  !CDS_PN = "2";
BODY = "Q_RES","I24": LOCATION = "R157" #&CDS_LOCATION = "R157" &SEC = "1" #&CDS_SEC = "1";
"A":   PN = "1"  !CDS_PN = "1";
"B":   PN = "2"  !CDS_PN = "2";
BODY = "Q_RES","I26": LOCATION = "R155" #&CDS_LOCATION = "R155" &SEC = "1" #&CDS_SEC = "1";
"A":   PN = "1"  !CDS_PN = "1";
"B":   PN = "2"  !CDS_PN = "2";
BODY = "Q_RES","I56": LOCATION = "R153" #&CDS_LOCATION = "R153" &SEC = "1" #&CDS_SEC = "1";
"A":   PN = "1"  !CDS_PN = "1";
"B":   PN = "2"  !CDS_PN = "2";
BODY = "Q_RES","I58": LOCATION = "R151" #&CDS_LOCATION = "R151" &SEC = "1" #&CDS_SEC = "1";
"A":   PN = "1"  !CDS_PN = "1";
"B":   PN = "2"  !CDS_PN = "2";
BODY = "Q_RES","I60": LOCATION = "R137" #&CDS_LOCATION = "R137" &SEC = "1" #&CDS_SEC = "1";
"A":   PN = "1"  !CDS_PN = "1";
"B":   PN = "2"  !CDS_PN = "2";
BODY = "Q_RES","I62": LOCATION = "R135" #&CDS_LOCATION = "R135" &SEC = "1" #&CDS_SEC = "1";
"A":   PN = "1"  !CDS_PN = "1";
"B":   PN = "2"  !CDS_PN = "2";
BODY = "Q_RES","I64": #LOCATION = "R156" !CDS_LOCATION = "R156" &SEC = "1" #&CDS_SEC = "1";
"A":   PN = "1"  !CDS_PN = "1";
"B":   PN = "2"  !CDS_PN = "2";
BODY = "Q_RES","I65": #LOCATION = "R158" !CDS_LOCATION = "R158" &SEC = "1" #&CDS_SEC = "1";
"A":   PN = "1"  !CDS_PN = "1";
"B":   PN = "2"  !CDS_PN = "2";
BODY = "Q_RES","I66": LOCATION = "R4302" #&CDS_LOCATION = "R4302" &SEC = "1" #&CDS_SEC = "1";
"A":   PN = "1"  !CDS_PN = "1";
"B":   PN = "2"  !CDS_PN = "2";
BODY = "Q_RES","I68": LOCATION = "R4301" #&CDS_LOCATION = "R4301" &SEC = "1" #&CDS_SEC = "1";
"A":   PN = "1"  !CDS_PN = "1";
"B":   PN = "2"  !CDS_PN = "2";
BODY = "Q_RES","I70": LOCATION = "R4300" #&CDS_LOCATION = "R4300" &SEC = "1" #&CDS_SEC = "1";
"A":   PN = "1"  !CDS_PN = "1";
"B":   PN = "2"  !CDS_PN = "2";
BODY = "Q_RES","I72": LOCATION = "R4299" #&CDS_LOCATION = "R4299" &SEC = "1" #&CDS_SEC = "1";
"A":   PN = "1"  !CDS_PN = "1";
"B":   PN = "2"  !CDS_PN = "2";
DRAWING = "@s9s_mb_2u_lib.s9s_mb_2u(sch_1):page126";
BODY = "Q_RES","I22": LOCATION = "R96" #&CDS_LOCATION = "R96" &SEC = "1" #&CDS_SEC = "1";
"A":   PN = "1"  !CDS_PN = "1";
"B":   PN = "2"  !CDS_PN = "2";
BODY = "Q_RES","I23": LOCATION = "R95" #&CDS_LOCATION = "R95" &SEC = "1" #&CDS_SEC = "1";
"A":   PN = "1"  !CDS_PN = "1";
"B":   PN = "2"  !CDS_PN = "2";
BODY = "Q_RES","I25": LOCATION = "R94" #&CDS_LOCATION = "R94" &SEC = "1" #&CDS_SEC = "1";
"A":   PN = "1"  !CDS_PN = "1";
"B":   PN = "2"  !CDS_PN = "2";
BODY = "Q_RES","I114": LOCATION = "R97" #&CDS_LOCATION = "R97" &SEC = "1" #&CDS_SEC = "1";
"A":   PN = "1"  !CDS_PN = "1";
"B":   PN = "2"  !CDS_PN = "2";
BODY = "Q_RES","I135": LOCATION = "R90" #&CDS_LOCATION = "R90" &SEC = "1" #&CDS_SEC = "1";
"A":   PN = "1"  !CDS_PN = "1";
"B":   PN = "2"  !CDS_PN = "2";
BODY = "Q_RES","I136": LOCATION = "R91" #&CDS_LOCATION = "R91" &SEC = "1" #&CDS_SEC = "1";
"A":   PN = "1"  !CDS_PN = "1";
"B":   PN = "2"  !CDS_PN = "2";
BODY = "Q_RES","I140": LOCATION = "R92" #&CDS_LOCATION = "R92" &SEC = "1" #&CDS_SEC = "1";
"A":   PN = "1"  !CDS_PN = "1";
"B":   PN = "2"  !CDS_PN = "2";
BODY = "Q_RES","I141": LOCATION = "R93" #&CDS_LOCATION = "R93" &SEC = "1" #&CDS_SEC = "1";
"A":   PN = "1"  !CDS_PN = "1";
"B":   PN = "2"  !CDS_PN = "2";
DRAWING = "@s9s_mb_2u_lib.s9s_mb_2u(sch_1):page127";
BODY = "Q_RES","I1": LOCATION = "R334" #&CDS_LOCATION = "R334" &SEC = "1" #&CDS_SEC = "1";
"A":   PN = "1"  !CDS_PN = "1";
"B":   PN = "2"  !CDS_PN = "2";
BODY = "Q_RES","I5": LOCATION = "R335" #&CDS_LOCATION = "R335" &SEC = "1" #&CDS_SEC = "1";
"A":   PN = "1"  !CDS_PN = "1";
"B":   PN = "2"  !CDS_PN = "2";
BODY = "Q_RES","I6": LOCATION = "R333" #&CDS_LOCATION = "R333" &SEC = "1" #&CDS_SEC = "1";
"A":   PN = "1"  !CDS_PN = "1";
"B":   PN = "2"  !CDS_PN = "2";
BODY = "Q_RES","I7": LOCATION = "R515" #&CDS_LOCATION = "R515" &SEC = "1" #&CDS_SEC = "1";
"A":   PN = "1"  !CDS_PN = "1";
"B":   PN = "2"  !CDS_PN = "2";
BODY = "Q_RES","I13": LOCATION = "R629" #&CDS_LOCATION = "R629" &SEC = "1" #&CDS_SEC = "1";
"A":   PN = "1"  !CDS_PN = "1";
"B":   PN = "2"  !CDS_PN = "2";
BODY = "Q_RES","I14": LOCATION = "R627" #&CDS_LOCATION = "R627" &SEC = "1" #&CDS_SEC = "1";
"A":   PN = "1"  !CDS_PN = "1";
"B":   PN = "2"  !CDS_PN = "2";
BODY = "Q_RES","I15": LOCATION = "R630" #&CDS_LOCATION = "R630" &SEC = "1" #&CDS_SEC = "1";
"A":   PN = "1"  !CDS_PN = "1";
"B":   PN = "2"  !CDS_PN = "2";
BODY = "Q_RES","I17": LOCATION = "R628" #&CDS_LOCATION = "R628" &SEC = "1" #&CDS_SEC = "1";
"A":   PN = "1"  !CDS_PN = "1";
"B":   PN = "2"  !CDS_PN = "2";
BODY = "Q_RES","I20": LOCATION = "R331" #&CDS_LOCATION = "R331" &SEC = "1" #&CDS_SEC = "1";
"A":   PN = "1"  !CDS_PN = "1";
"B":   PN = "2"  !CDS_PN = "2";
BODY = "Q_RES","I21": LOCATION = "R332" #&CDS_LOCATION = "R332" &SEC = "1" #&CDS_SEC = "1";
"A":   PN = "1"  !CDS_PN = "1";
"B":   PN = "2"  !CDS_PN = "2";
BODY = "Q_RES","I24": LOCATION = "R625" #&CDS_LOCATION = "R625" &SEC = "1" #&CDS_SEC = "1";
"A":   PN = "1"  !CDS_PN = "1";
"B":   PN = "2"  !CDS_PN = "2";
BODY = "Q_RES","I26": LOCATION = "R626" #&CDS_LOCATION = "R626" &SEC = "1" #&CDS_SEC = "1";
"A":   PN = "1"  !CDS_PN = "1";
"B":   PN = "2"  !CDS_PN = "2";
BODY = "Q_RES","I31": LOCATION = "R997" #&CDS_LOCATION = "R997" &SEC = "1" #&CDS_SEC = "1";
"A":   PN = "1"  !CDS_PN = "1";
"B":   PN = "2"  !CDS_PN = "2";
BODY = "Q_RES","I32": LOCATION = "R650" #&CDS_LOCATION = "R650" &SEC = "1" #&CDS_SEC = "1";
"A":   PN = "1"  !CDS_PN = "1";
"B":   PN = "2"  !CDS_PN = "2";
BODY = "Q_RES","I35": LOCATION = "R1004" #&CDS_LOCATION = "R1004" &SEC = "1" #&CDS_SEC = "1";
"A":   PN = "1"  !CDS_PN = "1";
"B":   PN = "2"  !CDS_PN = "2";
BODY = "Q_RES","I36": LOCATION = "R1005" #&CDS_LOCATION = "R1005" &SEC = "1" #&CDS_SEC = "1";
"A":   PN = "1"  !CDS_PN = "1";
"B":   PN = "2"  !CDS_PN = "2";
DRAWING = "@s9s_mb_2u_lib.s9s_mb_2u(sch_1):page128";
BODY = "Q_RES","I9": LOCATION = "R854" #&CDS_LOCATION = "R854" &SEC = "1" #&CDS_SEC = "1";
"A":   PN = "1"  !CDS_PN = "1";
"B":   PN = "2"  !CDS_PN = "2";
BODY = "Q_RES","I10": LOCATION = "R853" #&CDS_LOCATION = "R853" &SEC = "1" #&CDS_SEC = "1";
"A":   PN = "1"  !CDS_PN = "1";
"B":   PN = "2"  !CDS_PN = "2";
BODY = "Q_RES","I11": LOCATION = "R852" #&CDS_LOCATION = "R852" &SEC = "1" #&CDS_SEC = "1";
"A":   PN = "1"  !CDS_PN = "1";
"B":   PN = "2"  !CDS_PN = "2";
BODY = "Q_RES","I12": LOCATION = "R851" #&CDS_LOCATION = "R851" &SEC = "1" #&CDS_SEC = "1";
"A":   PN = "1"  !CDS_PN = "1";
"B":   PN = "2"  !CDS_PN = "2";
BODY = "Q_RES","I48": LOCATION = "R861" #&CDS_LOCATION = "R861" &SEC = "1" #&CDS_SEC = "1";
"A":   PN = "1"  !CDS_PN = "1";
"B":   PN = "2"  !CDS_PN = "2";
BODY = "Q_RES","I49": LOCATION = "R2969" #&CDS_LOCATION = "R2969" &SEC = "1" #&CDS_SEC = "1";
"A":   PN = "1"  !CDS_PN = "1";
"B":   PN = "2"  !CDS_PN = "2";
BODY = "Q_RES","I50": LOCATION = "R859" #&CDS_LOCATION = "R859" &SEC = "1" #&CDS_SEC = "1";
"A":   PN = "1"  !CDS_PN = "1";
"B":   PN = "2"  !CDS_PN = "2";
BODY = "Q_RES","I51": LOCATION = "R860" #&CDS_LOCATION = "R860" &SEC = "1" #&CDS_SEC = "1";
"A":   PN = "1"  !CDS_PN = "1";
"B":   PN = "2"  !CDS_PN = "2";
BODY = "Q_RES","I77": LOCATION = "R938" #&CDS_LOCATION = "R938" &SEC = "1" #&CDS_SEC = "1";
"A":   PN = "1"  !CDS_PN = "1";
"B":   PN = "2"  !CDS_PN = "2";
BODY = "Q_RES","I78": LOCATION = "R936" #&CDS_LOCATION = "R936" &SEC = "1" #&CDS_SEC = "1";
"A":   PN = "1"  !CDS_PN = "1";
"B":   PN = "2"  !CDS_PN = "2";
BODY = "Q_RES","I79": LOCATION = "R934" #&CDS_LOCATION = "R934" &SEC = "1" #&CDS_SEC = "1";
"A":   PN = "1"  !CDS_PN = "1";
"B":   PN = "2"  !CDS_PN = "2";
BODY = "Q_RES","I80": LOCATION = "R932" #&CDS_LOCATION = "R932" &SEC = "1" #&CDS_SEC = "1";
"A":   PN = "1"  !CDS_PN = "1";
"B":   PN = "2"  !CDS_PN = "2";
BODY = "Q_RES","I82": LOCATION = "R933" #&CDS_LOCATION = "R933" &SEC = "1" #&CDS_SEC = "1";
"A":   PN = "1"  !CDS_PN = "1";
"B":   PN = "2"  !CDS_PN = "2";
BODY = "Q_RES","I83": LOCATION = "R939" #&CDS_LOCATION = "R939" &SEC = "1" #&CDS_SEC = "1";
"A":   PN = "1"  !CDS_PN = "1";
"B":   PN = "2"  !CDS_PN = "2";
BODY = "Q_RES","I85": LOCATION = "R937" #&CDS_LOCATION = "R937" &SEC = "1" #&CDS_SEC = "1";
"A":   PN = "1"  !CDS_PN = "1";
"B":   PN = "2"  !CDS_PN = "2";
BODY = "Q_RES","I86": LOCATION = "R935" #&CDS_LOCATION = "R935" &SEC = "1" #&CDS_SEC = "1";
"A":   PN = "1"  !CDS_PN = "1";
"B":   PN = "2"  !CDS_PN = "2";
DRAWING = "@s9s_mb_2u_lib.s9s_mb_2u(sch_1):page129";
BODY = "Q_RES","I26": LOCATION = "R836" #&CDS_LOCATION = "R836" &SEC = "1" #&CDS_SEC = "1";
"A":   PN = "1"  !CDS_PN = "1";
"B":   PN = "2"  !CDS_PN = "2";
BODY = "Q_RES","I59": LOCATION = "R837" #&CDS_LOCATION = "R837" &SEC = "1" #&CDS_SEC = "1";
"A":   PN = "1"  !CDS_PN = "1";
"B":   PN = "2"  !CDS_PN = "2";
BODY = "Q_RES","I76": LOCATION = "R838" #&CDS_LOCATION = "R838" &SEC = "1" #&CDS_SEC = "1";
"A":   PN = "1"  !CDS_PN = "1";
"B":   PN = "2"  !CDS_PN = "2";
BODY = "Q_RES","I86": LOCATION = "R835" #&CDS_LOCATION = "R835" &SEC = "1" #&CDS_SEC = "1";
"A":   PN = "1"  !CDS_PN = "1";
"B":   PN = "2"  !CDS_PN = "2";
BODY = "Q_CAP","I91": LOCATION = "C622" #&CDS_LOCATION = "C622" &SEC = "1" #&CDS_SEC = "1";
"A":   PN = "1"  !CDS_PN = "1";
"B":   PN = "2"  !CDS_PN = "2";
BODY = "Q_CAP","I94": LOCATION = "C623" #&CDS_LOCATION = "C623" &SEC = "1" #&CDS_SEC = "1";
"A":   PN = "1"  !CDS_PN = "1";
"B":   PN = "2"  !CDS_PN = "2";
BODY = "Q_CAP","I99": LOCATION = "C624" #&CDS_LOCATION = "C624" &SEC = "1" #&CDS_SEC = "1";
"A":   PN = "1"  !CDS_PN = "1";
"B":   PN = "2"  !CDS_PN = "2";
BODY = "Q_CAP","I102": LOCATION = "C621" #&CDS_LOCATION = "C621" &SEC = "1" #&CDS_SEC = "1";
"A":   PN = "1"  !CDS_PN = "1";
"B":   PN = "2"  !CDS_PN = "2";
BODY = "Q_RES","I103": LOCATION = "R706" #&CDS_LOCATION = "R706" &SEC = "1" #&CDS_SEC = "1";
"A":   PN = "1"  !CDS_PN = "1";
"B":   PN = "2"  !CDS_PN = "2";
BODY = "Q_RES","I106": LOCATION = "R707" #&CDS_LOCATION = "R707" &SEC = "1" #&CDS_SEC = "1";
"A":   PN = "1"  !CDS_PN = "1";
"B":   PN = "2"  !CDS_PN = "2";
BODY = "Q_RES","I109": LOCATION = "R708" #&CDS_LOCATION = "R708" &SEC = "1" #&CDS_SEC = "1";
"A":   PN = "1"  !CDS_PN = "1";
"B":   PN = "2"  !CDS_PN = "2";
BODY = "Q_RES","I112": LOCATION = "R705" #&CDS_LOCATION = "R705" &SEC = "1" #&CDS_SEC = "1";
"A":   PN = "1"  !CDS_PN = "1";
"B":   PN = "2"  !CDS_PN = "2";
BODY = "Q_RES","I119": LOCATION = "R840" #&CDS_LOCATION = "R840" &SEC = "1" #&CDS_SEC = "1";
"A":   PN = "1"  !CDS_PN = "1";
"B":   PN = "2"  !CDS_PN = "2";
BODY = "Q_RES","I121": LOCATION = "R841" #&CDS_LOCATION = "R841" &SEC = "1" #&CDS_SEC = "1";
"A":   PN = "1"  !CDS_PN = "1";
"B":   PN = "2"  !CDS_PN = "2";
BODY = "Q_RES","I123": LOCATION = "R842" #&CDS_LOCATION = "R842" &SEC = "1" #&CDS_SEC = "1";
"A":   PN = "1"  !CDS_PN = "1";
"B":   PN = "2"  !CDS_PN = "2";
BODY = "Q_RES","I125": LOCATION = "R839" #&CDS_LOCATION = "R839" &SEC = "1" #&CDS_SEC = "1";
"A":   PN = "1"  !CDS_PN = "1";
"B":   PN = "2"  !CDS_PN = "2";
DRAWING = "@s9s_mb_2u_lib.s9s_mb_2u(sch_1):page130";
BODY = "Q_RES","I11": LOCATION = "R815" #&CDS_LOCATION = "R815" &SEC = "1" #&CDS_SEC = "1";
"A":   PN = "1"  !CDS_PN = "1";
"B":   PN = "2"  !CDS_PN = "2";
BODY = "Q_RES","I22": LOCATION = "R818" #&CDS_LOCATION = "R818" &SEC = "1" #&CDS_SEC = "1";
"A":   PN = "1"  !CDS_PN = "1";
"B":   PN = "2"  !CDS_PN = "2";
BODY = "Q_RES","I26": LOCATION = "R817" #&CDS_LOCATION = "R817" &SEC = "1" #&CDS_SEC = "1";
"A":   PN = "1"  !CDS_PN = "1";
"B":   PN = "2"  !CDS_PN = "2";
BODY = "Q_RES","I37": LOCATION = "R816" #&CDS_LOCATION = "R816" &SEC = "1" #&CDS_SEC = "1";
"A":   PN = "1"  !CDS_PN = "1";
"B":   PN = "2"  !CDS_PN = "2";
BODY = "Q_CAP","I59": LOCATION = "C616" #&CDS_LOCATION = "C616" &SEC = "1" #&CDS_SEC = "1";
"A":   PN = "1"  !CDS_PN = "1";
"B":   PN = "2"  !CDS_PN = "2";
BODY = "Q_CAP","I62": LOCATION = "C615" #&CDS_LOCATION = "C615" &SEC = "1" #&CDS_SEC = "1";
"A":   PN = "1"  !CDS_PN = "1";
"B":   PN = "2"  !CDS_PN = "2";
BODY = "Q_RES","I63": LOCATION = "R701" #&CDS_LOCATION = "R701" &SEC = "1" #&CDS_SEC = "1";
"A":   PN = "1"  !CDS_PN = "1";
"B":   PN = "2"  !CDS_PN = "2";
BODY = "Q_CAP","I65": LOCATION = "C614" #&CDS_LOCATION = "C614" &SEC = "1" #&CDS_SEC = "1";
"A":   PN = "1"  !CDS_PN = "1";
"B":   PN = "2"  !CDS_PN = "2";
BODY = "Q_CAP","I68": LOCATION = "C613" #&CDS_LOCATION = "C613" &SEC = "1" #&CDS_SEC = "1";
"A":   PN = "1"  !CDS_PN = "1";
"B":   PN = "2"  !CDS_PN = "2";
BODY = "Q_RES","I75": LOCATION = "R704" #&CDS_LOCATION = "R704" &SEC = "1" #&CDS_SEC = "1";
"A":   PN = "1"  !CDS_PN = "1";
"B":   PN = "2"  !CDS_PN = "2";
BODY = "Q_RES","I76": LOCATION = "R702" #&CDS_LOCATION = "R702" &SEC = "1" #&CDS_SEC = "1";
"A":   PN = "1"  !CDS_PN = "1";
"B":   PN = "2"  !CDS_PN = "2";
BODY = "Q_RES","I79": LOCATION = "R703" #&CDS_LOCATION = "R703" &SEC = "1" #&CDS_SEC = "1";
"A":   PN = "1"  !CDS_PN = "1";
"B":   PN = "2"  !CDS_PN = "2";
BODY = "Q_RES","I82": LOCATION = "R820" #&CDS_LOCATION = "R820" &SEC = "1" #&CDS_SEC = "1";
"A":   PN = "1"  !CDS_PN = "1";
"B":   PN = "2"  !CDS_PN = "2";
BODY = "Q_RES","I84": LOCATION = "R821" #&CDS_LOCATION = "R821" &SEC = "1" #&CDS_SEC = "1";
"A":   PN = "1"  !CDS_PN = "1";
"B":   PN = "2"  !CDS_PN = "2";
BODY = "Q_RES","I88": LOCATION = "R822" #&CDS_LOCATION = "R822" &SEC = "1" #&CDS_SEC = "1";
"A":   PN = "1"  !CDS_PN = "1";
"B":   PN = "2"  !CDS_PN = "2";
BODY = "Q_RES","I90": LOCATION = "R819" #&CDS_LOCATION = "R819" &SEC = "1" #&CDS_SEC = "1";
"A":   PN = "1"  !CDS_PN = "1";
"B":   PN = "2"  !CDS_PN = "2";
DRAWING = "@s9s_mb_2u_lib.s9s_mb_2u(sch_1):page133";
BODY = "Q_RES","I5": LOCATION = "R775" #&CDS_LOCATION = "R775" &SEC = "1" #&CDS_SEC = "1";
"A":   PN = "1"  !CDS_PN = "1";
"B":   PN = "2"  !CDS_PN = "2";
BODY = "Q_RES","I7": LOCATION = "R776" #&CDS_LOCATION = "R776" &SEC = "1" #&CDS_SEC = "1";
"A":   PN = "1"  !CDS_PN = "1";
"B":   PN = "2"  !CDS_PN = "2";
BODY = "Q_RES","I10": LOCATION = "R777" #&CDS_LOCATION = "R777" &SEC = "1" #&CDS_SEC = "1";
"A":   PN = "1"  !CDS_PN = "1";
"B":   PN = "2"  !CDS_PN = "2";
BODY = "Q_RES","I15": LOCATION = "R778" #&CDS_LOCATION = "R778" &SEC = "1" #&CDS_SEC = "1";
"A":   PN = "1"  !CDS_PN = "1";
"B":   PN = "2"  !CDS_PN = "2";
BODY = "SCONN60_ASP21410801","I44": LOCATION = "J42" #&CDS_LOCATION = "J42" &SEC = "1" #&CDS_SEC = "1";
"1":   PN = "1"  !CDS_PN = "1";
"2":   PN = "2"  !CDS_PN = "2";
"3":   PN = "3"  !CDS_PN = "3";
"4":   PN = "4"  !CDS_PN = "4";
"5":   PN = "5"  !CDS_PN = "5";
"6":   PN = "6"  !CDS_PN = "6";
"7":   PN = "7"  !CDS_PN = "7";
"8":   PN = "8"  !CDS_PN = "8";
"9":   PN = "9"  !CDS_PN = "9";
"10":   PN = "10"  !CDS_PN = "10";
"11":   PN = "11"  !CDS_PN = "11";
"12":   PN = "12"  !CDS_PN = "12";
"13":   PN = "13"  !CDS_PN = "13";
"14":   PN = "14"  !CDS_PN = "14";
"15":   PN = "15"  !CDS_PN = "15";
"16":   PN = "16"  !CDS_PN = "16";
"17":   PN = "17"  !CDS_PN = "17";
"18":   PN = "18"  !CDS_PN = "18";
"19":   PN = "19"  !CDS_PN = "19";
"20":   PN = "20"  !CDS_PN = "20";
"21":   PN = "21"  !CDS_PN = "21";
"22":   PN = "22"  !CDS_PN = "22";
"23":   PN = "23"  !CDS_PN = "23";
"24":   PN = "24"  !CDS_PN = "24";
"25":   PN = "25"  !CDS_PN = "25";
"26":   PN = "26"  !CDS_PN = "26";
"27":   PN = "27"  !CDS_PN = "27";
"28":   PN = "28"  !CDS_PN = "28";
"29":   PN = "29"  !CDS_PN = "29";
"30":   PN = "30"  !CDS_PN = "30";
"31":   PN = "31"  !CDS_PN = "31";
"32":   PN = "32"  !CDS_PN = "32";
"33":   PN = "33"  !CDS_PN = "33";
"34":   PN = "34"  !CDS_PN = "34";
"35":   PN = "35"  !CDS_PN = "35";
"36":   PN = "36"  !CDS_PN = "36";
"37":   PN = "37"  !CDS_PN = "37";
"38":   PN = "38"  !CDS_PN = "38";
"39":   PN = "39"  !CDS_PN = "39";
"40":   PN = "40"  !CDS_PN = "40";
"41":   PN = "41"  !CDS_PN = "41";
"42":   PN = "42"  !CDS_PN = "42";
"43":   PN = "43"  !CDS_PN = "43";
"44":   PN = "44"  !CDS_PN = "44";
"45":   PN = "45"  !CDS_PN = "45";
"46":   PN = "46"  !CDS_PN = "46";
"47":   PN = "47"  !CDS_PN = "47";
"48":   PN = "48"  !CDS_PN = "48";
"49":   PN = "49"  !CDS_PN = "49";
"50":   PN = "50"  !CDS_PN = "50";
"51":   PN = "51"  !CDS_PN = "51";
"52":   PN = "52"  !CDS_PN = "52";
"53":   PN = "53"  !CDS_PN = "53";
"54":   PN = "54"  !CDS_PN = "54";
"55":   PN = "55"  !CDS_PN = "55";
"56":   PN = "56"  !CDS_PN = "56";
"57":   PN = "57"  !CDS_PN = "57";
"58":   PN = "58"  !CDS_PN = "58";
"59":   PN = "59"  !CDS_PN = "59";
"60":   PN = "60"  !CDS_PN = "60";
"G1":   PN = "G1"  !CDS_PN = "G1";
"G2":   PN = "G2"  !CDS_PN = "G2";
"G3":   PN = "G3"  !CDS_PN = "G3";
"G4":   PN = "G4"  !CDS_PN = "G4";
BODY = "Q_RES","I70": LOCATION = "R763" #&CDS_LOCATION = "R763" &SEC = "1" #&CDS_SEC = "1";
"A":   PN = "1"  !CDS_PN = "1";
"B":   PN = "2"  !CDS_PN = "2";
BODY = "Q_RES","I71": LOCATION = "R762" #&CDS_LOCATION = "R762" &SEC = "1" #&CDS_SEC = "1";
"A":   PN = "1"  !CDS_PN = "1";
"B":   PN = "2"  !CDS_PN = "2";
BODY = "Q_RES","I74": LOCATION = "R765" #&CDS_LOCATION = "R765" &SEC = "1" #&CDS_SEC = "1";
"A":   PN = "1"  !CDS_PN = "1";
"B":   PN = "2"  !CDS_PN = "2";
BODY = "Q_RES","I83": LOCATION = "R764" #&CDS_LOCATION = "R764" &SEC = "1" #&CDS_SEC = "1";
"A":   PN = "1"  !CDS_PN = "1";
"B":   PN = "2"  !CDS_PN = "2";
BODY = "Q_RES","I92": LOCATION = "R780" #&CDS_LOCATION = "R780" &SEC = "1" #&CDS_SEC = "1";
"A":   PN = "1"  !CDS_PN = "1";
"B":   PN = "2"  !CDS_PN = "2";
BODY = "Q_RES","I95": LOCATION = "R779" #&CDS_LOCATION = "R779" &SEC = "1" #&CDS_SEC = "1";
"A":   PN = "1"  !CDS_PN = "1";
"B":   PN = "2"  !CDS_PN = "2";
BODY = "Q_CAP","I96": LOCATION = "C552" #&CDS_LOCATION = "C552" &SEC = "1" #&CDS_SEC = "1";
"A":   PN = "1"  !CDS_PN = "1";
"B":   PN = "2"  !CDS_PN = "2";
BODY = "Q_CAP","I99": LOCATION = "C550" #&CDS_LOCATION = "C550" &SEC = "1" #&CDS_SEC = "1";
"A":   PN = "1"  !CDS_PN = "1";
"B":   PN = "2"  !CDS_PN = "2";
BODY = "Q_CAP","I100": LOCATION = "C547" #&CDS_LOCATION = "C547" &SEC = "1" #&CDS_SEC = "1";
"A":   PN = "1"  !CDS_PN = "1";
"B":   PN = "2"  !CDS_PN = "2";
BODY = "Q_RES","I102": LOCATION = "R769" #&CDS_LOCATION = "R769" &SEC = "1" #&CDS_SEC = "1";
"A":   PN = "1"  !CDS_PN = "1";
"B":   PN = "2"  !CDS_PN = "2";
BODY = "Q_CAP","I105": LOCATION = "C551" #&CDS_LOCATION = "C551" &SEC = "1" #&CDS_SEC = "1";
"A":   PN = "1"  !CDS_PN = "1";
"B":   PN = "2"  !CDS_PN = "2";
BODY = "Q_RES","I111": LOCATION = "R766" #&CDS_LOCATION = "R766" &SEC = "1" #&CDS_SEC = "1";
"A":   PN = "1"  !CDS_PN = "1";
"B":   PN = "2"  !CDS_PN = "2";
BODY = "Q_RES","I112": LOCATION = "R768" #&CDS_LOCATION = "R768" &SEC = "1" #&CDS_SEC = "1";
"A":   PN = "1"  !CDS_PN = "1";
"B":   PN = "2"  !CDS_PN = "2";
BODY = "Q_RES","I113": LOCATION = "R767" #&CDS_LOCATION = "R767" &SEC = "1" #&CDS_SEC = "1";
"A":   PN = "1"  !CDS_PN = "1";
"B":   PN = "2"  !CDS_PN = "2";
BODY = "Q_RES","I118": LOCATION = "R772" #&CDS_LOCATION = "R772" &SEC = "1" #&CDS_SEC = "1";
"A":   PN = "1"  !CDS_PN = "1";
"B":   PN = "2"  !CDS_PN = "2";
BODY = "Q_RES","I120": LOCATION = "R771" #&CDS_LOCATION = "R771" &SEC = "1" #&CDS_SEC = "1";
"A":   PN = "1"  !CDS_PN = "1";
"B":   PN = "2"  !CDS_PN = "2";
BODY = "Q_RES","I124": LOCATION = "R773" #&CDS_LOCATION = "R773" &SEC = "1" #&CDS_SEC = "1";
"A":   PN = "1"  !CDS_PN = "1";
"B":   PN = "2"  !CDS_PN = "2";
BODY = "Q_CAP","I129": LOCATION = "C549" #&CDS_LOCATION = "C549" &SEC = "1" #&CDS_SEC = "1";
"A":   PN = "1"  !CDS_PN = "1";
"B":   PN = "2"  !CDS_PN = "2";
BODY = "Q_CAP","I130": LOCATION = "C548" #&CDS_LOCATION = "C548" &SEC = "1" #&CDS_SEC = "1";
"A":   PN = "1"  !CDS_PN = "1";
"B":   PN = "2"  !CDS_PN = "2";
BODY = "Q_RES","I132": LOCATION = "R774" #&CDS_LOCATION = "R774" &SEC = "1" #&CDS_SEC = "1";
"A":   PN = "1"  !CDS_PN = "1";
"B":   PN = "2"  !CDS_PN = "2";
BODY = "Q_RES","I144": LOCATION = "R1472" #&CDS_LOCATION = "R1472" &SEC = "1" #&CDS_SEC = "1";
"A":   PN = "1"  !CDS_PN = "1";
"B":   PN = "2"  !CDS_PN = "2";
BODY = "Q_RES","I148": LOCATION = "R4502" #&CDS_LOCATION = "R4502" &SEC = "1" #&CDS_SEC = "1";
"A":   PN = "1"  !CDS_PN = "1";
"B":   PN = "2"  !CDS_PN = "2";
BODY = "Q_RES","I153": LOCATION = "R4503" #&CDS_LOCATION = "R4503" &SEC = "1" #&CDS_SEC = "1";
"A":   PN = "1"  !CDS_PN = "1";
"B":   PN = "2"  !CDS_PN = "2";
DRAWING = "@s9s_mb_2u_lib.s9s_mb_2u(sch_1):page134";
BODY = "74CBTLV3126PW","I80": LOCATION = "U17" #&CDS_LOCATION = "U17" #SEC = "1" !CDS_SEC = "1";
"1A":   PN = "2"  !CDS_PN = "2";
"1B":   PN = "3"  !CDS_PN = "3";
"1OE":   PN = "1"  !CDS_PN = "1";
"2A":   PN = "5"  !CDS_PN = "5";
"2B":   PN = "6"  !CDS_PN = "6";
"2OE":   PN = "4"  !CDS_PN = "4";
"3A":   PN = "9"  !CDS_PN = "9";
"3B":   PN = "8"  !CDS_PN = "8";
"3OE":   PN = "10"  !CDS_PN = "10";
"4A":   PN = "12"  !CDS_PN = "12";
"4B":   PN = "11"  !CDS_PN = "11";
"4OE":   PN = "13"  !CDS_PN = "13";
"GND":   PN = "7"  !CDS_PN = "7";
"VCC":   PN = "14"  !CDS_PN = "14";
BODY = "Q_RES","I90": LOCATION = "R746" #&CDS_LOCATION = "R746" &SEC = "1" #&CDS_SEC = "1";
"A":   PN = "1"  !CDS_PN = "1";
"B":   PN = "2"  !CDS_PN = "2";
BODY = "Q_CAP","I93": LOCATION = "C545" #&CDS_LOCATION = "C545" &SEC = "1" #&CDS_SEC = "1";
"A":   PN = "1"  !CDS_PN = "1";
"B":   PN = "2"  !CDS_PN = "2";
BODY = "Q_RES","I126": LOCATION = "R754" #&CDS_LOCATION = "R754" &SEC = "1" #&CDS_SEC = "1";
"A":   PN = "1"  !CDS_PN = "1";
"B":   PN = "2"  !CDS_PN = "2";
BODY = "Q_RES","I127": LOCATION = "R752" #&CDS_LOCATION = "R752" &SEC = "1" #&CDS_SEC = "1";
"A":   PN = "1"  !CDS_PN = "1";
"B":   PN = "2"  !CDS_PN = "2";
BODY = "Q_RES","I128": LOCATION = "R753" #&CDS_LOCATION = "R753" &SEC = "1" #&CDS_SEC = "1";
"A":   PN = "1"  !CDS_PN = "1";
"B":   PN = "2"  !CDS_PN = "2";
BODY = "74CBTLV3126PW","I129": LOCATION = "U18" #&CDS_LOCATION = "U18" #SEC = "1" !CDS_SEC = "1";
"1A":   PN = "2"  !CDS_PN = "2";
"1B":   PN = "3"  !CDS_PN = "3";
"1OE":   PN = "1"  !CDS_PN = "1";
"2A":   PN = "5"  !CDS_PN = "5";
"2B":   PN = "6"  !CDS_PN = "6";
"2OE":   PN = "4"  !CDS_PN = "4";
"3A":   PN = "9"  !CDS_PN = "9";
"3B":   PN = "8"  !CDS_PN = "8";
"3OE":   PN = "10"  !CDS_PN = "10";
"4A":   PN = "12"  !CDS_PN = "12";
"4B":   PN = "11"  !CDS_PN = "11";
"4OE":   PN = "13"  !CDS_PN = "13";
"GND":   PN = "7"  !CDS_PN = "7";
"VCC":   PN = "14"  !CDS_PN = "14";
BODY = "Q_CAP","I135": LOCATION = "C546" #&CDS_LOCATION = "C546" &SEC = "1" #&CDS_SEC = "1";
"A":   PN = "1"  !CDS_PN = "1";
"B":   PN = "2"  !CDS_PN = "2";
BODY = "Q_RES","I147": LOCATION = "R755" #&CDS_LOCATION = "R755" &SEC = "1" #&CDS_SEC = "1";
"A":   PN = "1"  !CDS_PN = "1";
"B":   PN = "2"  !CDS_PN = "2";
BODY = "Q_RES","I148": LOCATION = "R756" #&CDS_LOCATION = "R756" &SEC = "1" #&CDS_SEC = "1";
"A":   PN = "1"  !CDS_PN = "1";
"B":   PN = "2"  !CDS_PN = "2";
BODY = "Q_RES","I166": LOCATION = "R757" #&CDS_LOCATION = "R757" &SEC = "1" #&CDS_SEC = "1";
"A":   PN = "1"  !CDS_PN = "1";
"B":   PN = "2"  !CDS_PN = "2";
BODY = "Q_RES","I168": LOCATION = "R758" #&CDS_LOCATION = "R758" &SEC = "1" #&CDS_SEC = "1";
"A":   PN = "1"  !CDS_PN = "1";
"B":   PN = "2"  !CDS_PN = "2";
BODY = "Q_RES","I169": LOCATION = "R759" #&CDS_LOCATION = "R759" &SEC = "1" #&CDS_SEC = "1";
"A":   PN = "1"  !CDS_PN = "1";
"B":   PN = "2"  !CDS_PN = "2";
BODY = "Q_RES","I174": LOCATION = "R760" #&CDS_LOCATION = "R760" &SEC = "1" #&CDS_SEC = "1";
"A":   PN = "1"  !CDS_PN = "1";
"B":   PN = "2"  !CDS_PN = "2";
BODY = "Q_RES","I175": LOCATION = "R761" #&CDS_LOCATION = "R761" &SEC = "1" #&CDS_SEC = "1";
"A":   PN = "1"  !CDS_PN = "1";
"B":   PN = "2"  !CDS_PN = "2";
BODY = "Q_RES","I176": LOCATION = "R747" #&CDS_LOCATION = "R747" &SEC = "1" #&CDS_SEC = "1";
"A":   PN = "1"  !CDS_PN = "1";
"B":   PN = "2"  !CDS_PN = "2";
BODY = "Q_RES","I177": LOCATION = "R751" #&CDS_LOCATION = "R751" &SEC = "1" #&CDS_SEC = "1";
"A":   PN = "1"  !CDS_PN = "1";
"B":   PN = "2"  !CDS_PN = "2";
BODY = "Q_RES","I178": LOCATION = "R750" #&CDS_LOCATION = "R750" &SEC = "1" #&CDS_SEC = "1";
"A":   PN = "1"  !CDS_PN = "1";
"B":   PN = "2"  !CDS_PN = "2";
BODY = "Q_RES","I179": LOCATION = "R749" #&CDS_LOCATION = "R749" &SEC = "1" #&CDS_SEC = "1";
"A":   PN = "1"  !CDS_PN = "1";
"B":   PN = "2"  !CDS_PN = "2";
BODY = "Q_RES","I180": LOCATION = "R748" #&CDS_LOCATION = "R748" &SEC = "1" #&CDS_SEC = "1";
"A":   PN = "1"  !CDS_PN = "1";
"B":   PN = "2"  !CDS_PN = "2";
DRAWING = "@s9s_mb_2u_lib.s9s_mb_2u(sch_1):page135";
BODY = "NC7SB3157","I58": LOCATION = "U21" #&CDS_LOCATION = "U21" &SEC = "1" #&CDS_SEC = "1";
"A":   PN = "4"  !CDS_PN = "4";
"B0":   PN = "3"  !CDS_PN = "3";
"B1":   PN = "1"  !CDS_PN = "1";
"GND":   PN = "2"  !CDS_PN = "2";
"S":   PN = "6"  !CDS_PN = "6";
"VCC":   PN = "5"  !CDS_PN = "5";
BODY = "Q_CAP","I61": LOCATION = "C541" #&CDS_LOCATION = "C541" &SEC = "1" #&CDS_SEC = "1";
"A":   PN = "1"  !CDS_PN = "1";
"B":   PN = "2"  !CDS_PN = "2";
BODY = "Q_RES","I65": LOCATION = "R743" #&CDS_LOCATION = "R743" &SEC = "1" #&CDS_SEC = "1";
"A":   PN = "1"  !CDS_PN = "1";
"B":   PN = "2"  !CDS_PN = "2";
BODY = "Q_RES","I66": LOCATION = "R741" #&CDS_LOCATION = "R741" &SEC = "1" #&CDS_SEC = "1";
"A":   PN = "1"  !CDS_PN = "1";
"B":   PN = "2"  !CDS_PN = "2";
BODY = "Q_CAP","I70": LOCATION = "C539" #&CDS_LOCATION = "C539" &SEC = "1" #&CDS_SEC = "1";
"A":   PN = "1"  !CDS_PN = "1";
"B":   PN = "2"  !CDS_PN = "2";
BODY = "NC7SB3157","I71": LOCATION = "U22" #&CDS_LOCATION = "U22" &SEC = "1" #&CDS_SEC = "1";
"A":   PN = "4"  !CDS_PN = "4";
"B0":   PN = "3"  !CDS_PN = "3";
"B1":   PN = "1"  !CDS_PN = "1";
"GND":   PN = "2"  !CDS_PN = "2";
"S":   PN = "6"  !CDS_PN = "6";
"VCC":   PN = "5"  !CDS_PN = "5";
BODY = "Q_RES","I77": LOCATION = "R744" #&CDS_LOCATION = "R744" &SEC = "1" #&CDS_SEC = "1";
"A":   PN = "1"  !CDS_PN = "1";
"B":   PN = "2"  !CDS_PN = "2";
BODY = "Q_RES","I78": LOCATION = "R742" #&CDS_LOCATION = "R742" &SEC = "1" #&CDS_SEC = "1";
"A":   PN = "1"  !CDS_PN = "1";
"B":   PN = "2"  !CDS_PN = "2";
BODY = "Q_CAP","I80": LOCATION = "C542" #&CDS_LOCATION = "C542" &SEC = "1" #&CDS_SEC = "1";
"A":   PN = "1"  !CDS_PN = "1";
"B":   PN = "2"  !CDS_PN = "2";
BODY = "Q_CAP","I81": LOCATION = "C540" #&CDS_LOCATION = "C540" &SEC = "1" #&CDS_SEC = "1";
"A":   PN = "1"  !CDS_PN = "1";
"B":   PN = "2"  !CDS_PN = "2";
BODY = "Q_CAP","I94": LOCATION = "C544" #&CDS_LOCATION = "C544" &SEC = "1" #&CDS_SEC = "1";
"A":   PN = "1"  !CDS_PN = "1";
"B":   PN = "2"  !CDS_PN = "2";
BODY = "74LVC1G02GW","I96": LOCATION = "U23" #&CDS_LOCATION = "U23" &SEC = "1" #&CDS_SEC = "1";
"A":   PN = "2"  !CDS_PN = "2";
"B":   PN = "1"  !CDS_PN = "1";
"GND":   PN = "3"  !CDS_PN = "3";
"VCC":   PN = "5"  !CDS_PN = "5";
"Y":   PN = "4"  !CDS_PN = "4";
BODY = "Q_RES","I97": LOCATION = "R745" #&CDS_LOCATION = "R745" &SEC = "1" #&CDS_SEC = "1";
"A":   PN = "1"  !CDS_PN = "1";
"B":   PN = "2"  !CDS_PN = "2";
BODY = "Q_CAP","I100": LOCATION = "C543" #&CDS_LOCATION = "C543" &SEC = "1" #&CDS_SEC = "1";
"A":   PN = "1"  !CDS_PN = "1";
"B":   PN = "2"  !CDS_PN = "2";
BODY = "Q_RES","I106": LOCATION = "R737" #&CDS_LOCATION = "R737" &SEC = "1" #&CDS_SEC = "1";
"A":   PN = "1"  !CDS_PN = "1";
"B":   PN = "2"  !CDS_PN = "2";
BODY = "Q_RES","I107": LOCATION = "R740" #&CDS_LOCATION = "R740" &SEC = "1" #&CDS_SEC = "1";
"A":   PN = "1"  !CDS_PN = "1";
"B":   PN = "2"  !CDS_PN = "2";
BODY = "Q_RES","I109": LOCATION = "R739" #&CDS_LOCATION = "R739" &SEC = "1" #&CDS_SEC = "1";
"A":   PN = "1"  !CDS_PN = "1";
"B":   PN = "2"  !CDS_PN = "2";
BODY = "Q_RES","I110": LOCATION = "R738" #&CDS_LOCATION = "R738" &SEC = "1" #&CDS_SEC = "1";
"A":   PN = "1"  !CDS_PN = "1";
"B":   PN = "2"  !CDS_PN = "2";
BODY = "74LVC1G66GV","I115": #LOCATION = "U16" !CDS_LOCATION = "U16" #SEC = "1" !CDS_SEC = "1";
"E":   PN = "4"  !CDS_PN = "4";
"GND":   PN = "3"  !CDS_PN = "3";
"VCC":   PN = "5"  !CDS_PN = "5";
"Y":   PN = "1"  !CDS_PN = "1";
"Z":   PN = "2"  !CDS_PN = "2";
DRAWING = "@s9s_mb_2u_lib.s9s_mb_2u(sch_1):page137";
BODY = "74CBTLV3126PW","I84": LOCATION = "U86" #&CDS_LOCATION = "U86" &SEC = "1" #&CDS_SEC = "1";
"1A":   PN = "2"  !CDS_PN = "2";
"1B":   PN = "3"  !CDS_PN = "3";
"1OE":   PN = "1"  !CDS_PN = "1";
"2A":   PN = "5"  !CDS_PN = "5";
"2B":   PN = "6"  !CDS_PN = "6";
"2OE":   PN = "4"  !CDS_PN = "4";
"3A":   PN = "9"  !CDS_PN = "9";
"3B":   PN = "8"  !CDS_PN = "8";
"3OE":   PN = "10"  !CDS_PN = "10";
"4A":   PN = "12"  !CDS_PN = "12";
"4B":   PN = "11"  !CDS_PN = "11";
"4OE":   PN = "13"  !CDS_PN = "13";
"GND":   PN = "7"  !CDS_PN = "7";
"VCC":   PN = "14"  !CDS_PN = "14";
BODY = "Q_RES","I87": LOCATION = "R1349" #&CDS_LOCATION = "R1349" &SEC = "1" #&CDS_SEC = "1";
"A":   PN = "1"  !CDS_PN = "1";
"B":   PN = "2"  !CDS_PN = "2";
BODY = "Q_RES","I88": LOCATION = "R1348" #&CDS_LOCATION = "R1348" &SEC = "1" #&CDS_SEC = "1";
"A":   PN = "1"  !CDS_PN = "1";
"B":   PN = "2"  !CDS_PN = "2";
BODY = "Q_CAP","I90": LOCATION = "C1292" #&CDS_LOCATION = "C1292" &SEC = "1" #&CDS_SEC = "1";
"A":   PN = "1"  !CDS_PN = "1";
"B":   PN = "2"  !CDS_PN = "2";
BODY = "Q_CAP","I95": LOCATION = "C1293" #&CDS_LOCATION = "C1293" &SEC = "1" #&CDS_SEC = "1";
"A":   PN = "1"  !CDS_PN = "1";
"B":   PN = "2"  !CDS_PN = "2";
BODY = "MOSFET_N","I96": LOCATION = "U87" #&CDS_LOCATION = "U87" &SEC = "1" #&CDS_SEC = "1";
"DRAIN":   PN = "D"  !CDS_PN = "D";
"GATE":   PN = "G"  !CDS_PN = "G";
"SOURCE":   PN = "S"  !CDS_PN = "S";
BODY = "Q_RES","I97": LOCATION = "R1375" #&CDS_LOCATION = "R1375" &SEC = "1" #&CDS_SEC = "1";
"A":   PN = "1"  !CDS_PN = "1";
"B":   PN = "2"  !CDS_PN = "2";
BODY = "Q_RES","I98": LOCATION = "R1370" #&CDS_LOCATION = "R1370" &SEC = "1" #&CDS_SEC = "1";
"A":   PN = "1"  !CDS_PN = "1";
"B":   PN = "2"  !CDS_PN = "2";
BODY = "Q_RES","I102": LOCATION = "R3025" #&CDS_LOCATION = "R3025" &SEC = "1" #&CDS_SEC = "1";
"A":   PN = "1"  !CDS_PN = "1";
"B":   PN = "2"  !CDS_PN = "2";
BODY = "Q_RES","I103": LOCATION = "R1374" #&CDS_LOCATION = "R1374" &SEC = "1" #&CDS_SEC = "1";
"A":   PN = "1"  !CDS_PN = "1";
"B":   PN = "2"  !CDS_PN = "2";
BODY = "Q_RES","I105": LOCATION = "R3027" #&CDS_LOCATION = "R3027" &SEC = "1" #&CDS_SEC = "1";
"A":   PN = "1"  !CDS_PN = "1";
"B":   PN = "2"  !CDS_PN = "2";
BODY = "Q_RES","I106": LOCATION = "R3026" #&CDS_LOCATION = "R3026" &SEC = "1" #&CDS_SEC = "1";
"A":   PN = "1"  !CDS_PN = "1";
"B":   PN = "2"  !CDS_PN = "2";
BODY = "NC7SB3157","I109": LOCATION = "U85" #&CDS_LOCATION = "U85" &SEC = "1" #&CDS_SEC = "1";
"A":   PN = "4"  !CDS_PN = "4";
"B0":   PN = "3"  !CDS_PN = "3";
"B1":   PN = "1"  !CDS_PN = "1";
"GND":   PN = "2"  !CDS_PN = "2";
"S":   PN = "6"  !CDS_PN = "6";
"VCC":   PN = "5"  !CDS_PN = "5";
BODY = "Q_CAP","I110": LOCATION = "C1289" #&CDS_LOCATION = "C1289" &SEC = "1" #&CDS_SEC = "1";
"A":   PN = "1"  !CDS_PN = "1";
"B":   PN = "2"  !CDS_PN = "2";
BODY = "Q_CAP","I112": LOCATION = "C1288" #&CDS_LOCATION = "C1288" &SEC = "1" #&CDS_SEC = "1";
"A":   PN = "1"  !CDS_PN = "1";
"B":   PN = "2"  !CDS_PN = "2";
BODY = "Q_RES","I116": LOCATION = "R1365" #&CDS_LOCATION = "R1365" &SEC = "1" #&CDS_SEC = "1";
"A":   PN = "1"  !CDS_PN = "1";
"B":   PN = "2"  !CDS_PN = "2";
DRAWING = "@s9s_mb_2u_lib.s9s_mb_2u(sch_1):page151";
BODY = "Q_RES","I56": LOCATION = "R1353" #&CDS_LOCATION = "R1353" &SEC = "1" #&CDS_SEC = "1";
"A":   PN = "1"  !CDS_PN = "1";
"B":   PN = "2"  !CDS_PN = "2";
BODY = "Q_RES","I3": LOCATION = "R3231" #&CDS_LOCATION = "R3231" &SEC = "1" #&CDS_SEC = "1";
"A":   PN = "1"  !CDS_PN = "1";
"B":   PN = "2"  !CDS_PN = "2";
BODY = "Q_RES","I5": LOCATION = "R1719" #&CDS_LOCATION = "R1719" &SEC = "1" #&CDS_SEC = "1";
"A":   PN = "1"  !CDS_PN = "1";
"B":   PN = "2"  !CDS_PN = "2";
BODY = "74LVC1G126SE7","I7": #LOCATION = "U224" !CDS_LOCATION = "U224" &SEC = "1" #&CDS_SEC = "1";
"A":   PN = "2"  !CDS_PN = "2";
"GND":   PN = "3"  !CDS_PN = "3";
"OE":   PN = "1"  !CDS_PN = "1";
"VCC":   PN = "5"  !CDS_PN = "5";
"Y":   PN = "4"  !CDS_PN = "4";
BODY = "Q_CAP","I8": LOCATION = "C1840" #&CDS_LOCATION = "C1840" &SEC = "1" #&CDS_SEC = "1";
"A":   PN = "1"  !CDS_PN = "1";
"B":   PN = "2"  !CDS_PN = "2";
BODY = "Q_RES","I13": LOCATION = "R3232" #&CDS_LOCATION = "R3232" &SEC = "1" #&CDS_SEC = "1";
"A":   PN = "1"  !CDS_PN = "1";
"B":   PN = "2"  !CDS_PN = "2";
BODY = "74LVC1G126SE7","I15": #LOCATION = "U66" !CDS_LOCATION = "U66" #SEC = "1" !CDS_SEC = "1";
"A":   PN = "2"  !CDS_PN = "2";
"GND":   PN = "3"  !CDS_PN = "3";
"OE":   PN = "1"  !CDS_PN = "1";
"VCC":   PN = "5"  !CDS_PN = "5";
"Y":   PN = "4"  !CDS_PN = "4";
BODY = "Q_RES","I17": LOCATION = "R3233" #&CDS_LOCATION = "R3233" &SEC = "1" #&CDS_SEC = "1";
"A":   PN = "1"  !CDS_PN = "1";
"B":   PN = "2"  !CDS_PN = "2";
BODY = "Q_RES","I19": LOCATION = "R2474" #&CDS_LOCATION = "R2474" &SEC = "1" #&CDS_SEC = "1";
"A":   PN = "1"  !CDS_PN = "1";
"B":   PN = "2"  !CDS_PN = "2";
BODY = "Q_RES","I21": LOCATION = "R1289" #&CDS_LOCATION = "R1289" &SEC = "1" #&CDS_SEC = "1";
"A":   PN = "1"  !CDS_PN = "1";
"B":   PN = "2"  !CDS_PN = "2";
BODY = "Q_CAP","I22": LOCATION = "C639" #&CDS_LOCATION = "C639" &SEC = "1" #&CDS_SEC = "1";
"A":   PN = "1"  !CDS_PN = "1";
"B":   PN = "2"  !CDS_PN = "2";
BODY = "74CBTLV3126PW","I30": LOCATION = "U68" #&CDS_LOCATION = "U68" &SEC = "1" #&CDS_SEC = "1";
"1A":   PN = "2"  !CDS_PN = "2";
"1B":   PN = "3"  !CDS_PN = "3";
"1OE":   PN = "1"  !CDS_PN = "1";
"2A":   PN = "5"  !CDS_PN = "5";
"2B":   PN = "6"  !CDS_PN = "6";
"2OE":   PN = "4"  !CDS_PN = "4";
"3A":   PN = "9"  !CDS_PN = "9";
"3B":   PN = "8"  !CDS_PN = "8";
"3OE":   PN = "10"  !CDS_PN = "10";
"4A":   PN = "12"  !CDS_PN = "12";
"4B":   PN = "11"  !CDS_PN = "11";
"4OE":   PN = "13"  !CDS_PN = "13";
"GND":   PN = "7"  !CDS_PN = "7";
"VCC":   PN = "14"  !CDS_PN = "14";
BODY = "Q_CAP","I32": LOCATION = "C641" #&CDS_LOCATION = "C641" &SEC = "1" #&CDS_SEC = "1";
"A":   PN = "1"  !CDS_PN = "1";
"B":   PN = "2"  !CDS_PN = "2";
BODY = "74CBTLV3126PW","I39": LOCATION = "U67" #&CDS_LOCATION = "U67" &SEC = "1" #&CDS_SEC = "1";
"1A":   PN = "2"  !CDS_PN = "2";
"1B":   PN = "3"  !CDS_PN = "3";
"1OE":   PN = "1"  !CDS_PN = "1";
"2A":   PN = "5"  !CDS_PN = "5";
"2B":   PN = "6"  !CDS_PN = "6";
"2OE":   PN = "4"  !CDS_PN = "4";
"3A":   PN = "9"  !CDS_PN = "9";
"3B":   PN = "8"  !CDS_PN = "8";
"3OE":   PN = "10"  !CDS_PN = "10";
"4A":   PN = "12"  !CDS_PN = "12";
"4B":   PN = "11"  !CDS_PN = "11";
"4OE":   PN = "13"  !CDS_PN = "13";
"GND":   PN = "7"  !CDS_PN = "7";
"VCC":   PN = "14"  !CDS_PN = "14";
BODY = "Q_CAP","I40": LOCATION = "C640" #&CDS_LOCATION = "C640" &SEC = "1" #&CDS_SEC = "1";
"A":   PN = "1"  !CDS_PN = "1";
"B":   PN = "2"  !CDS_PN = "2";
BODY = "Q_RES","I43": LOCATION = "R1896" #&CDS_LOCATION = "R1896" &SEC = "1" #&CDS_SEC = "1";
"A":   PN = "1"  !CDS_PN = "1";
"B":   PN = "2"  !CDS_PN = "2";
BODY = "Q_RES","I50": LOCATION = "R1897" #&CDS_LOCATION = "R1897" &SEC = "1" #&CDS_SEC = "1";
"A":   PN = "1"  !CDS_PN = "1";
"B":   PN = "2"  !CDS_PN = "2";
BODY = "Q_RES","I52": LOCATION = "R1898" #&CDS_LOCATION = "R1898" &SEC = "1" #&CDS_SEC = "1";
"A":   PN = "1"  !CDS_PN = "1";
"B":   PN = "2"  !CDS_PN = "2";
BODY = "Q_RES","I53": LOCATION = "R1356" #&CDS_LOCATION = "R1356" &SEC = "1" #&CDS_SEC = "1";
"A":   PN = "1"  !CDS_PN = "1";
"B":   PN = "2"  !CDS_PN = "2";
BODY = "Q_RES","I54": LOCATION = "R1355" #&CDS_LOCATION = "R1355" &SEC = "1" #&CDS_SEC = "1";
"A":   PN = "1"  !CDS_PN = "1";
"B":   PN = "2"  !CDS_PN = "2";
BODY = "Q_RES","I55": LOCATION = "R1354" #&CDS_LOCATION = "R1354" &SEC = "1" #&CDS_SEC = "1";
"A":   PN = "1"  !CDS_PN = "1";
"B":   PN = "2"  !CDS_PN = "2";
BODY = "Q_RES","I61": LOCATION = "R1296" #&CDS_LOCATION = "R1296" &SEC = "1" #&CDS_SEC = "1";
"A":   PN = "1"  !CDS_PN = "1";
"B":   PN = "2"  !CDS_PN = "2";
BODY = "Q_RES","I65": LOCATION = "R1295" #&CDS_LOCATION = "R1295" &SEC = "1" #&CDS_SEC = "1";
"A":   PN = "1"  !CDS_PN = "1";
"B":   PN = "2"  !CDS_PN = "2";
BODY = "Q_RES","I66": LOCATION = "R1294" #&CDS_LOCATION = "R1294" &SEC = "1" #&CDS_SEC = "1";
"A":   PN = "1"  !CDS_PN = "1";
"B":   PN = "2"  !CDS_PN = "2";
BODY = "Q_RES","I67": LOCATION = "R1293" #&CDS_LOCATION = "R1293" &SEC = "1" #&CDS_SEC = "1";
"A":   PN = "1"  !CDS_PN = "1";
"B":   PN = "2"  !CDS_PN = "2";
BODY = "Q_RES","I68": LOCATION = "R1292" #&CDS_LOCATION = "R1292" &SEC = "1" #&CDS_SEC = "1";
"A":   PN = "1"  !CDS_PN = "1";
"B":   PN = "2"  !CDS_PN = "2";
BODY = "Q_RES","I69": LOCATION = "R1291" #&CDS_LOCATION = "R1291" &SEC = "1" #&CDS_SEC = "1";
"A":   PN = "1"  !CDS_PN = "1";
"B":   PN = "2"  !CDS_PN = "2";
BODY = "Q_RES","I71": LOCATION = "R1352" #&CDS_LOCATION = "R1352" &SEC = "1" #&CDS_SEC = "1";
"A":   PN = "1"  !CDS_PN = "1";
"B":   PN = "2"  !CDS_PN = "2";
BODY = "Q_RES","I72": LOCATION = "R1351" #&CDS_LOCATION = "R1351" &SEC = "1" #&CDS_SEC = "1";
"A":   PN = "1"  !CDS_PN = "1";
"B":   PN = "2"  !CDS_PN = "2";
BODY = "Q_RES","I73": LOCATION = "R1350" #&CDS_LOCATION = "R1350" &SEC = "1" #&CDS_SEC = "1";
"A":   PN = "1"  !CDS_PN = "1";
"B":   PN = "2"  !CDS_PN = "2";
BODY = "Q_RES","I80": LOCATION = "R3237" #&CDS_LOCATION = "R3237" &SEC = "1" #&CDS_SEC = "1";
"A":   PN = "1"  !CDS_PN = "1";
"B":   PN = "2"  !CDS_PN = "2";
BODY = "Q_RES","I81": LOCATION = "R1290" #&CDS_LOCATION = "R1290" &SEC = "1" #&CDS_SEC = "1";
"A":   PN = "1"  !CDS_PN = "1";
"B":   PN = "2"  !CDS_PN = "2";
BODY = "Q_RES","I83": #LOCATION = "R2473" !CDS_LOCATION = "R2473" &SEC = "1" #&CDS_SEC = "1";
"A":   PN = "1"  !CDS_PN = "1";
"B":   PN = "2"  !CDS_PN = "2";
DRAWING = "@s9s_mb_2u_lib.s9s_mb_2u(sch_1):page152";
BODY = "74LVC1G17GW","I1": LOCATION = "U75" #&CDS_LOCATION = "U75" #SEC = "1" !CDS_SEC = "1";
"A":   PN = "2"  !CDS_PN = "2";
"GND":   PN = "3"  !CDS_PN = "3";
"NC":   PN = "1"  !CDS_PN = "1";
"VCC":   PN = "5"  !CDS_PN = "5";
"Y":   PN = "4"  !CDS_PN = "4";
BODY = "Q_CAP","I4": LOCATION = "C1173" #&CDS_LOCATION = "C1173" &SEC = "1" #&CDS_SEC = "1";
"A":   PN = "1"  !CDS_PN = "1";
"B":   PN = "2"  !CDS_PN = "2";
BODY = "Q_RES","I6": LOCATION = "R419" #&CDS_LOCATION = "R419" &SEC = "1" #&CDS_SEC = "1";
"A":   PN = "1"  !CDS_PN = "1";
"B":   PN = "2"  !CDS_PN = "2";
BODY = "Q_RES","I8": LOCATION = "R435" #&CDS_LOCATION = "R435" &SEC = "1" #&CDS_SEC = "1";
"A":   PN = "1"  !CDS_PN = "1";
"B":   PN = "2"  !CDS_PN = "2";
BODY = "Q_RES","I10": LOCATION = "R1504" #&CDS_LOCATION = "R1504" &SEC = "1" #&CDS_SEC = "1";
"A":   PN = "1"  !CDS_PN = "1";
"B":   PN = "2"  !CDS_PN = "2";
BODY = "Q_RES","I13": LOCATION = "R1505" #&CDS_LOCATION = "R1505" &SEC = "1" #&CDS_SEC = "1";
"A":   PN = "1"  !CDS_PN = "1";
"B":   PN = "2"  !CDS_PN = "2";
BODY = "Q_CAP","I24": LOCATION = "C1175" #&CDS_LOCATION = "C1175" &SEC = "1" #&CDS_SEC = "1";
"A":   PN = "1"  !CDS_PN = "1";
"B":   PN = "2"  !CDS_PN = "2";
BODY = "Q_RES","I26": LOCATION = "R1594" #&CDS_LOCATION = "R1594" &SEC = "1" #&CDS_SEC = "1";
"A":   PN = "1"  !CDS_PN = "1";
"B":   PN = "2"  !CDS_PN = "2";
BODY = "Q_RES","I37": LOCATION = "R1592" #&CDS_LOCATION = "R1592" &SEC = "1" #&CDS_SEC = "1";
"A":   PN = "1"  !CDS_PN = "1";
"B":   PN = "2"  !CDS_PN = "2";
BODY = "Q_RES","I40": LOCATION = "R1595" #&CDS_LOCATION = "R1595" &SEC = "1" #&CDS_SEC = "1";
"A":   PN = "1"  !CDS_PN = "1";
"B":   PN = "2"  !CDS_PN = "2";
BODY = "Q_RES","I42": LOCATION = "R1593" #&CDS_LOCATION = "R1593" &SEC = "1" #&CDS_SEC = "1";
"A":   PN = "1"  !CDS_PN = "1";
"B":   PN = "2"  !CDS_PN = "2";
BODY = "Q_CAP","I44": LOCATION = "C188" #&CDS_LOCATION = "C188" &SEC = "1" #&CDS_SEC = "1";
"A":   PN = "1"  !CDS_PN = "1";
"B":   PN = "2"  !CDS_PN = "2";
BODY = "PI6CV304LE","I46": LOCATION = "U90" #&CDS_LOCATION = "U90" &SEC = "1" #&CDS_SEC = "1";
"CLK_IN":   PN = "1"  !CDS_PN = "1";
"GND":   PN = "4"  !CDS_PN = "4";
"OE":   PN = "2"  !CDS_PN = "2";
"VDD":   PN = "6"  !CDS_PN = "6";
"Y0":   PN = "3"  !CDS_PN = "3";
"Y1":   PN = "5"  !CDS_PN = "5";
"Y2":   PN = "7"  !CDS_PN = "7";
"Y3":   PN = "8"  !CDS_PN = "8";
BODY = "Q_CAP","I49": LOCATION = "C1275" #&CDS_LOCATION = "C1275" &SEC = "1" #&CDS_SEC = "1";
"A":   PN = "1"  !CDS_PN = "1";
"B":   PN = "2"  !CDS_PN = "2";
BODY = "Q_RES","I52": LOCATION = "R1140" #&CDS_LOCATION = "R1140" &SEC = "1" #&CDS_SEC = "1";
"A":   PN = "1"  !CDS_PN = "1";
"B":   PN = "2"  !CDS_PN = "2";
BODY = "Q_RES","I53": LOCATION = "R1141" #&CDS_LOCATION = "R1141" &SEC = "1" #&CDS_SEC = "1";
"A":   PN = "1"  !CDS_PN = "1";
"B":   PN = "2"  !CDS_PN = "2";
BODY = "Q_RES","I56": LOCATION = "R1139" #&CDS_LOCATION = "R1139" &SEC = "1" #&CDS_SEC = "1";
"A":   PN = "1"  !CDS_PN = "1";
"B":   PN = "2"  !CDS_PN = "2";
BODY = "Q_CAP","I59": LOCATION = "C1274" #&CDS_LOCATION = "C1274" &SEC = "1" #&CDS_SEC = "1";
"A":   PN = "1"  !CDS_PN = "1";
"B":   PN = "2"  !CDS_PN = "2";
BODY = "Q_RES","I61": LOCATION = "R1138" #&CDS_LOCATION = "R1138" &SEC = "1" #&CDS_SEC = "1";
"A":   PN = "1"  !CDS_PN = "1";
"B":   PN = "2"  !CDS_PN = "2";
BODY = "Q_RES","I62": LOCATION = "R1824" #&CDS_LOCATION = "R1824" &SEC = "1" #&CDS_SEC = "1";
"A":   PN = "1"  !CDS_PN = "1";
"B":   PN = "2"  !CDS_PN = "2";
BODY = "74LVC1G07GV","I63": LOCATION = "U104" #&CDS_LOCATION = "U104" &SEC = "1" #&CDS_SEC = "1";
"A":   PN = "2"  !CDS_PN = "2";
"GND":   PN = "3"  !CDS_PN = "3";
"NC1":   PN = "1"  !CDS_PN = "1";
"VCC":   PN = "5"  !CDS_PN = "5";
"Y":   PN = "4"  !CDS_PN = "4";
BODY = "74LVC1G07GV","I65": LOCATION = "U157" #&CDS_LOCATION = "U157" &SEC = "1" #&CDS_SEC = "1";
"A":   PN = "2"  !CDS_PN = "2";
"GND":   PN = "3"  !CDS_PN = "3";
"NC1":   PN = "1"  !CDS_PN = "1";
"VCC":   PN = "5"  !CDS_PN = "5";
"Y":   PN = "4"  !CDS_PN = "4";
BODY = "Q_CAP","I68": LOCATION = "C1663" #&CDS_LOCATION = "C1663" &SEC = "1" #&CDS_SEC = "1";
"A":   PN = "1"  !CDS_PN = "1";
"B":   PN = "2"  !CDS_PN = "2";
BODY = "Q_RES","I71": LOCATION = "R2487" #&CDS_LOCATION = "R2487" &SEC = "1" #&CDS_SEC = "1";
"A":   PN = "1"  !CDS_PN = "1";
"B":   PN = "2"  !CDS_PN = "2";
BODY = "Q_RES","I74": LOCATION = "R2488" #&CDS_LOCATION = "R2488" &SEC = "1" #&CDS_SEC = "1";
"A":   PN = "1"  !CDS_PN = "1";
"B":   PN = "2"  !CDS_PN = "2";
BODY = "Q_RES","I75": LOCATION = "R2489" #&CDS_LOCATION = "R2489" &SEC = "1" #&CDS_SEC = "1";
"A":   PN = "1"  !CDS_PN = "1";
"B":   PN = "2"  !CDS_PN = "2";
BODY = "Q_OSC4P","I76": #LOCATION = "OSC1" !CDS_LOCATION = "OSC1" &SEC = "1" #&CDS_SEC = "1";
"GND":   PN = "2"  !CDS_PN = "2";
"OE":   PN = "1"  !CDS_PN = "1";
"OUT":   PN = "3"  !CDS_PN = "3";
"VDD":   PN = "4"  !CDS_PN = "4";
BODY = "Q_RES","I78": LOCATION = "R3181" #&CDS_LOCATION = "R3181" &SEC = "1" #&CDS_SEC = "1";
"A":   PN = "1"  !CDS_PN = "1";
"B":   PN = "2"  !CDS_PN = "2";
BODY = "74LVC1G126SE7","I79": #LOCATION = "U82" !CDS_LOCATION = "U82" &SEC = "1" #&CDS_SEC = "1";
"A":   PN = "2"  !CDS_PN = "2";
"GND":   PN = "3"  !CDS_PN = "3";
"OE":   PN = "1"  !CDS_PN = "1";
"VCC":   PN = "5"  !CDS_PN = "5";
"Y":   PN = "4"  !CDS_PN = "4";
BODY = "Q_CAP","I87": LOCATION = "C2344" #&CDS_LOCATION = "C2344" &SEC = "1" #&CDS_SEC = "1";
"A":   PN = "1"  !CDS_PN = "1";
"B":   PN = "2"  !CDS_PN = "2";
BODY = "Q_RES","I90": LOCATION = "R4601" #&CDS_LOCATION = "R4601" &SEC = "1" #&CDS_SEC = "1";
"A":   PN = "1"  !CDS_PN = "1";
"B":   PN = "2"  !CDS_PN = "2";
BODY = "74LVC1G66GV","I92": #LOCATION = "U320" !CDS_LOCATION = "U320" &SEC = "1" #&CDS_SEC = "1";
"E":   PN = "4"  !CDS_PN = "4";
"GND":   PN = "3"  !CDS_PN = "3";
"VCC":   PN = "5"  !CDS_PN = "5";
"Y":   PN = "1"  !CDS_PN = "1";
"Z":   PN = "2"  !CDS_PN = "2";
DRAWING = "@s9s_mb_2u_lib.s9s_mb_2u(sch_1):page154";
BODY = "Q_RES","I130": LOCATION = "R1130" #&CDS_LOCATION = "R1130" &SEC = "1" #&CDS_SEC = "1";
"A":   PN = "1"  !CDS_PN = "1";
"B":   PN = "2"  !CDS_PN = "2";
BODY = "Q_RES","I131": LOCATION = "R1131" #&CDS_LOCATION = "R1131" &SEC = "1" #&CDS_SEC = "1";
"A":   PN = "1"  !CDS_PN = "1";
"B":   PN = "2"  !CDS_PN = "2";
BODY = "Q_RES","I132": LOCATION = "R1921" #&CDS_LOCATION = "R1921" &SEC = "1" #&CDS_SEC = "1";
"A":   PN = "1"  !CDS_PN = "1";
"B":   PN = "2"  !CDS_PN = "2";
BODY = "Q_RES","I133": LOCATION = "R1127" #&CDS_LOCATION = "R1127" &SEC = "1" #&CDS_SEC = "1";
"A":   PN = "1"  !CDS_PN = "1";
"B":   PN = "2"  !CDS_PN = "2";
BODY = "Q_RES","I134": LOCATION = "R3037" #&CDS_LOCATION = "R3037" &SEC = "1" #&CDS_SEC = "1";
"A":   PN = "1"  !CDS_PN = "1";
"B":   PN = "2"  !CDS_PN = "2";
BODY = "Q_RES","I137": LOCATION = "R1128" #&CDS_LOCATION = "R1128" &SEC = "1" #&CDS_SEC = "1";
"A":   PN = "1"  !CDS_PN = "1";
"B":   PN = "2"  !CDS_PN = "2";
BODY = "Q_RES","I140": LOCATION = "R1126" #&CDS_LOCATION = "R1126" &SEC = "1" #&CDS_SEC = "1";
"A":   PN = "1"  !CDS_PN = "1";
"B":   PN = "2"  !CDS_PN = "2";
BODY = "Q_RES","I142": LOCATION = "R1123" #&CDS_LOCATION = "R1123" &SEC = "1" #&CDS_SEC = "1";
"A":   PN = "1"  !CDS_PN = "1";
"B":   PN = "2"  !CDS_PN = "2";
BODY = "Q_RES","I143": LOCATION = "R1124" #&CDS_LOCATION = "R1124" &SEC = "1" #&CDS_SEC = "1";
"A":   PN = "1"  !CDS_PN = "1";
"B":   PN = "2"  !CDS_PN = "2";
BODY = "Q_CAP","I148": LOCATION = "C581" #&CDS_LOCATION = "C581" &SEC = "1" #&CDS_SEC = "1";
"A":   PN = "1"  !CDS_PN = "1";
"B":   PN = "2"  !CDS_PN = "2";
BODY = "Q_CAP","I169": LOCATION = "C578" #&CDS_LOCATION = "C578" &SEC = "1" #&CDS_SEC = "1";
"A":   PN = "1"  !CDS_PN = "1";
"B":   PN = "2"  !CDS_PN = "2";
BODY = "Q_RES","I172": LOCATION = "R1129" #&CDS_LOCATION = "R1129" &SEC = "1" #&CDS_SEC = "1";
"A":   PN = "1"  !CDS_PN = "1";
"B":   PN = "2"  !CDS_PN = "2";
BODY = "MOSFET_N","I177": LOCATION = "U49" #&CDS_LOCATION = "U49" &SEC = "1" #&CDS_SEC = "1";
"DRAIN":   PN = "D"  !CDS_PN = "D";
"GATE":   PN = "G"  !CDS_PN = "G";
"SOURCE":   PN = "S"  !CDS_PN = "S";
BODY = "74LVC1G08W57","I189": LOCATION = "U210" #&CDS_LOCATION = "U210" &SEC = "1" #&CDS_SEC = "1";
"A":   PN = "1"  !CDS_PN = "1";
"B":   PN = "2"  !CDS_PN = "2";
"GND":   PN = "3"  !CDS_PN = "3";
"VCC":   PN = "5"  !CDS_PN = "5";
"Y":   PN = "4"  !CDS_PN = "4";
BODY = "74LVC1G08W57","I190": LOCATION = "U208" #&CDS_LOCATION = "U208" &SEC = "1" #&CDS_SEC = "1";
"A":   PN = "1"  !CDS_PN = "1";
"B":   PN = "2"  !CDS_PN = "2";
"GND":   PN = "3"  !CDS_PN = "3";
"VCC":   PN = "5"  !CDS_PN = "5";
"Y":   PN = "4"  !CDS_PN = "4";
BODY = "Q_CAP","I192": LOCATION = "C579" #&CDS_LOCATION = "C579" &SEC = "1" #&CDS_SEC = "1";
"A":   PN = "1"  !CDS_PN = "1";
"B":   PN = "2"  !CDS_PN = "2";
BODY = "PCA9555APW","I206": #LOCATION = "U209" !CDS_LOCATION = "U209" #SEC = "1" !CDS_SEC = "1";
"A0":   PN = "21"  !CDS_PN = "21";
"A1":   PN = "2"  !CDS_PN = "2";
"A2":   PN = "3"  !CDS_PN = "3";
"INT#":   PN = "1"  !CDS_PN = "1";
"P0_0":   PN = "4"  !CDS_PN = "4";
"P0_1":   PN = "5"  !CDS_PN = "5";
"P0_2":   PN = "6"  !CDS_PN = "6";
"P0_3":   PN = "7"  !CDS_PN = "7";
"P0_4":   PN = "8"  !CDS_PN = "8";
"P0_5":   PN = "9"  !CDS_PN = "9";
"P0_6":   PN = "10"  !CDS_PN = "10";
"P0_7":   PN = "11"  !CDS_PN = "11";
"P1_0":   PN = "13"  !CDS_PN = "13";
"P1_1":   PN = "14"  !CDS_PN = "14";
"P1_2":   PN = "15"  !CDS_PN = "15";
"P1_3":   PN = "16"  !CDS_PN = "16";
"P1_4":   PN = "17"  !CDS_PN = "17";
"P1_5":   PN = "18"  !CDS_PN = "18";
"P1_6":   PN = "19"  !CDS_PN = "19";
"P1_7":   PN = "20"  !CDS_PN = "20";
"SCL":   PN = "22"  !CDS_PN = "22";
"SDA":   PN = "23"  !CDS_PN = "23";
"VDD":   PN = "24"  !CDS_PN = "24";
"VSS":   PN = "12"  !CDS_PN = "12";
BODY = "74LVC1G08W57","I221": LOCATION = "U322" #&CDS_LOCATION = "U322" &SEC = "1" #&CDS_SEC = "1";
"A":   PN = "1"  !CDS_PN = "1";
"B":   PN = "2"  !CDS_PN = "2";
"GND":   PN = "3"  !CDS_PN = "3";
"VCC":   PN = "5"  !CDS_PN = "5";
"Y":   PN = "4"  !CDS_PN = "4";
BODY = "Q_CAP","I223": LOCATION = "C2346" #&CDS_LOCATION = "C2346" &SEC = "1" #&CDS_SEC = "1";
"A":   PN = "1"  !CDS_PN = "1";
"B":   PN = "2"  !CDS_PN = "2";
BODY = "APX80929SAG7","I228": #LOCATION = "U52" !CDS_LOCATION = "U52" &SEC = "1" #&CDS_SEC = "1";
"GND":   PN = "1"  !CDS_PN = "1";
"RESET_L":   PN = "2"  !CDS_PN = "2";
"VCC":   PN = "3"  !CDS_PN = "3";
BODY = "Q_CAP","I229": #LOCATION = "C580" !CDS_LOCATION = "C580" &SEC = "1" #&CDS_SEC = "1";
"A":   PN = "1"  !CDS_PN = "1";
"B":   PN = "2"  !CDS_PN = "2";
BODY = "Q_RES","I232": LOCATION = "R4613" #&CDS_LOCATION = "R4613" &SEC = "1" #&CDS_SEC = "1";
"A":   PN = "1"  !CDS_PN = "1";
"B":   PN = "2"  !CDS_PN = "2";
BODY = "Q_RES","I235": LOCATION = "R3160" #&CDS_LOCATION = "R3160" &SEC = "1" #&CDS_SEC = "1";
"A":   PN = "1"  !CDS_PN = "1";
"B":   PN = "2"  !CDS_PN = "2";
BODY = "Q_RES","I237": LOCATION = "R4618" #&CDS_LOCATION = "R4618" &SEC = "1" #&CDS_SEC = "1";
"A":   PN = "1"  !CDS_PN = "1";
"B":   PN = "2"  !CDS_PN = "2";
BODY = "Q_RES","I238": #LOCATION = "R4614" !CDS_LOCATION = "R4614" &SEC = "1" #&CDS_SEC = "1";
"A":   PN = "1"  !CDS_PN = "1";
"B":   PN = "2"  !CDS_PN = "2";
BODY = "Q_CAP","I241": LOCATION = "C2376" #&CDS_LOCATION = "C2376" &SEC = "1" #&CDS_SEC = "1";
"A":   PN = "1"  !CDS_PN = "1";
"B":   PN = "2"  !CDS_PN = "2";
BODY = "74LVC1G08W57","I243": LOCATION = "U334" #&CDS_LOCATION = "U334" &SEC = "1" #&CDS_SEC = "1";
"A":   PN = "1"  !CDS_PN = "1";
"B":   PN = "2"  !CDS_PN = "2";
"GND":   PN = "3"  !CDS_PN = "3";
"VCC":   PN = "5"  !CDS_PN = "5";
"Y":   PN = "4"  !CDS_PN = "4";
BODY = "Q_RES","I245": LOCATION = "R4746" #&CDS_LOCATION = "R4746" &SEC = "1" #&CDS_SEC = "1";
"A":   PN = "1"  !CDS_PN = "1";
"B":   PN = "2"  !CDS_PN = "2";
BODY = "Q_RES","I247": LOCATION = "R4750" #&CDS_LOCATION = "R4750" &SEC = "1" #&CDS_SEC = "1";
"A":   PN = "1"  !CDS_PN = "1";
"B":   PN = "2"  !CDS_PN = "2";
BODY = "Q_RES","I249": LOCATION = "R4747" #&CDS_LOCATION = "R4747" &SEC = "1" #&CDS_SEC = "1";
"A":   PN = "1"  !CDS_PN = "1";
"B":   PN = "2"  !CDS_PN = "2";
BODY = "Q_RES","I253": LOCATION = "R4748" #&CDS_LOCATION = "R4748" &SEC = "1" #&CDS_SEC = "1";
"A":   PN = "1"  !CDS_PN = "1";
"B":   PN = "2"  !CDS_PN = "2";
BODY = "Q_RES","I254": LOCATION = "R4749" #&CDS_LOCATION = "R4749" &SEC = "1" #&CDS_SEC = "1";
"A":   PN = "1"  !CDS_PN = "1";
"B":   PN = "2"  !CDS_PN = "2";
BODY = "Q_RES","I256": LOCATION = "R4745" #&CDS_LOCATION = "R4745" &SEC = "1" #&CDS_SEC = "1";
"A":   PN = "1"  !CDS_PN = "1";
"B":   PN = "2"  !CDS_PN = "2";
BODY = "Q_RES","I257": LOCATION = "R4764" #&CDS_LOCATION = "R4764" &SEC = "1" #&CDS_SEC = "1";
"A":   PN = "1"  !CDS_PN = "1";
"B":   PN = "2"  !CDS_PN = "2";
DRAWING = "@s9s_mb_2u_lib.s9s_mb_2u(sch_1):page164";
BODY = "Q_CAP_DIFFBUS","I21": LOCATION = "C932" #&CDS_LOCATION = "C932" &SEC = "1" #&CDS_SEC = "1";
"1":   PN = "1"  !CDS_PN = "1";
"2":   PN = "2"  !CDS_PN = "2";
BODY = "Q_CAP_DIFFBUS","I22": LOCATION = "C933" #&CDS_LOCATION = "C933" &SEC = "1" #&CDS_SEC = "1";
"1":   PN = "1"  !CDS_PN = "1";
"2":   PN = "2"  !CDS_PN = "2";
BODY = "Q_CAP_DIFFBUS","I23": LOCATION = "C931" #&CDS_LOCATION = "C931" &SEC = "1" #&CDS_SEC = "1";
"1":   PN = "1"  !CDS_PN = "1";
"2":   PN = "2"  !CDS_PN = "2";
BODY = "Q_CAP_DIFFBUS","I24": LOCATION = "C930" #&CDS_LOCATION = "C930" &SEC = "1" #&CDS_SEC = "1";
"1":   PN = "1"  !CDS_PN = "1";
"2":   PN = "2"  !CDS_PN = "2";
BODY = "Q_CAP_DIFFBUS","I25": LOCATION = "C928" #&CDS_LOCATION = "C928" &SEC = "1" #&CDS_SEC = "1";
"1":   PN = "1"  !CDS_PN = "1";
"2":   PN = "2"  !CDS_PN = "2";
BODY = "Q_CAP_DIFFBUS","I53": LOCATION = "C916" #&CDS_LOCATION = "C916" &SEC = "1" #&CDS_SEC = "1";
"1":   PN = "1"  !CDS_PN = "1";
"2":   PN = "2"  !CDS_PN = "2";
BODY = "Q_CAP_DIFFBUS","I54": LOCATION = "C917" #&CDS_LOCATION = "C917" &SEC = "1" #&CDS_SEC = "1";
"1":   PN = "1"  !CDS_PN = "1";
"2":   PN = "2"  !CDS_PN = "2";
BODY = "Q_CAP_DIFFBUS","I55": LOCATION = "C915" #&CDS_LOCATION = "C915" &SEC = "1" #&CDS_SEC = "1";
"1":   PN = "1"  !CDS_PN = "1";
"2":   PN = "2"  !CDS_PN = "2";
BODY = "Q_CAP_DIFFBUS","I56": LOCATION = "C914" #&CDS_LOCATION = "C914" &SEC = "1" #&CDS_SEC = "1";
"1":   PN = "1"  !CDS_PN = "1";
"2":   PN = "2"  !CDS_PN = "2";
BODY = "Q_CAP_DIFFBUS","I57": LOCATION = "C913" #&CDS_LOCATION = "C913" &SEC = "1" #&CDS_SEC = "1";
"1":   PN = "1"  !CDS_PN = "1";
"2":   PN = "2"  !CDS_PN = "2";
BODY = "Q_CAP_DIFFBUS","I58": LOCATION = "C912" #&CDS_LOCATION = "C912" &SEC = "1" #&CDS_SEC = "1";
"1":   PN = "1"  !CDS_PN = "1";
"2":   PN = "2"  !CDS_PN = "2";
BODY = "Q_CAP_DIFFBUS","I59": LOCATION = "C911" #&CDS_LOCATION = "C911" &SEC = "1" #&CDS_SEC = "1";
"1":   PN = "1"  !CDS_PN = "1";
"2":   PN = "2"  !CDS_PN = "2";
BODY = "Q_CAP_DIFFBUS","I61": LOCATION = "C909" #&CDS_LOCATION = "C909" &SEC = "1" #&CDS_SEC = "1";
"1":   PN = "1"  !CDS_PN = "1";
"2":   PN = "2"  !CDS_PN = "2";
BODY = "Q_CAP_DIFFBUS","I62": LOCATION = "C908" #&CDS_LOCATION = "C908" &SEC = "1" #&CDS_SEC = "1";
"1":   PN = "1"  !CDS_PN = "1";
"2":   PN = "2"  !CDS_PN = "2";
BODY = "Q_CAP_DIFFBUS","I63": LOCATION = "C906" #&CDS_LOCATION = "C906" &SEC = "1" #&CDS_SEC = "1";
"1":   PN = "1"  !CDS_PN = "1";
"2":   PN = "2"  !CDS_PN = "2";
BODY = "Q_CAP_DIFFBUS","I64": LOCATION = "C907" #&CDS_LOCATION = "C907" &SEC = "1" #&CDS_SEC = "1";
"1":   PN = "1"  !CDS_PN = "1";
"2":   PN = "2"  !CDS_PN = "2";
BODY = "Q_CAP_DIFFBUS","I65": LOCATION = "C905" #&CDS_LOCATION = "C905" &SEC = "1" #&CDS_SEC = "1";
"1":   PN = "1"  !CDS_PN = "1";
"2":   PN = "2"  !CDS_PN = "2";
BODY = "Q_CAP_DIFFBUS","I66": LOCATION = "C904" #&CDS_LOCATION = "C904" &SEC = "1" #&CDS_SEC = "1";
"1":   PN = "1"  !CDS_PN = "1";
"2":   PN = "2"  !CDS_PN = "2";
BODY = "Q_CAP_DIFFBUS","I67": LOCATION = "C903" #&CDS_LOCATION = "C903" &SEC = "1" #&CDS_SEC = "1";
"1":   PN = "1"  !CDS_PN = "1";
"2":   PN = "2"  !CDS_PN = "2";
BODY = "Q_CAP_DIFFBUS","I68": LOCATION = "C902" #&CDS_LOCATION = "C902" &SEC = "1" #&CDS_SEC = "1";
"1":   PN = "1"  !CDS_PN = "1";
"2":   PN = "2"  !CDS_PN = "2";
BODY = "Q_CAP_DIFFBUS","I121": LOCATION = "C965" #&CDS_LOCATION = "C965" &SEC = "1" #&CDS_SEC = "1";
"1":   PN = "1"  !CDS_PN = "1";
"2":   PN = "2"  !CDS_PN = "2";
BODY = "Q_CAP_DIFFBUS","I122": LOCATION = "C964" #&CDS_LOCATION = "C964" &SEC = "1" #&CDS_SEC = "1";
"1":   PN = "1"  !CDS_PN = "1";
"2":   PN = "2"  !CDS_PN = "2";
BODY = "Q_CAP_DIFFBUS","I123": LOCATION = "C963" #&CDS_LOCATION = "C963" &SEC = "1" #&CDS_SEC = "1";
"1":   PN = "1"  !CDS_PN = "1";
"2":   PN = "2"  !CDS_PN = "2";
BODY = "Q_CAP_DIFFBUS","I124": LOCATION = "C962" #&CDS_LOCATION = "C962" &SEC = "1" #&CDS_SEC = "1";
"1":   PN = "1"  !CDS_PN = "1";
"2":   PN = "2"  !CDS_PN = "2";
BODY = "Q_CAP_DIFFBUS","I125": LOCATION = "C961" #&CDS_LOCATION = "C961" &SEC = "1" #&CDS_SEC = "1";
"1":   PN = "1"  !CDS_PN = "1";
"2":   PN = "2"  !CDS_PN = "2";
BODY = "Q_CAP_DIFFBUS","I164": LOCATION = "C939" #&CDS_LOCATION = "C939" &SEC = "1" #&CDS_SEC = "1";
"1":   PN = "1"  !CDS_PN = "1";
"2":   PN = "2"  !CDS_PN = "2";
BODY = "Q_CAP_DIFFBUS","I165": LOCATION = "C938" #&CDS_LOCATION = "C938" &SEC = "1" #&CDS_SEC = "1";
"1":   PN = "1"  !CDS_PN = "1";
"2":   PN = "2"  !CDS_PN = "2";
BODY = "Q_CAP_DIFFBUS","I166": LOCATION = "C937" #&CDS_LOCATION = "C937" &SEC = "1" #&CDS_SEC = "1";
"1":   PN = "1"  !CDS_PN = "1";
"2":   PN = "2"  !CDS_PN = "2";
BODY = "Q_CAP_DIFFBUS","I167": LOCATION = "C936" #&CDS_LOCATION = "C936" &SEC = "1" #&CDS_SEC = "1";
"1":   PN = "1"  !CDS_PN = "1";
"2":   PN = "2"  !CDS_PN = "2";
BODY = "Q_CAP_DIFFBUS","I168": LOCATION = "C935" #&CDS_LOCATION = "C935" &SEC = "1" #&CDS_SEC = "1";
"1":   PN = "1"  !CDS_PN = "1";
"2":   PN = "2"  !CDS_PN = "2";
BODY = "Q_CAP_DIFFBUS","I26": LOCATION = "C929" #&CDS_LOCATION = "C929" &SEC = "1" #&CDS_SEC = "1";
"1":   PN = "1"  !CDS_PN = "1";
"2":   PN = "2"  !CDS_PN = "2";
BODY = "Q_CAP_DIFFBUS","I27": LOCATION = "C927" #&CDS_LOCATION = "C927" &SEC = "1" #&CDS_SEC = "1";
"1":   PN = "1"  !CDS_PN = "1";
"2":   PN = "2"  !CDS_PN = "2";
BODY = "Q_CAP_DIFFBUS","I28": LOCATION = "C926" #&CDS_LOCATION = "C926" &SEC = "1" #&CDS_SEC = "1";
"1":   PN = "1"  !CDS_PN = "1";
"2":   PN = "2"  !CDS_PN = "2";
BODY = "Q_CAP_DIFFBUS","I29": LOCATION = "C925" #&CDS_LOCATION = "C925" &SEC = "1" #&CDS_SEC = "1";
"1":   PN = "1"  !CDS_PN = "1";
"2":   PN = "2"  !CDS_PN = "2";
BODY = "Q_CAP_DIFFBUS","I30": LOCATION = "C924" #&CDS_LOCATION = "C924" &SEC = "1" #&CDS_SEC = "1";
"1":   PN = "1"  !CDS_PN = "1";
"2":   PN = "2"  !CDS_PN = "2";
BODY = "Q_CAP_DIFFBUS","I31": LOCATION = "C923" #&CDS_LOCATION = "C923" &SEC = "1" #&CDS_SEC = "1";
"1":   PN = "1"  !CDS_PN = "1";
"2":   PN = "2"  !CDS_PN = "2";
BODY = "Q_CAP_DIFFBUS","I32": LOCATION = "C922" #&CDS_LOCATION = "C922" &SEC = "1" #&CDS_SEC = "1";
"1":   PN = "1"  !CDS_PN = "1";
"2":   PN = "2"  !CDS_PN = "2";
BODY = "Q_CAP_DIFFBUS","I33": LOCATION = "C921" #&CDS_LOCATION = "C921" &SEC = "1" #&CDS_SEC = "1";
"1":   PN = "1"  !CDS_PN = "1";
"2":   PN = "2"  !CDS_PN = "2";
BODY = "Q_CAP_DIFFBUS","I34": LOCATION = "C920" #&CDS_LOCATION = "C920" &SEC = "1" #&CDS_SEC = "1";
"1":   PN = "1"  !CDS_PN = "1";
"2":   PN = "2"  !CDS_PN = "2";
BODY = "Q_CAP_DIFFBUS","I35": LOCATION = "C918" #&CDS_LOCATION = "C918" &SEC = "1" #&CDS_SEC = "1";
"1":   PN = "1"  !CDS_PN = "1";
"2":   PN = "2"  !CDS_PN = "2";
BODY = "Q_CAP_DIFFBUS","I36": LOCATION = "C919" #&CDS_LOCATION = "C919" &SEC = "1" #&CDS_SEC = "1";
"1":   PN = "1"  !CDS_PN = "1";
"2":   PN = "2"  !CDS_PN = "2";
BODY = "Q_CAP_DIFFBUS","I60": LOCATION = "C910" #&CDS_LOCATION = "C910" &SEC = "1" #&CDS_SEC = "1";
"1":   PN = "1"  !CDS_PN = "1";
"2":   PN = "2"  !CDS_PN = "2";
BODY = "Q_CAP_DIFFBUS","I126": LOCATION = "C960" #&CDS_LOCATION = "C960" &SEC = "1" #&CDS_SEC = "1";
"1":   PN = "1"  !CDS_PN = "1";
"2":   PN = "2"  !CDS_PN = "2";
BODY = "Q_CAP_DIFFBUS","I127": LOCATION = "C959" #&CDS_LOCATION = "C959" &SEC = "1" #&CDS_SEC = "1";
"1":   PN = "1"  !CDS_PN = "1";
"2":   PN = "2"  !CDS_PN = "2";
BODY = "Q_CAP_DIFFBUS","I128": LOCATION = "C958" #&CDS_LOCATION = "C958" &SEC = "1" #&CDS_SEC = "1";
"1":   PN = "1"  !CDS_PN = "1";
"2":   PN = "2"  !CDS_PN = "2";
BODY = "Q_CAP_DIFFBUS","I133": LOCATION = "C954" #&CDS_LOCATION = "C954" &SEC = "1" #&CDS_SEC = "1";
"1":   PN = "1"  !CDS_PN = "1";
"2":   PN = "2"  !CDS_PN = "2";
BODY = "Q_CAP_DIFFBUS","I134": LOCATION = "C953" #&CDS_LOCATION = "C953" &SEC = "1" #&CDS_SEC = "1";
"1":   PN = "1"  !CDS_PN = "1";
"2":   PN = "2"  !CDS_PN = "2";
BODY = "Q_CAP_DIFFBUS","I135": LOCATION = "C952" #&CDS_LOCATION = "C952" &SEC = "1" #&CDS_SEC = "1";
"1":   PN = "1"  !CDS_PN = "1";
"2":   PN = "2"  !CDS_PN = "2";
BODY = "Q_CAP_DIFFBUS","I136": LOCATION = "C951" #&CDS_LOCATION = "C951" &SEC = "1" #&CDS_SEC = "1";
"1":   PN = "1"  !CDS_PN = "1";
"2":   PN = "2"  !CDS_PN = "2";
BODY = "Q_CAP_DIFFBUS","I137": LOCATION = "C950" #&CDS_LOCATION = "C950" &SEC = "1" #&CDS_SEC = "1";
"1":   PN = "1"  !CDS_PN = "1";
"2":   PN = "2"  !CDS_PN = "2";
BODY = "Q_CAP_DIFFBUS","I151": LOCATION = "C949" #&CDS_LOCATION = "C949" &SEC = "1" #&CDS_SEC = "1";
"1":   PN = "1"  !CDS_PN = "1";
"2":   PN = "2"  !CDS_PN = "2";
BODY = "Q_CAP_DIFFBUS","I152": LOCATION = "C948" #&CDS_LOCATION = "C948" &SEC = "1" #&CDS_SEC = "1";
"1":   PN = "1"  !CDS_PN = "1";
"2":   PN = "2"  !CDS_PN = "2";
BODY = "Q_CAP_DIFFBUS","I153": LOCATION = "C947" #&CDS_LOCATION = "C947" &SEC = "1" #&CDS_SEC = "1";
"1":   PN = "1"  !CDS_PN = "1";
"2":   PN = "2"  !CDS_PN = "2";
BODY = "Q_CAP_DIFFBUS","I154": LOCATION = "C946" #&CDS_LOCATION = "C946" &SEC = "1" #&CDS_SEC = "1";
"1":   PN = "1"  !CDS_PN = "1";
"2":   PN = "2"  !CDS_PN = "2";
BODY = "Q_CAP_DIFFBUS","I155": LOCATION = "C945" #&CDS_LOCATION = "C945" &SEC = "1" #&CDS_SEC = "1";
"1":   PN = "1"  !CDS_PN = "1";
"2":   PN = "2"  !CDS_PN = "2";
BODY = "Q_CAP_DIFFBUS","I156": LOCATION = "C944" #&CDS_LOCATION = "C944" &SEC = "1" #&CDS_SEC = "1";
"1":   PN = "1"  !CDS_PN = "1";
"2":   PN = "2"  !CDS_PN = "2";
BODY = "Q_CAP_DIFFBUS","I157": LOCATION = "C943" #&CDS_LOCATION = "C943" &SEC = "1" #&CDS_SEC = "1";
"1":   PN = "1"  !CDS_PN = "1";
"2":   PN = "2"  !CDS_PN = "2";
BODY = "Q_CAP_DIFFBUS","I158": LOCATION = "C942" #&CDS_LOCATION = "C942" &SEC = "1" #&CDS_SEC = "1";
"1":   PN = "1"  !CDS_PN = "1";
"2":   PN = "2"  !CDS_PN = "2";
BODY = "Q_CAP_DIFFBUS","I159": LOCATION = "C941" #&CDS_LOCATION = "C941" &SEC = "1" #&CDS_SEC = "1";
"1":   PN = "1"  !CDS_PN = "1";
"2":   PN = "2"  !CDS_PN = "2";
BODY = "Q_CAP_DIFFBUS","I160": LOCATION = "C940" #&CDS_LOCATION = "C940" &SEC = "1" #&CDS_SEC = "1";
"1":   PN = "1"  !CDS_PN = "1";
"2":   PN = "2"  !CDS_PN = "2";
BODY = "Q_CAP_DIFFBUS","I169": LOCATION = "C934" #&CDS_LOCATION = "C934" &SEC = "1" #&CDS_SEC = "1";
"1":   PN = "1"  !CDS_PN = "1";
"2":   PN = "2"  !CDS_PN = "2";
BODY = "Q_CAP_DIFFBUS","I206": LOCATION = "C957" #&CDS_LOCATION = "C957" &SEC = "1" #&CDS_SEC = "1";
"1":   PN = "1"  !CDS_PN = "1";
"2":   PN = "2"  !CDS_PN = "2";
BODY = "Q_CAP_DIFFBUS","I207": LOCATION = "C956" #&CDS_LOCATION = "C956" &SEC = "1" #&CDS_SEC = "1";
"1":   PN = "1"  !CDS_PN = "1";
"2":   PN = "2"  !CDS_PN = "2";
BODY = "Q_CAP_DIFFBUS","I208": LOCATION = "C955" #&CDS_LOCATION = "C955" &SEC = "1" #&CDS_SEC = "1";
"1":   PN = "1"  !CDS_PN = "1";
"2":   PN = "2"  !CDS_PN = "2";
DRAWING = "@s9s_mb_2u_lib.s9s_mb_2u(sch_1):page165";
BODY = "Q_CAP_DIFFBUS","I120": LOCATION = "C901" #&CDS_LOCATION = "C901" &SEC = "1" #&CDS_SEC = "1";
"1":   PN = "1"  !CDS_PN = "1";
"2":   PN = "2"  !CDS_PN = "2";
BODY = "Q_CAP_DIFFBUS","I121": LOCATION = "C900" #&CDS_LOCATION = "C900" &SEC = "1" #&CDS_SEC = "1";
"1":   PN = "1"  !CDS_PN = "1";
"2":   PN = "2"  !CDS_PN = "2";
BODY = "Q_CAP_DIFFBUS","I122": LOCATION = "C899" #&CDS_LOCATION = "C899" &SEC = "1" #&CDS_SEC = "1";
"1":   PN = "1"  !CDS_PN = "1";
"2":   PN = "2"  !CDS_PN = "2";
BODY = "Q_CAP_DIFFBUS","I123": LOCATION = "C897" #&CDS_LOCATION = "C897" &SEC = "1" #&CDS_SEC = "1";
"1":   PN = "1"  !CDS_PN = "1";
"2":   PN = "2"  !CDS_PN = "2";
BODY = "Q_CAP_DIFFBUS","I124": LOCATION = "C896" #&CDS_LOCATION = "C896" &SEC = "1" #&CDS_SEC = "1";
"1":   PN = "1"  !CDS_PN = "1";
"2":   PN = "2"  !CDS_PN = "2";
BODY = "Q_CAP_DIFFBUS","I125": LOCATION = "C895" #&CDS_LOCATION = "C895" &SEC = "1" #&CDS_SEC = "1";
"1":   PN = "1"  !CDS_PN = "1";
"2":   PN = "2"  !CDS_PN = "2";
BODY = "Q_CAP_DIFFBUS","I126": LOCATION = "C894" #&CDS_LOCATION = "C894" &SEC = "1" #&CDS_SEC = "1";
"1":   PN = "1"  !CDS_PN = "1";
"2":   PN = "2"  !CDS_PN = "2";
BODY = "Q_CAP_DIFFBUS","I127": LOCATION = "C892" #&CDS_LOCATION = "C892" &SEC = "1" #&CDS_SEC = "1";
"1":   PN = "1"  !CDS_PN = "1";
"2":   PN = "2"  !CDS_PN = "2";
BODY = "Q_CAP_DIFFBUS","I128": LOCATION = "C893" #&CDS_LOCATION = "C893" &SEC = "1" #&CDS_SEC = "1";
"1":   PN = "1"  !CDS_PN = "1";
"2":   PN = "2"  !CDS_PN = "2";
BODY = "Q_CAP_DIFFBUS","I134": LOCATION = "C889" #&CDS_LOCATION = "C889" &SEC = "1" #&CDS_SEC = "1";
"1":   PN = "1"  !CDS_PN = "1";
"2":   PN = "2"  !CDS_PN = "2";
BODY = "Q_CAP_DIFFBUS","I135": LOCATION = "C888" #&CDS_LOCATION = "C888" &SEC = "1" #&CDS_SEC = "1";
"1":   PN = "1"  !CDS_PN = "1";
"2":   PN = "2"  !CDS_PN = "2";
BODY = "Q_CAP_DIFFBUS","I136": LOCATION = "C887" #&CDS_LOCATION = "C887" &SEC = "1" #&CDS_SEC = "1";
"1":   PN = "1"  !CDS_PN = "1";
"2":   PN = "2"  !CDS_PN = "2";
BODY = "Q_CAP_DIFFBUS","I137": LOCATION = "C886" #&CDS_LOCATION = "C886" &SEC = "1" #&CDS_SEC = "1";
"1":   PN = "1"  !CDS_PN = "1";
"2":   PN = "2"  !CDS_PN = "2";
BODY = "Q_CAP_DIFFBUS","I152": LOCATION = "C885" #&CDS_LOCATION = "C885" &SEC = "1" #&CDS_SEC = "1";
"1":   PN = "1"  !CDS_PN = "1";
"2":   PN = "2"  !CDS_PN = "2";
BODY = "Q_CAP_DIFFBUS","I153": LOCATION = "C883" #&CDS_LOCATION = "C883" &SEC = "1" #&CDS_SEC = "1";
"1":   PN = "1"  !CDS_PN = "1";
"2":   PN = "2"  !CDS_PN = "2";
BODY = "Q_CAP_DIFFBUS","I154": LOCATION = "C882" #&CDS_LOCATION = "C882" &SEC = "1" #&CDS_SEC = "1";
"1":   PN = "1"  !CDS_PN = "1";
"2":   PN = "2"  !CDS_PN = "2";
BODY = "Q_CAP_DIFFBUS","I155": LOCATION = "C881" #&CDS_LOCATION = "C881" &SEC = "1" #&CDS_SEC = "1";
"1":   PN = "1"  !CDS_PN = "1";
"2":   PN = "2"  !CDS_PN = "2";
BODY = "Q_CAP_DIFFBUS","I156": LOCATION = "C880" #&CDS_LOCATION = "C880" &SEC = "1" #&CDS_SEC = "1";
"1":   PN = "1"  !CDS_PN = "1";
"2":   PN = "2"  !CDS_PN = "2";
BODY = "Q_CAP_DIFFBUS","I157": LOCATION = "C878" #&CDS_LOCATION = "C878" &SEC = "1" #&CDS_SEC = "1";
"1":   PN = "1"  !CDS_PN = "1";
"2":   PN = "2"  !CDS_PN = "2";
BODY = "Q_CAP_DIFFBUS","I158": LOCATION = "C879" #&CDS_LOCATION = "C879" &SEC = "1" #&CDS_SEC = "1";
"1":   PN = "1"  !CDS_PN = "1";
"2":   PN = "2"  !CDS_PN = "2";
BODY = "Q_CAP_DIFFBUS","I159": LOCATION = "C877" #&CDS_LOCATION = "C877" &SEC = "1" #&CDS_SEC = "1";
"1":   PN = "1"  !CDS_PN = "1";
"2":   PN = "2"  !CDS_PN = "2";
BODY = "Q_CAP_DIFFBUS","I160": LOCATION = "C876" #&CDS_LOCATION = "C876" &SEC = "1" #&CDS_SEC = "1";
"1":   PN = "1"  !CDS_PN = "1";
"2":   PN = "2"  !CDS_PN = "2";
BODY = "Q_CAP_DIFFBUS","I165": LOCATION = "C874" #&CDS_LOCATION = "C874" &SEC = "1" #&CDS_SEC = "1";
"1":   PN = "1"  !CDS_PN = "1";
"2":   PN = "2"  !CDS_PN = "2";
BODY = "Q_CAP_DIFFBUS","I166": LOCATION = "C873" #&CDS_LOCATION = "C873" &SEC = "1" #&CDS_SEC = "1";
"1":   PN = "1"  !CDS_PN = "1";
"2":   PN = "2"  !CDS_PN = "2";
BODY = "Q_CAP_DIFFBUS","I167": LOCATION = "C872" #&CDS_LOCATION = "C872" &SEC = "1" #&CDS_SEC = "1";
"1":   PN = "1"  !CDS_PN = "1";
"2":   PN = "2"  !CDS_PN = "2";
BODY = "Q_CAP_DIFFBUS","I168": LOCATION = "C871" #&CDS_LOCATION = "C871" &SEC = "1" #&CDS_SEC = "1";
"1":   PN = "1"  !CDS_PN = "1";
"2":   PN = "2"  !CDS_PN = "2";
BODY = "Q_CAP_DIFFBUS","I169": LOCATION = "C870" #&CDS_LOCATION = "C870" &SEC = "1" #&CDS_SEC = "1";
"1":   PN = "1"  !CDS_PN = "1";
"2":   PN = "2"  !CDS_PN = "2";
BODY = "Q_CAP_DIFFBUS","I21": LOCATION = "C869" #&CDS_LOCATION = "C869" &SEC = "1" #&CDS_SEC = "1";
"1":   PN = "1"  !CDS_PN = "1";
"2":   PN = "2"  !CDS_PN = "2";
BODY = "Q_CAP_DIFFBUS","I22": LOCATION = "C868" #&CDS_LOCATION = "C868" &SEC = "1" #&CDS_SEC = "1";
"1":   PN = "1"  !CDS_PN = "1";
"2":   PN = "2"  !CDS_PN = "2";
BODY = "Q_CAP_DIFFBUS","I23": LOCATION = "C867" #&CDS_LOCATION = "C867" &SEC = "1" #&CDS_SEC = "1";
"1":   PN = "1"  !CDS_PN = "1";
"2":   PN = "2"  !CDS_PN = "2";
BODY = "Q_CAP_DIFFBUS","I24": LOCATION = "C866" #&CDS_LOCATION = "C866" &SEC = "1" #&CDS_SEC = "1";
"1":   PN = "1"  !CDS_PN = "1";
"2":   PN = "2"  !CDS_PN = "2";
BODY = "Q_CAP_DIFFBUS","I25": LOCATION = "C864" #&CDS_LOCATION = "C864" &SEC = "1" #&CDS_SEC = "1";
"1":   PN = "1"  !CDS_PN = "1";
"2":   PN = "2"  !CDS_PN = "2";
BODY = "Q_CAP_DIFFBUS","I26": LOCATION = "C865" #&CDS_LOCATION = "C865" &SEC = "1" #&CDS_SEC = "1";
"1":   PN = "1"  !CDS_PN = "1";
"2":   PN = "2"  !CDS_PN = "2";
BODY = "Q_CAP_DIFFBUS","I27": LOCATION = "C863" #&CDS_LOCATION = "C863" &SEC = "1" #&CDS_SEC = "1";
"1":   PN = "1"  !CDS_PN = "1";
"2":   PN = "2"  !CDS_PN = "2";
BODY = "Q_CAP_DIFFBUS","I28": LOCATION = "C862" #&CDS_LOCATION = "C862" &SEC = "1" #&CDS_SEC = "1";
"1":   PN = "1"  !CDS_PN = "1";
"2":   PN = "2"  !CDS_PN = "2";
BODY = "Q_CAP_DIFFBUS","I29": LOCATION = "C861" #&CDS_LOCATION = "C861" &SEC = "1" #&CDS_SEC = "1";
"1":   PN = "1"  !CDS_PN = "1";
"2":   PN = "2"  !CDS_PN = "2";
BODY = "Q_CAP_DIFFBUS","I30": LOCATION = "C860" #&CDS_LOCATION = "C860" &SEC = "1" #&CDS_SEC = "1";
"1":   PN = "1"  !CDS_PN = "1";
"2":   PN = "2"  !CDS_PN = "2";
BODY = "Q_CAP_DIFFBUS","I36": LOCATION = "C859" #&CDS_LOCATION = "C859" &SEC = "1" #&CDS_SEC = "1";
"1":   PN = "1"  !CDS_PN = "1";
"2":   PN = "2"  !CDS_PN = "2";
BODY = "Q_CAP_DIFFBUS","I37": LOCATION = "C858" #&CDS_LOCATION = "C858" &SEC = "1" #&CDS_SEC = "1";
"1":   PN = "1"  !CDS_PN = "1";
"2":   PN = "2"  !CDS_PN = "2";
BODY = "Q_CAP_DIFFBUS","I38": LOCATION = "C857" #&CDS_LOCATION = "C857" &SEC = "1" #&CDS_SEC = "1";
"1":   PN = "1"  !CDS_PN = "1";
"2":   PN = "2"  !CDS_PN = "2";
BODY = "Q_CAP_DIFFBUS","I39": LOCATION = "C856" #&CDS_LOCATION = "C856" &SEC = "1" #&CDS_SEC = "1";
"1":   PN = "1"  !CDS_PN = "1";
"2":   PN = "2"  !CDS_PN = "2";
BODY = "Q_CAP_DIFFBUS","I40": LOCATION = "C855" #&CDS_LOCATION = "C855" &SEC = "1" #&CDS_SEC = "1";
"1":   PN = "1"  !CDS_PN = "1";
"2":   PN = "2"  !CDS_PN = "2";
BODY = "Q_CAP_DIFFBUS","I41": LOCATION = "C854" #&CDS_LOCATION = "C854" &SEC = "1" #&CDS_SEC = "1";
"1":   PN = "1"  !CDS_PN = "1";
"2":   PN = "2"  !CDS_PN = "2";
BODY = "Q_CAP_DIFFBUS","I61": LOCATION = "C852" #&CDS_LOCATION = "C852" &SEC = "1" #&CDS_SEC = "1";
"1":   PN = "1"  !CDS_PN = "1";
"2":   PN = "2"  !CDS_PN = "2";
BODY = "Q_CAP_DIFFBUS","I62": LOCATION = "C853" #&CDS_LOCATION = "C853" &SEC = "1" #&CDS_SEC = "1";
"1":   PN = "1"  !CDS_PN = "1";
"2":   PN = "2"  !CDS_PN = "2";
BODY = "Q_CAP_DIFFBUS","I63": LOCATION = "C851" #&CDS_LOCATION = "C851" &SEC = "1" #&CDS_SEC = "1";
"1":   PN = "1"  !CDS_PN = "1";
"2":   PN = "2"  !CDS_PN = "2";
BODY = "Q_CAP_DIFFBUS","I64": LOCATION = "C850" #&CDS_LOCATION = "C850" &SEC = "1" #&CDS_SEC = "1";
"1":   PN = "1"  !CDS_PN = "1";
"2":   PN = "2"  !CDS_PN = "2";
BODY = "Q_CAP_DIFFBUS","I65": LOCATION = "C849" #&CDS_LOCATION = "C849" &SEC = "1" #&CDS_SEC = "1";
"1":   PN = "1"  !CDS_PN = "1";
"2":   PN = "2"  !CDS_PN = "2";
BODY = "Q_CAP_DIFFBUS","I66": LOCATION = "C848" #&CDS_LOCATION = "C848" &SEC = "1" #&CDS_SEC = "1";
"1":   PN = "1"  !CDS_PN = "1";
"2":   PN = "2"  !CDS_PN = "2";
BODY = "Q_CAP_DIFFBUS","I67": LOCATION = "C847" #&CDS_LOCATION = "C847" &SEC = "1" #&CDS_SEC = "1";
"1":   PN = "1"  !CDS_PN = "1";
"2":   PN = "2"  !CDS_PN = "2";
BODY = "Q_CAP_DIFFBUS","I68": LOCATION = "C846" #&CDS_LOCATION = "C846" &SEC = "1" #&CDS_SEC = "1";
"1":   PN = "1"  !CDS_PN = "1";
"2":   PN = "2"  !CDS_PN = "2";
BODY = "Q_CAP_DIFFBUS","I69": LOCATION = "C845" #&CDS_LOCATION = "C845" &SEC = "1" #&CDS_SEC = "1";
"1":   PN = "1"  !CDS_PN = "1";
"2":   PN = "2"  !CDS_PN = "2";
BODY = "Q_CAP_DIFFBUS","I70": LOCATION = "C844" #&CDS_LOCATION = "C844" &SEC = "1" #&CDS_SEC = "1";
"1":   PN = "1"  !CDS_PN = "1";
"2":   PN = "2"  !CDS_PN = "2";
BODY = "Q_CAP_DIFFBUS","I76": LOCATION = "C842" #&CDS_LOCATION = "C842" &SEC = "1" #&CDS_SEC = "1";
"1":   PN = "1"  !CDS_PN = "1";
"2":   PN = "2"  !CDS_PN = "2";
BODY = "Q_CAP_DIFFBUS","I77": LOCATION = "C843" #&CDS_LOCATION = "C843" &SEC = "1" #&CDS_SEC = "1";
"1":   PN = "1"  !CDS_PN = "1";
"2":   PN = "2"  !CDS_PN = "2";
BODY = "Q_CAP_DIFFBUS","I78": LOCATION = "C841" #&CDS_LOCATION = "C841" &SEC = "1" #&CDS_SEC = "1";
"1":   PN = "1"  !CDS_PN = "1";
"2":   PN = "2"  !CDS_PN = "2";
BODY = "Q_CAP_DIFFBUS","I79": LOCATION = "C840" #&CDS_LOCATION = "C840" &SEC = "1" #&CDS_SEC = "1";
"1":   PN = "1"  !CDS_PN = "1";
"2":   PN = "2"  !CDS_PN = "2";
BODY = "Q_CAP_DIFFBUS","I80": LOCATION = "C838" #&CDS_LOCATION = "C838" &SEC = "1" #&CDS_SEC = "1";
"1":   PN = "1"  !CDS_PN = "1";
"2":   PN = "2"  !CDS_PN = "2";
BODY = "Q_CAP_DIFFBUS","I81": LOCATION = "C839" #&CDS_LOCATION = "C839" &SEC = "1" #&CDS_SEC = "1";
"1":   PN = "1"  !CDS_PN = "1";
"2":   PN = "2"  !CDS_PN = "2";
BODY = "Q_CAP_DIFFBUS","I132": LOCATION = "C891" #&CDS_LOCATION = "C891" &SEC = "1" #&CDS_SEC = "1";
"1":   PN = "1"  !CDS_PN = "1";
"2":   PN = "2"  !CDS_PN = "2";
BODY = "Q_CAP_DIFFBUS","I133": LOCATION = "C890" #&CDS_LOCATION = "C890" &SEC = "1" #&CDS_SEC = "1";
"1":   PN = "1"  !CDS_PN = "1";
"2":   PN = "2"  !CDS_PN = "2";
BODY = "Q_CAP_DIFFBUS","I151": LOCATION = "C884" #&CDS_LOCATION = "C884" &SEC = "1" #&CDS_SEC = "1";
"1":   PN = "1"  !CDS_PN = "1";
"2":   PN = "2"  !CDS_PN = "2";
BODY = "Q_CAP_DIFFBUS","I164": LOCATION = "C875" #&CDS_LOCATION = "C875" &SEC = "1" #&CDS_SEC = "1";
"1":   PN = "1"  !CDS_PN = "1";
"2":   PN = "2"  !CDS_PN = "2";
BODY = "Q_CAP_DIFFBUS","I206": LOCATION = "C898" #&CDS_LOCATION = "C898" &SEC = "1" #&CDS_SEC = "1";
"1":   PN = "1"  !CDS_PN = "1";
"2":   PN = "2"  !CDS_PN = "2";
DRAWING = "@s9s_mb_2u_lib.s9s_mb_2u(sch_1):page166";
BODY = "Q_CAP_DIFFBUS","I229": LOCATION = "C1579" #&CDS_LOCATION = "C1579" &SEC = "1" #&CDS_SEC = "1";
"1":   PN = "1"  !CDS_PN = "1";
"2":   PN = "2"  !CDS_PN = "2";
BODY = "Q_CAP_DIFFBUS","I230": LOCATION = "C1578" #&CDS_LOCATION = "C1578" &SEC = "1" #&CDS_SEC = "1";
"1":   PN = "1"  !CDS_PN = "1";
"2":   PN = "2"  !CDS_PN = "2";
BODY = "Q_CAP_DIFFBUS","I231": LOCATION = "C1575" #&CDS_LOCATION = "C1575" &SEC = "1" #&CDS_SEC = "1";
"1":   PN = "1"  !CDS_PN = "1";
"2":   PN = "2"  !CDS_PN = "2";
BODY = "Q_CAP_DIFFBUS","I232": LOCATION = "C1574" #&CDS_LOCATION = "C1574" &SEC = "1" #&CDS_SEC = "1";
"1":   PN = "1"  !CDS_PN = "1";
"2":   PN = "2"  !CDS_PN = "2";
BODY = "Q_CAP_DIFFBUS","I233": LOCATION = "C1573" #&CDS_LOCATION = "C1573" &SEC = "1" #&CDS_SEC = "1";
"1":   PN = "1"  !CDS_PN = "1";
"2":   PN = "2"  !CDS_PN = "2";
BODY = "Q_CAP_DIFFBUS","I234": LOCATION = "C1572" #&CDS_LOCATION = "C1572" &SEC = "1" #&CDS_SEC = "1";
"1":   PN = "1"  !CDS_PN = "1";
"2":   PN = "2"  !CDS_PN = "2";
BODY = "Q_CAP_DIFFBUS","I235": LOCATION = "C1570" #&CDS_LOCATION = "C1570" &SEC = "1" #&CDS_SEC = "1";
"1":   PN = "1"  !CDS_PN = "1";
"2":   PN = "2"  !CDS_PN = "2";
BODY = "Q_CAP_DIFFBUS","I236": LOCATION = "C1571" #&CDS_LOCATION = "C1571" &SEC = "1" #&CDS_SEC = "1";
"1":   PN = "1"  !CDS_PN = "1";
"2":   PN = "2"  !CDS_PN = "2";
BODY = "Q_CAP_DIFFBUS","I237": LOCATION = "C1569" #&CDS_LOCATION = "C1569" &SEC = "1" #&CDS_SEC = "1";
"1":   PN = "1"  !CDS_PN = "1";
"2":   PN = "2"  !CDS_PN = "2";
BODY = "Q_CAP_DIFFBUS","I238": LOCATION = "C1568" #&CDS_LOCATION = "C1568" &SEC = "1" #&CDS_SEC = "1";
"1":   PN = "1"  !CDS_PN = "1";
"2":   PN = "2"  !CDS_PN = "2";
BODY = "Q_CAP_DIFFBUS","I239": LOCATION = "C1567" #&CDS_LOCATION = "C1567" &SEC = "1" #&CDS_SEC = "1";
"1":   PN = "1"  !CDS_PN = "1";
"2":   PN = "2"  !CDS_PN = "2";
BODY = "Q_CAP_DIFFBUS","I240": LOCATION = "C1566" #&CDS_LOCATION = "C1566" &SEC = "1" #&CDS_SEC = "1";
"1":   PN = "1"  !CDS_PN = "1";
"2":   PN = "2"  !CDS_PN = "2";
BODY = "Q_CAP_DIFFBUS","I241": LOCATION = "C1565" #&CDS_LOCATION = "C1565" &SEC = "1" #&CDS_SEC = "1";
"1":   PN = "1"  !CDS_PN = "1";
"2":   PN = "2"  !CDS_PN = "2";
BODY = "Q_CAP_DIFFBUS","I242": LOCATION = "C1564" #&CDS_LOCATION = "C1564" &SEC = "1" #&CDS_SEC = "1";
"1":   PN = "1"  !CDS_PN = "1";
"2":   PN = "2"  !CDS_PN = "2";
BODY = "Q_CAP_DIFFBUS","I259": LOCATION = "C1563" #&CDS_LOCATION = "C1563" &SEC = "1" #&CDS_SEC = "1";
"1":   PN = "1"  !CDS_PN = "1";
"2":   PN = "2"  !CDS_PN = "2";
BODY = "Q_CAP_DIFFBUS","I260": LOCATION = "C1794" #&CDS_LOCATION = "C1794" &SEC = "1" #&CDS_SEC = "1";
"1":   PN = "1"  !CDS_PN = "1";
"2":   PN = "2"  !CDS_PN = "2";
BODY = "Q_CAP_DIFFBUS","I261": LOCATION = "C1793" #&CDS_LOCATION = "C1793" &SEC = "1" #&CDS_SEC = "1";
"1":   PN = "1"  !CDS_PN = "1";
"2":   PN = "2"  !CDS_PN = "2";
BODY = "Q_CAP_DIFFBUS","I262": LOCATION = "C1560" #&CDS_LOCATION = "C1560" &SEC = "1" #&CDS_SEC = "1";
"1":   PN = "1"  !CDS_PN = "1";
"2":   PN = "2"  !CDS_PN = "2";
BODY = "Q_CAP_DIFFBUS","I263": LOCATION = "C1559" #&CDS_LOCATION = "C1559" &SEC = "1" #&CDS_SEC = "1";
"1":   PN = "1"  !CDS_PN = "1";
"2":   PN = "2"  !CDS_PN = "2";
BODY = "Q_CAP_DIFFBUS","I264": LOCATION = "C1558" #&CDS_LOCATION = "C1558" &SEC = "1" #&CDS_SEC = "1";
"1":   PN = "1"  !CDS_PN = "1";
"2":   PN = "2"  !CDS_PN = "2";
BODY = "Q_CAP_DIFFBUS","I265": LOCATION = "C1556" #&CDS_LOCATION = "C1556" &SEC = "1" #&CDS_SEC = "1";
"1":   PN = "1"  !CDS_PN = "1";
"2":   PN = "2"  !CDS_PN = "2";
BODY = "Q_CAP_DIFFBUS","I266": LOCATION = "C1557" #&CDS_LOCATION = "C1557" &SEC = "1" #&CDS_SEC = "1";
"1":   PN = "1"  !CDS_PN = "1";
"2":   PN = "2"  !CDS_PN = "2";
BODY = "Q_CAP_DIFFBUS","I267": LOCATION = "C1555" #&CDS_LOCATION = "C1555" &SEC = "1" #&CDS_SEC = "1";
"1":   PN = "1"  !CDS_PN = "1";
"2":   PN = "2"  !CDS_PN = "2";
BODY = "Q_CAP_DIFFBUS","I268": LOCATION = "C1554" #&CDS_LOCATION = "C1554" &SEC = "1" #&CDS_SEC = "1";
"1":   PN = "1"  !CDS_PN = "1";
"2":   PN = "2"  !CDS_PN = "2";
BODY = "Q_CAP_DIFFBUS","I269": LOCATION = "C1553" #&CDS_LOCATION = "C1553" &SEC = "1" #&CDS_SEC = "1";
"1":   PN = "1"  !CDS_PN = "1";
"2":   PN = "2"  !CDS_PN = "2";
BODY = "Q_CAP_DIFFBUS","I270": LOCATION = "C1552" #&CDS_LOCATION = "C1552" &SEC = "1" #&CDS_SEC = "1";
"1":   PN = "1"  !CDS_PN = "1";
"2":   PN = "2"  !CDS_PN = "2";
BODY = "Q_CAP_DIFFBUS","I271": LOCATION = "C1792" #&CDS_LOCATION = "C1792" &SEC = "1" #&CDS_SEC = "1";
"1":   PN = "1"  !CDS_PN = "1";
"2":   PN = "2"  !CDS_PN = "2";
BODY = "Q_CAP_DIFFBUS","I272": LOCATION = "C1550" #&CDS_LOCATION = "C1550" &SEC = "1" #&CDS_SEC = "1";
"1":   PN = "1"  !CDS_PN = "1";
"2":   PN = "2"  !CDS_PN = "2";
BODY = "Q_CAP_DIFFBUS","I273": LOCATION = "C1548" #&CDS_LOCATION = "C1548" &SEC = "1" #&CDS_SEC = "1";
"1":   PN = "1"  !CDS_PN = "1";
"2":   PN = "2"  !CDS_PN = "2";
BODY = "Q_CAP_DIFFBUS","I274": LOCATION = "C1549" #&CDS_LOCATION = "C1549" &SEC = "1" #&CDS_SEC = "1";
"1":   PN = "1"  !CDS_PN = "1";
"2":   PN = "2"  !CDS_PN = "2";
BODY = "Q_CAP_DIFFBUS","I311": LOCATION = "C1577" #&CDS_LOCATION = "C1577" &SEC = "1" #&CDS_SEC = "1";
"1":   PN = "1"  !CDS_PN = "1";
"2":   PN = "2"  !CDS_PN = "2";
BODY = "Q_CAP_DIFFBUS","I312": LOCATION = "C1576" #&CDS_LOCATION = "C1576" &SEC = "1" #&CDS_SEC = "1";
"1":   PN = "1"  !CDS_PN = "1";
"2":   PN = "2"  !CDS_PN = "2";
BODY = "Q_CAP_DIFFBUS","I363": LOCATION = "C820" #&CDS_LOCATION = "C820" &SEC = "1" #&CDS_SEC = "1";
"1":   PN = "1"  !CDS_PN = "1";
"2":   PN = "2"  !CDS_PN = "2";
BODY = "Q_CAP_DIFFBUS","I364": LOCATION = "C821" #&CDS_LOCATION = "C821" &SEC = "1" #&CDS_SEC = "1";
"1":   PN = "1"  !CDS_PN = "1";
"2":   PN = "2"  !CDS_PN = "2";
BODY = "Q_CAP_DIFFBUS","I365": LOCATION = "C818" #&CDS_LOCATION = "C818" &SEC = "1" #&CDS_SEC = "1";
"1":   PN = "1"  !CDS_PN = "1";
"2":   PN = "2"  !CDS_PN = "2";
BODY = "Q_CAP_DIFFBUS","I333": LOCATION = "C836" #&CDS_LOCATION = "C836" &SEC = "1" #&CDS_SEC = "1";
"1":   PN = "1"  !CDS_PN = "1";
"2":   PN = "2"  !CDS_PN = "2";
BODY = "Q_CAP_DIFFBUS","I334": LOCATION = "C837" #&CDS_LOCATION = "C837" &SEC = "1" #&CDS_SEC = "1";
"1":   PN = "1"  !CDS_PN = "1";
"2":   PN = "2"  !CDS_PN = "2";
BODY = "Q_CAP_DIFFBUS","I335": LOCATION = "C834" #&CDS_LOCATION = "C834" &SEC = "1" #&CDS_SEC = "1";
"1":   PN = "1"  !CDS_PN = "1";
"2":   PN = "2"  !CDS_PN = "2";
BODY = "Q_CAP_DIFFBUS","I336": LOCATION = "C835" #&CDS_LOCATION = "C835" &SEC = "1" #&CDS_SEC = "1";
"1":   PN = "1"  !CDS_PN = "1";
"2":   PN = "2"  !CDS_PN = "2";
BODY = "Q_CAP_DIFFBUS","I337": LOCATION = "C831" #&CDS_LOCATION = "C831" &SEC = "1" #&CDS_SEC = "1";
"1":   PN = "1"  !CDS_PN = "1";
"2":   PN = "2"  !CDS_PN = "2";
BODY = "Q_CAP_DIFFBUS","I338": LOCATION = "C832" #&CDS_LOCATION = "C832" &SEC = "1" #&CDS_SEC = "1";
"1":   PN = "1"  !CDS_PN = "1";
"2":   PN = "2"  !CDS_PN = "2";
BODY = "Q_CAP_DIFFBUS","I339": LOCATION = "C833" #&CDS_LOCATION = "C833" &SEC = "1" #&CDS_SEC = "1";
"1":   PN = "1"  !CDS_PN = "1";
"2":   PN = "2"  !CDS_PN = "2";
BODY = "Q_CAP_DIFFBUS","I340": LOCATION = "C828" #&CDS_LOCATION = "C828" &SEC = "1" #&CDS_SEC = "1";
"1":   PN = "1"  !CDS_PN = "1";
"2":   PN = "2"  !CDS_PN = "2";
BODY = "Q_CAP_DIFFBUS","I341": LOCATION = "C830" #&CDS_LOCATION = "C830" &SEC = "1" #&CDS_SEC = "1";
"1":   PN = "1"  !CDS_PN = "1";
"2":   PN = "2"  !CDS_PN = "2";
BODY = "Q_CAP_DIFFBUS","I342": LOCATION = "C829" #&CDS_LOCATION = "C829" &SEC = "1" #&CDS_SEC = "1";
"1":   PN = "1"  !CDS_PN = "1";
"2":   PN = "2"  !CDS_PN = "2";
BODY = "Q_CAP_DIFFBUS","I343": LOCATION = "C827" #&CDS_LOCATION = "C827" &SEC = "1" #&CDS_SEC = "1";
"1":   PN = "1"  !CDS_PN = "1";
"2":   PN = "2"  !CDS_PN = "2";
BODY = "Q_CAP_DIFFBUS","I344": LOCATION = "C826" #&CDS_LOCATION = "C826" &SEC = "1" #&CDS_SEC = "1";
"1":   PN = "1"  !CDS_PN = "1";
"2":   PN = "2"  !CDS_PN = "2";
BODY = "Q_CAP_DIFFBUS","I345": LOCATION = "C822" #&CDS_LOCATION = "C822" &SEC = "1" #&CDS_SEC = "1";
"1":   PN = "1"  !CDS_PN = "1";
"2":   PN = "2"  !CDS_PN = "2";
BODY = "Q_CAP_DIFFBUS","I346": LOCATION = "C823" #&CDS_LOCATION = "C823" &SEC = "1" #&CDS_SEC = "1";
"1":   PN = "1"  !CDS_PN = "1";
"2":   PN = "2"  !CDS_PN = "2";
BODY = "Q_CAP_DIFFBUS","I366": LOCATION = "C819" #&CDS_LOCATION = "C819" &SEC = "1" #&CDS_SEC = "1";
"1":   PN = "1"  !CDS_PN = "1";
"2":   PN = "2"  !CDS_PN = "2";
BODY = "Q_CAP_DIFFBUS","I367": LOCATION = "C817" #&CDS_LOCATION = "C817" &SEC = "1" #&CDS_SEC = "1";
"1":   PN = "1"  !CDS_PN = "1";
"2":   PN = "2"  !CDS_PN = "2";
BODY = "Q_CAP_DIFFBUS","I368": LOCATION = "C816" #&CDS_LOCATION = "C816" &SEC = "1" #&CDS_SEC = "1";
"1":   PN = "1"  !CDS_PN = "1";
"2":   PN = "2"  !CDS_PN = "2";
BODY = "Q_CAP_DIFFBUS","I369": LOCATION = "C815" #&CDS_LOCATION = "C815" &SEC = "1" #&CDS_SEC = "1";
"1":   PN = "1"  !CDS_PN = "1";
"2":   PN = "2"  !CDS_PN = "2";
BODY = "Q_CAP_DIFFBUS","I370": LOCATION = "C814" #&CDS_LOCATION = "C814" &SEC = "1" #&CDS_SEC = "1";
"1":   PN = "1"  !CDS_PN = "1";
"2":   PN = "2"  !CDS_PN = "2";
BODY = "Q_CAP_DIFFBUS","I371": LOCATION = "C812" #&CDS_LOCATION = "C812" &SEC = "1" #&CDS_SEC = "1";
"1":   PN = "1"  !CDS_PN = "1";
"2":   PN = "2"  !CDS_PN = "2";
BODY = "Q_CAP_DIFFBUS","I372": LOCATION = "C813" #&CDS_LOCATION = "C813" &SEC = "1" #&CDS_SEC = "1";
"1":   PN = "1"  !CDS_PN = "1";
"2":   PN = "2"  !CDS_PN = "2";
BODY = "Q_CAP_DIFFBUS","I373": LOCATION = "C811" #&CDS_LOCATION = "C811" &SEC = "1" #&CDS_SEC = "1";
"1":   PN = "1"  !CDS_PN = "1";
"2":   PN = "2"  !CDS_PN = "2";
BODY = "Q_CAP_DIFFBUS","I374": LOCATION = "C810" #&CDS_LOCATION = "C810" &SEC = "1" #&CDS_SEC = "1";
"1":   PN = "1"  !CDS_PN = "1";
"2":   PN = "2"  !CDS_PN = "2";
BODY = "Q_CAP_DIFFBUS","I375": LOCATION = "C809" #&CDS_LOCATION = "C809" &SEC = "1" #&CDS_SEC = "1";
"1":   PN = "1"  !CDS_PN = "1";
"2":   PN = "2"  !CDS_PN = "2";
BODY = "Q_CAP_DIFFBUS","I376": LOCATION = "C808" #&CDS_LOCATION = "C808" &SEC = "1" #&CDS_SEC = "1";
"1":   PN = "1"  !CDS_PN = "1";
"2":   PN = "2"  !CDS_PN = "2";
BODY = "Q_CAP_DIFFBUS","I377": LOCATION = "C806" #&CDS_LOCATION = "C806" &SEC = "1" #&CDS_SEC = "1";
"1":   PN = "1"  !CDS_PN = "1";
"2":   PN = "2"  !CDS_PN = "2";
BODY = "Q_CAP_DIFFBUS","I378": LOCATION = "C807" #&CDS_LOCATION = "C807" &SEC = "1" #&CDS_SEC = "1";
"1":   PN = "1"  !CDS_PN = "1";
"2":   PN = "2"  !CDS_PN = "2";
BODY = "Q_CAP_DIFFBUS","I415": LOCATION = "C825" #&CDS_LOCATION = "C825" &SEC = "1" #&CDS_SEC = "1";
"1":   PN = "1"  !CDS_PN = "1";
"2":   PN = "2"  !CDS_PN = "2";
BODY = "Q_CAP_DIFFBUS","I416": LOCATION = "C824" #&CDS_LOCATION = "C824" &SEC = "1" #&CDS_SEC = "1";
"1":   PN = "1"  !CDS_PN = "1";
"2":   PN = "2"  !CDS_PN = "2";
DRAWING = "@s9s_mb_2u_lib.s9s_mb_2u(sch_1):page167";
BODY = "Q_CAP_DIFFBUS","I122": LOCATION = "C773" #&CDS_LOCATION = "C773" &SEC = "1" #&CDS_SEC = "1";
"1":   PN = "1"  !CDS_PN = "1";
"2":   PN = "2"  !CDS_PN = "2";
BODY = "Q_CAP_DIFFBUS","I123": LOCATION = "C772" #&CDS_LOCATION = "C772" &SEC = "1" #&CDS_SEC = "1";
"1":   PN = "1"  !CDS_PN = "1";
"2":   PN = "2"  !CDS_PN = "2";
BODY = "Q_CAP_DIFFBUS","I124": LOCATION = "C771" #&CDS_LOCATION = "C771" &SEC = "1" #&CDS_SEC = "1";
"1":   PN = "1"  !CDS_PN = "1";
"2":   PN = "2"  !CDS_PN = "2";
BODY = "Q_CAP_DIFFBUS","I125": LOCATION = "C770" #&CDS_LOCATION = "C770" &SEC = "1" #&CDS_SEC = "1";
"1":   PN = "1"  !CDS_PN = "1";
"2":   PN = "2"  !CDS_PN = "2";
BODY = "Q_CAP_DIFFBUS","I126": LOCATION = "C769" #&CDS_LOCATION = "C769" &SEC = "1" #&CDS_SEC = "1";
"1":   PN = "1"  !CDS_PN = "1";
"2":   PN = "2"  !CDS_PN = "2";
BODY = "Q_CAP_DIFFBUS","I127": LOCATION = "C768" #&CDS_LOCATION = "C768" &SEC = "1" #&CDS_SEC = "1";
"1":   PN = "1"  !CDS_PN = "1";
"2":   PN = "2"  !CDS_PN = "2";
BODY = "Q_CAP_DIFFBUS","I128": LOCATION = "C767" #&CDS_LOCATION = "C767" &SEC = "1" #&CDS_SEC = "1";
"1":   PN = "1"  !CDS_PN = "1";
"2":   PN = "2"  !CDS_PN = "2";
BODY = "Q_CAP_DIFFBUS","I129": LOCATION = "C766" #&CDS_LOCATION = "C766" &SEC = "1" #&CDS_SEC = "1";
"1":   PN = "1"  !CDS_PN = "1";
"2":   PN = "2"  !CDS_PN = "2";
BODY = "Q_CAP_DIFFBUS","I130": LOCATION = "C764" #&CDS_LOCATION = "C764" &SEC = "1" #&CDS_SEC = "1";
"1":   PN = "1"  !CDS_PN = "1";
"2":   PN = "2"  !CDS_PN = "2";
BODY = "Q_CAP_DIFFBUS","I131": LOCATION = "C765" #&CDS_LOCATION = "C765" &SEC = "1" #&CDS_SEC = "1";
"1":   PN = "1"  !CDS_PN = "1";
"2":   PN = "2"  !CDS_PN = "2";
BODY = "Q_CAP_DIFFBUS","I135": LOCATION = "C763" #&CDS_LOCATION = "C763" &SEC = "1" #&CDS_SEC = "1";
"1":   PN = "1"  !CDS_PN = "1";
"2":   PN = "2"  !CDS_PN = "2";
BODY = "Q_CAP_DIFFBUS","I136": LOCATION = "C762" #&CDS_LOCATION = "C762" &SEC = "1" #&CDS_SEC = "1";
"1":   PN = "1"  !CDS_PN = "1";
"2":   PN = "2"  !CDS_PN = "2";
BODY = "Q_CAP_DIFFBUS","I137": LOCATION = "C761" #&CDS_LOCATION = "C761" &SEC = "1" #&CDS_SEC = "1";
"1":   PN = "1"  !CDS_PN = "1";
"2":   PN = "2"  !CDS_PN = "2";
BODY = "Q_CAP_DIFFBUS","I138": LOCATION = "C760" #&CDS_LOCATION = "C760" &SEC = "1" #&CDS_SEC = "1";
"1":   PN = "1"  !CDS_PN = "1";
"2":   PN = "2"  !CDS_PN = "2";
BODY = "Q_CAP_DIFFBUS","I139": LOCATION = "C759" #&CDS_LOCATION = "C759" &SEC = "1" #&CDS_SEC = "1";
"1":   PN = "1"  !CDS_PN = "1";
"2":   PN = "2"  !CDS_PN = "2";
BODY = "Q_CAP_DIFFBUS","I140": LOCATION = "C758" #&CDS_LOCATION = "C758" &SEC = "1" #&CDS_SEC = "1";
"1":   PN = "1"  !CDS_PN = "1";
"2":   PN = "2"  !CDS_PN = "2";
BODY = "Q_CAP_DIFFBUS","I154": LOCATION = "C756" #&CDS_LOCATION = "C756" &SEC = "1" #&CDS_SEC = "1";
"1":   PN = "1"  !CDS_PN = "1";
"2":   PN = "2"  !CDS_PN = "2";
BODY = "Q_CAP_DIFFBUS","I155": LOCATION = "C757" #&CDS_LOCATION = "C757" &SEC = "1" #&CDS_SEC = "1";
"1":   PN = "1"  !CDS_PN = "1";
"2":   PN = "2"  !CDS_PN = "2";
BODY = "Q_CAP_DIFFBUS","I156": LOCATION = "C755" #&CDS_LOCATION = "C755" &SEC = "1" #&CDS_SEC = "1";
"1":   PN = "1"  !CDS_PN = "1";
"2":   PN = "2"  !CDS_PN = "2";
BODY = "Q_CAP_DIFFBUS","I157": LOCATION = "C754" #&CDS_LOCATION = "C754" &SEC = "1" #&CDS_SEC = "1";
"1":   PN = "1"  !CDS_PN = "1";
"2":   PN = "2"  !CDS_PN = "2";
BODY = "Q_CAP_DIFFBUS","I158": LOCATION = "C753" #&CDS_LOCATION = "C753" &SEC = "1" #&CDS_SEC = "1";
"1":   PN = "1"  !CDS_PN = "1";
"2":   PN = "2"  !CDS_PN = "2";
BODY = "Q_CAP_DIFFBUS","I159": LOCATION = "C752" #&CDS_LOCATION = "C752" &SEC = "1" #&CDS_SEC = "1";
"1":   PN = "1"  !CDS_PN = "1";
"2":   PN = "2"  !CDS_PN = "2";
BODY = "Q_CAP_DIFFBUS","I160": LOCATION = "C750" #&CDS_LOCATION = "C750" &SEC = "1" #&CDS_SEC = "1";
"1":   PN = "1"  !CDS_PN = "1";
"2":   PN = "2"  !CDS_PN = "2";
BODY = "Q_CAP_DIFFBUS","I161": LOCATION = "C751" #&CDS_LOCATION = "C751" &SEC = "1" #&CDS_SEC = "1";
"1":   PN = "1"  !CDS_PN = "1";
"2":   PN = "2"  !CDS_PN = "2";
BODY = "Q_CAP_DIFFBUS","I162": LOCATION = "C749" #&CDS_LOCATION = "C749" &SEC = "1" #&CDS_SEC = "1";
"1":   PN = "1"  !CDS_PN = "1";
"2":   PN = "2"  !CDS_PN = "2";
BODY = "Q_CAP_DIFFBUS","I163": LOCATION = "C748" #&CDS_LOCATION = "C748" &SEC = "1" #&CDS_SEC = "1";
"1":   PN = "1"  !CDS_PN = "1";
"2":   PN = "2"  !CDS_PN = "2";
BODY = "Q_CAP_DIFFBUS","I167": LOCATION = "C747" #&CDS_LOCATION = "C747" &SEC = "1" #&CDS_SEC = "1";
"1":   PN = "1"  !CDS_PN = "1";
"2":   PN = "2"  !CDS_PN = "2";
BODY = "Q_CAP_DIFFBUS","I168": LOCATION = "C746" #&CDS_LOCATION = "C746" &SEC = "1" #&CDS_SEC = "1";
"1":   PN = "1"  !CDS_PN = "1";
"2":   PN = "2"  !CDS_PN = "2";
BODY = "Q_CAP_DIFFBUS","I169": LOCATION = "C745" #&CDS_LOCATION = "C745" &SEC = "1" #&CDS_SEC = "1";
"1":   PN = "1"  !CDS_PN = "1";
"2":   PN = "2"  !CDS_PN = "2";
BODY = "Q_CAP_DIFFBUS","I170": LOCATION = "C744" #&CDS_LOCATION = "C744" &SEC = "1" #&CDS_SEC = "1";
"1":   PN = "1"  !CDS_PN = "1";
"2":   PN = "2"  !CDS_PN = "2";
BODY = "Q_CAP_DIFFBUS","I171": LOCATION = "C743" #&CDS_LOCATION = "C743" &SEC = "1" #&CDS_SEC = "1";
"1":   PN = "1"  !CDS_PN = "1";
"2":   PN = "2"  !CDS_PN = "2";
BODY = "Q_CAP_DIFFBUS","I172": LOCATION = "C742" #&CDS_LOCATION = "C742" &SEC = "1" #&CDS_SEC = "1";
"1":   PN = "1"  !CDS_PN = "1";
"2":   PN = "2"  !CDS_PN = "2";
BODY = "Q_CAP_DIFFBUS","I229": LOCATION = "C740" #&CDS_LOCATION = "C740" &SEC = "1" #&CDS_SEC = "1";
"1":   PN = "1"  !CDS_PN = "1";
"2":   PN = "2"  !CDS_PN = "2";
BODY = "Q_CAP_DIFFBUS","I230": LOCATION = "C741" #&CDS_LOCATION = "C741" &SEC = "1" #&CDS_SEC = "1";
"1":   PN = "1"  !CDS_PN = "1";
"2":   PN = "2"  !CDS_PN = "2";
BODY = "Q_CAP_DIFFBUS","I231": LOCATION = "C739" #&CDS_LOCATION = "C739" &SEC = "1" #&CDS_SEC = "1";
"1":   PN = "1"  !CDS_PN = "1";
"2":   PN = "2"  !CDS_PN = "2";
BODY = "Q_CAP_DIFFBUS","I232": LOCATION = "C738" #&CDS_LOCATION = "C738" &SEC = "1" #&CDS_SEC = "1";
"1":   PN = "1"  !CDS_PN = "1";
"2":   PN = "2"  !CDS_PN = "2";
BODY = "Q_CAP_DIFFBUS","I233": LOCATION = "C737" #&CDS_LOCATION = "C737" &SEC = "1" #&CDS_SEC = "1";
"1":   PN = "1"  !CDS_PN = "1";
"2":   PN = "2"  !CDS_PN = "2";
BODY = "Q_CAP_DIFFBUS","I234": LOCATION = "C736" #&CDS_LOCATION = "C736" &SEC = "1" #&CDS_SEC = "1";
"1":   PN = "1"  !CDS_PN = "1";
"2":   PN = "2"  !CDS_PN = "2";
BODY = "Q_CAP_DIFFBUS","I235": LOCATION = "C734" #&CDS_LOCATION = "C734" &SEC = "1" #&CDS_SEC = "1";
"1":   PN = "1"  !CDS_PN = "1";
"2":   PN = "2"  !CDS_PN = "2";
BODY = "Q_CAP_DIFFBUS","I236": LOCATION = "C735" #&CDS_LOCATION = "C735" &SEC = "1" #&CDS_SEC = "1";
"1":   PN = "1"  !CDS_PN = "1";
"2":   PN = "2"  !CDS_PN = "2";
BODY = "Q_CAP_DIFFBUS","I237": LOCATION = "C733" #&CDS_LOCATION = "C733" &SEC = "1" #&CDS_SEC = "1";
"1":   PN = "1"  !CDS_PN = "1";
"2":   PN = "2"  !CDS_PN = "2";
BODY = "Q_CAP_DIFFBUS","I246": LOCATION = "C732" #&CDS_LOCATION = "C732" &SEC = "1" #&CDS_SEC = "1";
"1":   PN = "1"  !CDS_PN = "1";
"2":   PN = "2"  !CDS_PN = "2";
BODY = "Q_CAP_DIFFBUS","I247": LOCATION = "C731" #&CDS_LOCATION = "C731" &SEC = "1" #&CDS_SEC = "1";
"1":   PN = "1"  !CDS_PN = "1";
"2":   PN = "2"  !CDS_PN = "2";
BODY = "Q_CAP_DIFFBUS","I248": LOCATION = "C730" #&CDS_LOCATION = "C730" &SEC = "1" #&CDS_SEC = "1";
"1":   PN = "1"  !CDS_PN = "1";
"2":   PN = "2"  !CDS_PN = "2";
BODY = "Q_CAP_DIFFBUS","I249": LOCATION = "C729" #&CDS_LOCATION = "C729" &SEC = "1" #&CDS_SEC = "1";
"1":   PN = "1"  !CDS_PN = "1";
"2":   PN = "2"  !CDS_PN = "2";
BODY = "Q_CAP_DIFFBUS","I250": LOCATION = "C728" #&CDS_LOCATION = "C728" &SEC = "1" #&CDS_SEC = "1";
"1":   PN = "1"  !CDS_PN = "1";
"2":   PN = "2"  !CDS_PN = "2";
BODY = "Q_CAP_DIFFBUS","I251": LOCATION = "C727" #&CDS_LOCATION = "C727" &SEC = "1" #&CDS_SEC = "1";
"1":   PN = "1"  !CDS_PN = "1";
"2":   PN = "2"  !CDS_PN = "2";
BODY = "Q_CAP_DIFFBUS","I274": LOCATION = "C725" #&CDS_LOCATION = "C725" &SEC = "1" #&CDS_SEC = "1";
"1":   PN = "1"  !CDS_PN = "1";
"2":   PN = "2"  !CDS_PN = "2";
BODY = "Q_CAP_DIFFBUS","I275": LOCATION = "C724" #&CDS_LOCATION = "C724" &SEC = "1" #&CDS_SEC = "1";
"1":   PN = "1"  !CDS_PN = "1";
"2":   PN = "2"  !CDS_PN = "2";
BODY = "Q_CAP_DIFFBUS","I276": LOCATION = "C722" #&CDS_LOCATION = "C722" &SEC = "1" #&CDS_SEC = "1";
"1":   PN = "1"  !CDS_PN = "1";
"2":   PN = "2"  !CDS_PN = "2";
BODY = "Q_CAP_DIFFBUS","I277": LOCATION = "C723" #&CDS_LOCATION = "C723" &SEC = "1" #&CDS_SEC = "1";
"1":   PN = "1"  !CDS_PN = "1";
"2":   PN = "2"  !CDS_PN = "2";
BODY = "Q_CAP_DIFFBUS","I278": LOCATION = "C721" #&CDS_LOCATION = "C721" &SEC = "1" #&CDS_SEC = "1";
"1":   PN = "1"  !CDS_PN = "1";
"2":   PN = "2"  !CDS_PN = "2";
BODY = "Q_CAP_DIFFBUS","I279": LOCATION = "C720" #&CDS_LOCATION = "C720" &SEC = "1" #&CDS_SEC = "1";
"1":   PN = "1"  !CDS_PN = "1";
"2":   PN = "2"  !CDS_PN = "2";
BODY = "Q_CAP_DIFFBUS","I280": LOCATION = "C719" #&CDS_LOCATION = "C719" &SEC = "1" #&CDS_SEC = "1";
"1":   PN = "1"  !CDS_PN = "1";
"2":   PN = "2"  !CDS_PN = "2";
BODY = "Q_CAP_DIFFBUS","I281": LOCATION = "C718" #&CDS_LOCATION = "C718" &SEC = "1" #&CDS_SEC = "1";
"1":   PN = "1"  !CDS_PN = "1";
"2":   PN = "2"  !CDS_PN = "2";
BODY = "Q_CAP_DIFFBUS","I282": LOCATION = "C717" #&CDS_LOCATION = "C717" &SEC = "1" #&CDS_SEC = "1";
"1":   PN = "1"  !CDS_PN = "1";
"2":   PN = "2"  !CDS_PN = "2";
BODY = "Q_CAP_DIFFBUS","I283": LOCATION = "C716" #&CDS_LOCATION = "C716" &SEC = "1" #&CDS_SEC = "1";
"1":   PN = "1"  !CDS_PN = "1";
"2":   PN = "2"  !CDS_PN = "2";
BODY = "Q_CAP_DIFFBUS","I294": LOCATION = "C715" #&CDS_LOCATION = "C715" &SEC = "1" #&CDS_SEC = "1";
"1":   PN = "1"  !CDS_PN = "1";
"2":   PN = "2"  !CDS_PN = "2";
BODY = "Q_CAP_DIFFBUS","I295": LOCATION = "C714" #&CDS_LOCATION = "C714" &SEC = "1" #&CDS_SEC = "1";
"1":   PN = "1"  !CDS_PN = "1";
"2":   PN = "2"  !CDS_PN = "2";
BODY = "Q_CAP_DIFFBUS","I296": LOCATION = "C712" #&CDS_LOCATION = "C712" &SEC = "1" #&CDS_SEC = "1";
"1":   PN = "1"  !CDS_PN = "1";
"2":   PN = "2"  !CDS_PN = "2";
BODY = "Q_CAP_DIFFBUS","I297": LOCATION = "C713" #&CDS_LOCATION = "C713" &SEC = "1" #&CDS_SEC = "1";
"1":   PN = "1"  !CDS_PN = "1";
"2":   PN = "2"  !CDS_PN = "2";
BODY = "Q_CAP_DIFFBUS","I298": LOCATION = "C711" #&CDS_LOCATION = "C711" &SEC = "1" #&CDS_SEC = "1";
"1":   PN = "1"  !CDS_PN = "1";
"2":   PN = "2"  !CDS_PN = "2";
BODY = "Q_CAP_DIFFBUS","I299": LOCATION = "C710" #&CDS_LOCATION = "C710" &SEC = "1" #&CDS_SEC = "1";
"1":   PN = "1"  !CDS_PN = "1";
"2":   PN = "2"  !CDS_PN = "2";
BODY = "Q_CAP_DIFFBUS","I312": LOCATION = "C726" #&CDS_LOCATION = "C726" &SEC = "1" #&CDS_SEC = "1";
"1":   PN = "1"  !CDS_PN = "1";
"2":   PN = "2"  !CDS_PN = "2";
DRAWING = "@s9s_mb_2u_lib.s9s_mb_2u(sch_1):page168";
BODY = "Q_CAP_DIFFBUS","I125": LOCATION = "C708" #&CDS_LOCATION = "C708" &SEC = "1" #&CDS_SEC = "1";
"1":   PN = "1"  !CDS_PN = "1";
"2":   PN = "2"  !CDS_PN = "2";
BODY = "Q_CAP_DIFFBUS","I126": LOCATION = "C709" #&CDS_LOCATION = "C709" &SEC = "1" #&CDS_SEC = "1";
"1":   PN = "1"  !CDS_PN = "1";
"2":   PN = "2"  !CDS_PN = "2";
BODY = "Q_CAP_DIFFBUS","I127": LOCATION = "C706" #&CDS_LOCATION = "C706" &SEC = "1" #&CDS_SEC = "1";
"1":   PN = "1"  !CDS_PN = "1";
"2":   PN = "2"  !CDS_PN = "2";
BODY = "Q_CAP_DIFFBUS","I128": LOCATION = "C707" #&CDS_LOCATION = "C707" &SEC = "1" #&CDS_SEC = "1";
"1":   PN = "1"  !CDS_PN = "1";
"2":   PN = "2"  !CDS_PN = "2";
BODY = "Q_CAP_DIFFBUS","I129": LOCATION = "C704" #&CDS_LOCATION = "C704" &SEC = "1" #&CDS_SEC = "1";
"1":   PN = "1"  !CDS_PN = "1";
"2":   PN = "2"  !CDS_PN = "2";
BODY = "Q_CAP_DIFFBUS","I130": LOCATION = "C705" #&CDS_LOCATION = "C705" &SEC = "1" #&CDS_SEC = "1";
"1":   PN = "1"  !CDS_PN = "1";
"2":   PN = "2"  !CDS_PN = "2";
BODY = "Q_CAP_DIFFBUS","I131": LOCATION = "C701" #&CDS_LOCATION = "C701" &SEC = "1" #&CDS_SEC = "1";
"1":   PN = "1"  !CDS_PN = "1";
"2":   PN = "2"  !CDS_PN = "2";
BODY = "Q_CAP_DIFFBUS","I132": LOCATION = "C702" #&CDS_LOCATION = "C702" &SEC = "1" #&CDS_SEC = "1";
"1":   PN = "1"  !CDS_PN = "1";
"2":   PN = "2"  !CDS_PN = "2";
BODY = "Q_CAP_DIFFBUS","I133": LOCATION = "C703" #&CDS_LOCATION = "C703" &SEC = "1" #&CDS_SEC = "1";
"1":   PN = "1"  !CDS_PN = "1";
"2":   PN = "2"  !CDS_PN = "2";
BODY = "Q_CAP_DIFFBUS","I134": LOCATION = "C700" #&CDS_LOCATION = "C700" &SEC = "1" #&CDS_SEC = "1";
"1":   PN = "1"  !CDS_PN = "1";
"2":   PN = "2"  !CDS_PN = "2";
BODY = "Q_CAP_DIFFBUS","I135": LOCATION = "C698" #&CDS_LOCATION = "C698" &SEC = "1" #&CDS_SEC = "1";
"1":   PN = "1"  !CDS_PN = "1";
"2":   PN = "2"  !CDS_PN = "2";
BODY = "Q_CAP_DIFFBUS","I136": LOCATION = "C699" #&CDS_LOCATION = "C699" &SEC = "1" #&CDS_SEC = "1";
"1":   PN = "1"  !CDS_PN = "1";
"2":   PN = "2"  !CDS_PN = "2";
BODY = "Q_CAP_DIFFBUS","I137": LOCATION = "C696" #&CDS_LOCATION = "C696" &SEC = "1" #&CDS_SEC = "1";
"1":   PN = "1"  !CDS_PN = "1";
"2":   PN = "2"  !CDS_PN = "2";
BODY = "Q_CAP_DIFFBUS","I138": LOCATION = "C697" #&CDS_LOCATION = "C697" &SEC = "1" #&CDS_SEC = "1";
"1":   PN = "1"  !CDS_PN = "1";
"2":   PN = "2"  !CDS_PN = "2";
BODY = "Q_CAP_DIFFBUS","I139": LOCATION = "C695" #&CDS_LOCATION = "C695" &SEC = "1" #&CDS_SEC = "1";
"1":   PN = "1"  !CDS_PN = "1";
"2":   PN = "2"  !CDS_PN = "2";
BODY = "Q_CAP_DIFFBUS","I140": LOCATION = "C694" #&CDS_LOCATION = "C694" &SEC = "1" #&CDS_SEC = "1";
"1":   PN = "1"  !CDS_PN = "1";
"2":   PN = "2"  !CDS_PN = "2";
BODY = "Q_CAP_DIFFBUS","I157": LOCATION = "C693" #&CDS_LOCATION = "C693" &SEC = "1" #&CDS_SEC = "1";
"1":   PN = "1"  !CDS_PN = "1";
"2":   PN = "2"  !CDS_PN = "2";
BODY = "Q_CAP_DIFFBUS","I158": LOCATION = "C692" #&CDS_LOCATION = "C692" &SEC = "1" #&CDS_SEC = "1";
"1":   PN = "1"  !CDS_PN = "1";
"2":   PN = "2"  !CDS_PN = "2";
BODY = "Q_CAP_DIFFBUS","I159": LOCATION = "C690" #&CDS_LOCATION = "C690" &SEC = "1" #&CDS_SEC = "1";
"1":   PN = "1"  !CDS_PN = "1";
"2":   PN = "2"  !CDS_PN = "2";
BODY = "Q_CAP_DIFFBUS","I160": LOCATION = "C691" #&CDS_LOCATION = "C691" &SEC = "1" #&CDS_SEC = "1";
"1":   PN = "1"  !CDS_PN = "1";
"2":   PN = "2"  !CDS_PN = "2";
BODY = "Q_CAP_DIFFBUS","I161": LOCATION = "C687" #&CDS_LOCATION = "C687" &SEC = "1" #&CDS_SEC = "1";
"1":   PN = "1"  !CDS_PN = "1";
"2":   PN = "2"  !CDS_PN = "2";
BODY = "Q_CAP_DIFFBUS","I162": LOCATION = "C688" #&CDS_LOCATION = "C688" &SEC = "1" #&CDS_SEC = "1";
"1":   PN = "1"  !CDS_PN = "1";
"2":   PN = "2"  !CDS_PN = "2";
BODY = "Q_CAP_DIFFBUS","I163": LOCATION = "C689" #&CDS_LOCATION = "C689" &SEC = "1" #&CDS_SEC = "1";
"1":   PN = "1"  !CDS_PN = "1";
"2":   PN = "2"  !CDS_PN = "2";
BODY = "Q_CAP_DIFFBUS","I164": LOCATION = "C686" #&CDS_LOCATION = "C686" &SEC = "1" #&CDS_SEC = "1";
"1":   PN = "1"  !CDS_PN = "1";
"2":   PN = "2"  !CDS_PN = "2";
BODY = "Q_CAP_DIFFBUS","I165": LOCATION = "C685" #&CDS_LOCATION = "C685" &SEC = "1" #&CDS_SEC = "1";
"1":   PN = "1"  !CDS_PN = "1";
"2":   PN = "2"  !CDS_PN = "2";
BODY = "Q_CAP_DIFFBUS","I166": LOCATION = "C684" #&CDS_LOCATION = "C684" &SEC = "1" #&CDS_SEC = "1";
"1":   PN = "1"  !CDS_PN = "1";
"2":   PN = "2"  !CDS_PN = "2";
BODY = "Q_CAP_DIFFBUS","I167": LOCATION = "C682" #&CDS_LOCATION = "C682" &SEC = "1" #&CDS_SEC = "1";
"1":   PN = "1"  !CDS_PN = "1";
"2":   PN = "2"  !CDS_PN = "2";
BODY = "Q_CAP_DIFFBUS","I168": LOCATION = "C683" #&CDS_LOCATION = "C683" &SEC = "1" #&CDS_SEC = "1";
"1":   PN = "1"  !CDS_PN = "1";
"2":   PN = "2"  !CDS_PN = "2";
BODY = "Q_CAP_DIFFBUS","I169": LOCATION = "C679" #&CDS_LOCATION = "C679" &SEC = "1" #&CDS_SEC = "1";
"1":   PN = "1"  !CDS_PN = "1";
"2":   PN = "2"  !CDS_PN = "2";
BODY = "Q_CAP_DIFFBUS","I170": LOCATION = "C680" #&CDS_LOCATION = "C680" &SEC = "1" #&CDS_SEC = "1";
"1":   PN = "1"  !CDS_PN = "1";
"2":   PN = "2"  !CDS_PN = "2";
BODY = "Q_CAP_DIFFBUS","I171": LOCATION = "C681" #&CDS_LOCATION = "C681" &SEC = "1" #&CDS_SEC = "1";
"1":   PN = "1"  !CDS_PN = "1";
"2":   PN = "2"  !CDS_PN = "2";
BODY = "Q_CAP_DIFFBUS","I172": LOCATION = "C678" #&CDS_LOCATION = "C678" &SEC = "1" #&CDS_SEC = "1";
"1":   PN = "1"  !CDS_PN = "1";
"2":   PN = "2"  !CDS_PN = "2";
BODY = "Q_CAP_DIFFBUS","I229": LOCATION = "C1547" #&CDS_LOCATION = "C1547" &SEC = "1" #&CDS_SEC = "1";
"1":   PN = "1"  !CDS_PN = "1";
"2":   PN = "2"  !CDS_PN = "2";
BODY = "Q_CAP_DIFFBUS","I230": LOCATION = "C1546" #&CDS_LOCATION = "C1546" &SEC = "1" #&CDS_SEC = "1";
"1":   PN = "1"  !CDS_PN = "1";
"2":   PN = "2"  !CDS_PN = "2";
BODY = "Q_CAP_DIFFBUS","I231": LOCATION = "C1545" #&CDS_LOCATION = "C1545" &SEC = "1" #&CDS_SEC = "1";
"1":   PN = "1"  !CDS_PN = "1";
"2":   PN = "2"  !CDS_PN = "2";
BODY = "Q_CAP_DIFFBUS","I232": LOCATION = "C1544" #&CDS_LOCATION = "C1544" &SEC = "1" #&CDS_SEC = "1";
"1":   PN = "1"  !CDS_PN = "1";
"2":   PN = "2"  !CDS_PN = "2";
BODY = "Q_CAP_DIFFBUS","I233": LOCATION = "C1542" #&CDS_LOCATION = "C1542" &SEC = "1" #&CDS_SEC = "1";
"1":   PN = "1"  !CDS_PN = "1";
"2":   PN = "2"  !CDS_PN = "2";
BODY = "Q_CAP_DIFFBUS","I234": LOCATION = "C1543" #&CDS_LOCATION = "C1543" &SEC = "1" #&CDS_SEC = "1";
"1":   PN = "1"  !CDS_PN = "1";
"2":   PN = "2"  !CDS_PN = "2";
BODY = "Q_CAP_DIFFBUS","I235": LOCATION = "C1541" #&CDS_LOCATION = "C1541" &SEC = "1" #&CDS_SEC = "1";
"1":   PN = "1"  !CDS_PN = "1";
"2":   PN = "2"  !CDS_PN = "2";
BODY = "Q_CAP_DIFFBUS","I236": LOCATION = "C1540" #&CDS_LOCATION = "C1540" &SEC = "1" #&CDS_SEC = "1";
"1":   PN = "1"  !CDS_PN = "1";
"2":   PN = "2"  !CDS_PN = "2";
BODY = "Q_CAP_DIFFBUS","I237": LOCATION = "C1539" #&CDS_LOCATION = "C1539" &SEC = "1" #&CDS_SEC = "1";
"1":   PN = "1"  !CDS_PN = "1";
"2":   PN = "2"  !CDS_PN = "2";
BODY = "Q_CAP_DIFFBUS","I238": LOCATION = "C1538" #&CDS_LOCATION = "C1538" &SEC = "1" #&CDS_SEC = "1";
"1":   PN = "1"  !CDS_PN = "1";
"2":   PN = "2"  !CDS_PN = "2";
BODY = "Q_CAP_DIFFBUS","I249": LOCATION = "C1537" #&CDS_LOCATION = "C1537" &SEC = "1" #&CDS_SEC = "1";
"1":   PN = "1"  !CDS_PN = "1";
"2":   PN = "2"  !CDS_PN = "2";
BODY = "Q_CAP_DIFFBUS","I250": LOCATION = "C1536" #&CDS_LOCATION = "C1536" &SEC = "1" #&CDS_SEC = "1";
"1":   PN = "1"  !CDS_PN = "1";
"2":   PN = "2"  !CDS_PN = "2";
BODY = "Q_CAP_DIFFBUS","I251": LOCATION = "C1534" #&CDS_LOCATION = "C1534" &SEC = "1" #&CDS_SEC = "1";
"1":   PN = "1"  !CDS_PN = "1";
"2":   PN = "2"  !CDS_PN = "2";
BODY = "Q_CAP_DIFFBUS","I252": LOCATION = "C1535" #&CDS_LOCATION = "C1535" &SEC = "1" #&CDS_SEC = "1";
"1":   PN = "1"  !CDS_PN = "1";
"2":   PN = "2"  !CDS_PN = "2";
BODY = "Q_CAP_DIFFBUS","I253": LOCATION = "C1533" #&CDS_LOCATION = "C1533" &SEC = "1" #&CDS_SEC = "1";
"1":   PN = "1"  !CDS_PN = "1";
"2":   PN = "2"  !CDS_PN = "2";
BODY = "Q_CAP_DIFFBUS","I254": LOCATION = "C1532" #&CDS_LOCATION = "C1532" &SEC = "1" #&CDS_SEC = "1";
"1":   PN = "1"  !CDS_PN = "1";
"2":   PN = "2"  !CDS_PN = "2";
BODY = "Q_CAP_DIFFBUS","I277": LOCATION = "C1530" #&CDS_LOCATION = "C1530" &SEC = "1" #&CDS_SEC = "1";
"1":   PN = "1"  !CDS_PN = "1";
"2":   PN = "2"  !CDS_PN = "2";
BODY = "Q_CAP_DIFFBUS","I278": LOCATION = "C1531" #&CDS_LOCATION = "C1531" &SEC = "1" #&CDS_SEC = "1";
"1":   PN = "1"  !CDS_PN = "1";
"2":   PN = "2"  !CDS_PN = "2";
BODY = "Q_CAP_DIFFBUS","I279": LOCATION = "C1529" #&CDS_LOCATION = "C1529" &SEC = "1" #&CDS_SEC = "1";
"1":   PN = "1"  !CDS_PN = "1";
"2":   PN = "2"  !CDS_PN = "2";
BODY = "Q_CAP_DIFFBUS","I280": LOCATION = "C1528" #&CDS_LOCATION = "C1528" &SEC = "1" #&CDS_SEC = "1";
"1":   PN = "1"  !CDS_PN = "1";
"2":   PN = "2"  !CDS_PN = "2";
BODY = "Q_CAP_DIFFBUS","I281": LOCATION = "C1527" #&CDS_LOCATION = "C1527" &SEC = "1" #&CDS_SEC = "1";
"1":   PN = "1"  !CDS_PN = "1";
"2":   PN = "2"  !CDS_PN = "2";
BODY = "Q_CAP_DIFFBUS","I282": LOCATION = "C1526" #&CDS_LOCATION = "C1526" &SEC = "1" #&CDS_SEC = "1";
"1":   PN = "1"  !CDS_PN = "1";
"2":   PN = "2"  !CDS_PN = "2";
BODY = "Q_CAP_DIFFBUS","I283": LOCATION = "C1525" #&CDS_LOCATION = "C1525" &SEC = "1" #&CDS_SEC = "1";
"1":   PN = "1"  !CDS_PN = "1";
"2":   PN = "2"  !CDS_PN = "2";
BODY = "Q_CAP_DIFFBUS","I284": LOCATION = "C1524" #&CDS_LOCATION = "C1524" &SEC = "1" #&CDS_SEC = "1";
"1":   PN = "1"  !CDS_PN = "1";
"2":   PN = "2"  !CDS_PN = "2";
BODY = "Q_CAP_DIFFBUS","I285": LOCATION = "C1523" #&CDS_LOCATION = "C1523" &SEC = "1" #&CDS_SEC = "1";
"1":   PN = "1"  !CDS_PN = "1";
"2":   PN = "2"  !CDS_PN = "2";
BODY = "Q_CAP_DIFFBUS","I286": LOCATION = "C1522" #&CDS_LOCATION = "C1522" &SEC = "1" #&CDS_SEC = "1";
"1":   PN = "1"  !CDS_PN = "1";
"2":   PN = "2"  !CDS_PN = "2";
BODY = "Q_CAP_DIFFBUS","I297": LOCATION = "C1520" #&CDS_LOCATION = "C1520" &SEC = "1" #&CDS_SEC = "1";
"1":   PN = "1"  !CDS_PN = "1";
"2":   PN = "2"  !CDS_PN = "2";
BODY = "Q_CAP_DIFFBUS","I298": LOCATION = "C1521" #&CDS_LOCATION = "C1521" &SEC = "1" #&CDS_SEC = "1";
"1":   PN = "1"  !CDS_PN = "1";
"2":   PN = "2"  !CDS_PN = "2";
BODY = "Q_CAP_DIFFBUS","I299": LOCATION = "C1519" #&CDS_LOCATION = "C1519" &SEC = "1" #&CDS_SEC = "1";
"1":   PN = "1"  !CDS_PN = "1";
"2":   PN = "2"  !CDS_PN = "2";
BODY = "Q_CAP_DIFFBUS","I300": LOCATION = "C1518" #&CDS_LOCATION = "C1518" &SEC = "1" #&CDS_SEC = "1";
"1":   PN = "1"  !CDS_PN = "1";
"2":   PN = "2"  !CDS_PN = "2";
BODY = "Q_CAP_DIFFBUS","I301": LOCATION = "C1517" #&CDS_LOCATION = "C1517" &SEC = "1" #&CDS_SEC = "1";
"1":   PN = "1"  !CDS_PN = "1";
"2":   PN = "2"  !CDS_PN = "2";
BODY = "Q_CAP_DIFFBUS","I302": LOCATION = "C1516" #&CDS_LOCATION = "C1516" &SEC = "1" #&CDS_SEC = "1";
"1":   PN = "1"  !CDS_PN = "1";
"2":   PN = "2"  !CDS_PN = "2";
DRAWING = "@s9s_mb_2u_lib.s9s_mb_2u(sch_1):page169";
BODY = "Q_CAP_DIFFBUS","I21": LOCATION = "C153" #&CDS_LOCATION = "C153" &SEC = "1" #&CDS_SEC = "1";
"1":   PN = "1"  !CDS_PN = "1";
"2":   PN = "2"  !CDS_PN = "2";
BODY = "Q_CAP_DIFFBUS","I22": LOCATION = "C154" #&CDS_LOCATION = "C154" &SEC = "1" #&CDS_SEC = "1";
"1":   PN = "1"  !CDS_PN = "1";
"2":   PN = "2"  !CDS_PN = "2";
BODY = "Q_CAP_DIFFBUS","I23": LOCATION = "C152" #&CDS_LOCATION = "C152" &SEC = "1" #&CDS_SEC = "1";
"1":   PN = "1"  !CDS_PN = "1";
"2":   PN = "2"  !CDS_PN = "2";
BODY = "Q_CAP_DIFFBUS","I24": LOCATION = "C151" #&CDS_LOCATION = "C151" &SEC = "1" #&CDS_SEC = "1";
"1":   PN = "1"  !CDS_PN = "1";
"2":   PN = "2"  !CDS_PN = "2";
BODY = "Q_CAP_DIFFBUS","I25": LOCATION = "C149" #&CDS_LOCATION = "C149" &SEC = "1" #&CDS_SEC = "1";
"1":   PN = "1"  !CDS_PN = "1";
"2":   PN = "2"  !CDS_PN = "2";
BODY = "Q_CAP_DIFFBUS","I26": LOCATION = "C150" #&CDS_LOCATION = "C150" &SEC = "1" #&CDS_SEC = "1";
"1":   PN = "1"  !CDS_PN = "1";
"2":   PN = "2"  !CDS_PN = "2";
BODY = "Q_CAP_DIFFBUS","I27": LOCATION = "C148" #&CDS_LOCATION = "C148" &SEC = "1" #&CDS_SEC = "1";
"1":   PN = "1"  !CDS_PN = "1";
"2":   PN = "2"  !CDS_PN = "2";
BODY = "Q_CAP_DIFFBUS","I28": LOCATION = "C147" #&CDS_LOCATION = "C147" &SEC = "1" #&CDS_SEC = "1";
"1":   PN = "1"  !CDS_PN = "1";
"2":   PN = "2"  !CDS_PN = "2";
BODY = "Q_CAP_DIFFBUS","I29": LOCATION = "C146" #&CDS_LOCATION = "C146" &SEC = "1" #&CDS_SEC = "1";
"1":   PN = "1"  !CDS_PN = "1";
"2":   PN = "2"  !CDS_PN = "2";
BODY = "Q_CAP_DIFFBUS","I30": LOCATION = "C145" #&CDS_LOCATION = "C145" &SEC = "1" #&CDS_SEC = "1";
"1":   PN = "1"  !CDS_PN = "1";
"2":   PN = "2"  !CDS_PN = "2";
BODY = "Q_CAP_DIFFBUS","I31": LOCATION = "C144" #&CDS_LOCATION = "C144" &SEC = "1" #&CDS_SEC = "1";
"1":   PN = "1"  !CDS_PN = "1";
"2":   PN = "2"  !CDS_PN = "2";
BODY = "Q_CAP_DIFFBUS","I32": LOCATION = "C143" #&CDS_LOCATION = "C143" &SEC = "1" #&CDS_SEC = "1";
"1":   PN = "1"  !CDS_PN = "1";
"2":   PN = "2"  !CDS_PN = "2";
BODY = "Q_CAP_DIFFBUS","I33": LOCATION = "C142" #&CDS_LOCATION = "C142" &SEC = "1" #&CDS_SEC = "1";
"1":   PN = "1"  !CDS_PN = "1";
"2":   PN = "2"  !CDS_PN = "2";
BODY = "Q_CAP_DIFFBUS","I34": LOCATION = "C141" #&CDS_LOCATION = "C141" &SEC = "1" #&CDS_SEC = "1";
"1":   PN = "1"  !CDS_PN = "1";
"2":   PN = "2"  !CDS_PN = "2";
BODY = "Q_CAP_DIFFBUS","I35": LOCATION = "C139" #&CDS_LOCATION = "C139" &SEC = "1" #&CDS_SEC = "1";
"1":   PN = "1"  !CDS_PN = "1";
"2":   PN = "2"  !CDS_PN = "2";
BODY = "Q_CAP_DIFFBUS","I36": LOCATION = "C1791" #&CDS_LOCATION = "C1791" &SEC = "1" #&CDS_SEC = "1";
"1":   PN = "1"  !CDS_PN = "1";
"2":   PN = "2"  !CDS_PN = "2";
BODY = "Q_CAP_DIFFBUS","I113": LOCATION = "C155" #&CDS_LOCATION = "C155" &SEC = "1" #&CDS_SEC = "1";
"1":   PN = "1"  !CDS_PN = "1";
"2":   PN = "2"  !CDS_PN = "2";
BODY = "Q_CAP_DIFFBUS","I114": LOCATION = "C156" #&CDS_LOCATION = "C156" &SEC = "1" #&CDS_SEC = "1";
"1":   PN = "1"  !CDS_PN = "1";
"2":   PN = "2"  !CDS_PN = "2";
BODY = "Q_CAP_DIFFBUS","I115": LOCATION = "C157" #&CDS_LOCATION = "C157" &SEC = "1" #&CDS_SEC = "1";
"1":   PN = "1"  !CDS_PN = "1";
"2":   PN = "2"  !CDS_PN = "2";
BODY = "Q_CAP_DIFFBUS","I116": LOCATION = "C158" #&CDS_LOCATION = "C158" &SEC = "1" #&CDS_SEC = "1";
"1":   PN = "1"  !CDS_PN = "1";
"2":   PN = "2"  !CDS_PN = "2";
BODY = "Q_CAP_DIFFBUS","I117": LOCATION = "C159" #&CDS_LOCATION = "C159" &SEC = "1" #&CDS_SEC = "1";
"1":   PN = "1"  !CDS_PN = "1";
"2":   PN = "2"  !CDS_PN = "2";
BODY = "Q_CAP_DIFFBUS","I118": LOCATION = "C160" #&CDS_LOCATION = "C160" &SEC = "1" #&CDS_SEC = "1";
"1":   PN = "1"  !CDS_PN = "1";
"2":   PN = "2"  !CDS_PN = "2";
BODY = "Q_CAP_DIFFBUS","I119": LOCATION = "C161" #&CDS_LOCATION = "C161" &SEC = "1" #&CDS_SEC = "1";
"1":   PN = "1"  !CDS_PN = "1";
"2":   PN = "2"  !CDS_PN = "2";
BODY = "Q_CAP_DIFFBUS","I120": LOCATION = "C162" #&CDS_LOCATION = "C162" &SEC = "1" #&CDS_SEC = "1";
"1":   PN = "1"  !CDS_PN = "1";
"2":   PN = "2"  !CDS_PN = "2";
BODY = "Q_CAP_DIFFBUS","I121": LOCATION = "C163" #&CDS_LOCATION = "C163" &SEC = "1" #&CDS_SEC = "1";
"1":   PN = "1"  !CDS_PN = "1";
"2":   PN = "2"  !CDS_PN = "2";
BODY = "Q_CAP_DIFFBUS","I122": LOCATION = "C164" #&CDS_LOCATION = "C164" &SEC = "1" #&CDS_SEC = "1";
"1":   PN = "1"  !CDS_PN = "1";
"2":   PN = "2"  !CDS_PN = "2";
BODY = "Q_CAP_DIFFBUS","I123": LOCATION = "C165" #&CDS_LOCATION = "C165" &SEC = "1" #&CDS_SEC = "1";
"1":   PN = "1"  !CDS_PN = "1";
"2":   PN = "2"  !CDS_PN = "2";
BODY = "Q_CAP_DIFFBUS","I124": LOCATION = "C166" #&CDS_LOCATION = "C166" &SEC = "1" #&CDS_SEC = "1";
"1":   PN = "1"  !CDS_PN = "1";
"2":   PN = "2"  !CDS_PN = "2";
BODY = "Q_CAP_DIFFBUS","I125": LOCATION = "C168" #&CDS_LOCATION = "C168" &SEC = "1" #&CDS_SEC = "1";
"1":   PN = "1"  !CDS_PN = "1";
"2":   PN = "2"  !CDS_PN = "2";
BODY = "Q_CAP_DIFFBUS","I126": LOCATION = "C167" #&CDS_LOCATION = "C167" &SEC = "1" #&CDS_SEC = "1";
"1":   PN = "1"  !CDS_PN = "1";
"2":   PN = "2"  !CDS_PN = "2";
BODY = "Q_CAP_DIFFBUS","I127": LOCATION = "C169" #&CDS_LOCATION = "C169" &SEC = "1" #&CDS_SEC = "1";
"1":   PN = "1"  !CDS_PN = "1";
"2":   PN = "2"  !CDS_PN = "2";
BODY = "Q_CAP_DIFFBUS","I128": LOCATION = "C170" #&CDS_LOCATION = "C170" &SEC = "1" #&CDS_SEC = "1";
"1":   PN = "1"  !CDS_PN = "1";
"2":   PN = "2"  !CDS_PN = "2";
DRAWING = "@s9s_mb_2u_lib.s9s_mb_2u(sch_1):page171";
BODY = "Q_CAP","I10": LOCATION = "C1507" #&CDS_LOCATION = "C1507" &SEC = "1" #&CDS_SEC = "1";
"A":   PN = "1"  !CDS_PN = "1";
"B":   PN = "2"  !CDS_PN = "2";
BODY = "Q_CRYSTAL","I11": LOCATION = "Y1" #&CDS_LOCATION = "Y1" #SEC = "1" !CDS_SEC = "1";
"1":   PN = "1"  !CDS_PN = "1";
"2":   PN = "2"  !CDS_PN = "2";
BODY = "Q_CAP","I17": LOCATION = "C1508" #&CDS_LOCATION = "C1508" &SEC = "1" #&CDS_SEC = "1";
"A":   PN = "1"  !CDS_PN = "1";
"B":   PN = "2"  !CDS_PN = "2";
BODY = "Q_RES","I69": LOCATION = "R477" #&CDS_LOCATION = "R477" &SEC = "1" #&CDS_SEC = "1";
"A":   PN = "1"  !CDS_PN = "1";
"B":   PN = "2"  !CDS_PN = "2";
BODY = "Q_RES","I74": LOCATION = "R120" #&CDS_LOCATION = "R120" &SEC = "1" #&CDS_SEC = "1";
"A":   PN = "1"  !CDS_PN = "1";
"B":   PN = "2"  !CDS_PN = "2";
BODY = "Q_XTAL_4P_13BI_24GND","I75": LOCATION = "Y7" #&CDS_LOCATION = "Y7" &SEC = "1" #&CDS_SEC = "1";
"G1":   PN = "2"  !CDS_PN = "2";
"G2":   PN = "4"  !CDS_PN = "4";
"X1":   PN = "1"  !CDS_PN = "1";
"X2":   PN = "3"  !CDS_PN = "3";
BODY = "Q_CAP","I76": LOCATION = "C104" #&CDS_LOCATION = "C104" &SEC = "1" #&CDS_SEC = "1";
"A":   PN = "1"  !CDS_PN = "1";
"B":   PN = "2"  !CDS_PN = "2";
BODY = "Q_CAP","I77": LOCATION = "C103" #&CDS_LOCATION = "C103" &SEC = "1" #&CDS_SEC = "1";
"A":   PN = "1"  !CDS_PN = "1";
"B":   PN = "2"  !CDS_PN = "2";
BODY = "EMMITSBURG_REV0P9","I78": LOCATION = "U4" #&CDS_LOCATION = "U4" &SEC = "1" #&CDS_SEC = "1";
"CLKOUT_SRC_N_0":   PN = "A16"  !CDS_PN = "A16";
"CLKOUT_SRC_N_1":   PN = "G23"  !CDS_PN = "G23";
"CLKOUT_SRC_N_2":   PN = "H21"  !CDS_PN = "H21";
"CLKOUT_SRC_N_3":   PN = "B17"  !CDS_PN = "B17";
"CLKOUT_SRC_N_4":   PN = "B19"  !CDS_PN = "B19";
"CLKOUT_SRC_N_5":   PN = "A12"  !CDS_PN = "A12";
"CLKOUT_SRC_N_6":   PN = "B11"  !CDS_PN = "B11";
"CLKOUT_SRC_N_7":   PN = "A14"  !CDS_PN = "A14";
"CLKOUT_SRC_N_8":   PN = "F18"  !CDS_PN = "F18";
"CLKOUT_SRC_N_9":   PN = "B15"  !CDS_PN = "B15";
"CLKOUT_SRC_N_10":   PN = "J16"  !CDS_PN = "J16";
"CLKOUT_SRC_N_11":   PN = "G16"  !CDS_PN = "G16";
"CLKOUT_SRC_N_12":   PN = "A10"  !CDS_PN = "A10";
"CLKOUT_SRC_N_13":   PN = "A8"  !CDS_PN = "A8";
"CLKOUT_SRC_N_14":   PN = "B7"  !CDS_PN = "B7";
"CLKOUT_SRC_N_15":   PN = "B5"  !CDS_PN = "B5";
"CLKOUT_SRC_N_16":   PN = "A18"  !CDS_PN = "A18";
"CLKOUT_SRC_P_0":   PN = "C16"  !CDS_PN = "C16";
"CLKOUT_SRC_P_1":   PN = "F21"  !CDS_PN = "F21";
"CLKOUT_SRC_P_2":   PN = "K21"  !CDS_PN = "K21";
"CLKOUT_SRC_P_3":   PN = "D17"  !CDS_PN = "D17";
"CLKOUT_SRC_P_4":   PN = "D19"  !CDS_PN = "D19";
"CLKOUT_SRC_P_5":   PN = "C12"  !CDS_PN = "C12";
"CLKOUT_SRC_P_6":   PN = "D11"  !CDS_PN = "D11";
"CLKOUT_SRC_P_7":   PN = "C14"  !CDS_PN = "C14";
"CLKOUT_SRC_P_8":   PN = "H18"  !CDS_PN = "H18";
"CLKOUT_SRC_P_9":   PN = "D15"  !CDS_PN = "D15";
"CLKOUT_SRC_P_10":   PN = "K18"  !CDS_PN = "K18";
"CLKOUT_SRC_P_11":   PN = "H15"  !CDS_PN = "H15";
"CLKOUT_SRC_P_12":   PN = "C10"  !CDS_PN = "C10";
"CLKOUT_SRC_P_13":   PN = "C8"  !CDS_PN = "C8";
"CLKOUT_SRC_P_14":   PN = "D7"  !CDS_PN = "D7";
"CLKOUT_SRC_P_15":   PN = "C6"  !CDS_PN = "C6";
"CLKOUT_SRC_P_16":   PN = "C18"  !CDS_PN = "C18";
"PMSYNC_CLK_N_0":   PN = "D27"  !CDS_PN = "D27";
"PMSYNC_CLK_N_1":   PN = "C28"  !CDS_PN = "C28";
"PMSYNC_CLK_P_0":   PN = "B27"  !CDS_PN = "B27";
"PMSYNC_CLK_P_1":   PN = "A28"  !CDS_PN = "A28";
"REFCLK_INJ_NS_N":   PN = "D25"  !CDS_PN = "D25";
"REFCLK_INJ_NS_P":   PN = "B25"  !CDS_PN = "B25";
"REFCLK_INJ_S_N":   PN = "D21"  !CDS_PN = "D21";
"REFCLK_INJ_S_P":   PN = "B21"  !CDS_PN = "B21";
"RSVD_H24":   PN = "H24"  !CDS_PN = "H24";
"RSVD_J23":   PN = "J23"  !CDS_PN = "J23";
"RTC_EXTCAP":   PN = "BF5"  !CDS_PN = "BF5";
"RTCX1":   PN = "BE6"  !CDS_PN = "BE6";
"RTCX2":   PN = "BF7"  !CDS_PN = "BF7";
"XCLK_BIASREF":   PN = "N29"  !CDS_PN = "N29";
"XTAL_IN":   PN = "B23"  !CDS_PN = "B23";
"XTAL_OUT":   PN = "D23"  !CDS_PN = "D23";
BODY = "Q_CAP","I89": LOCATION = "C609" #&CDS_LOCATION = "C609" &SEC = "1" #&CDS_SEC = "1";
"A":   PN = "1"  !CDS_PN = "1";
"B":   PN = "2"  !CDS_PN = "2";
BODY = "Q_RES","I92": LOCATION = "R1316" #&CDS_LOCATION = "R1316" &SEC = "1" #&CDS_SEC = "1";
"A":   PN = "1"  !CDS_PN = "1";
"B":   PN = "2"  !CDS_PN = "2";
BODY = "Q_RES","I103": LOCATION = "R1720" #&CDS_LOCATION = "R1720" &SEC = "1" #&CDS_SEC = "1";
"A":   PN = "1"  !CDS_PN = "1";
"B":   PN = "2"  !CDS_PN = "2";
BODY = "Q_RES","I104": LOCATION = "R1721" #&CDS_LOCATION = "R1721" &SEC = "1" #&CDS_SEC = "1";
"A":   PN = "1"  !CDS_PN = "1";
"B":   PN = "2"  !CDS_PN = "2";
BODY = "Q_RES","I116": LOCATION = "R4305" #&CDS_LOCATION = "R4305" &SEC = "1" #&CDS_SEC = "1";
"A":   PN = "1"  !CDS_PN = "1";
"B":   PN = "2"  !CDS_PN = "2";
BODY = "Q_RES","I117": LOCATION = "R4306" #&CDS_LOCATION = "R4306" &SEC = "1" #&CDS_SEC = "1";
"A":   PN = "1"  !CDS_PN = "1";
"B":   PN = "2"  !CDS_PN = "2";
BODY = "Q_RES","I121": #LOCATION = "R4303" !CDS_LOCATION = "R4303" &SEC = "1" #&CDS_SEC = "1";
"A":   PN = "1"  !CDS_PN = "1";
"B":   PN = "2"  !CDS_PN = "2";
BODY = "Q_RES","I122": #LOCATION = "R4304" !CDS_LOCATION = "R4304" &SEC = "1" #&CDS_SEC = "1";
"A":   PN = "1"  !CDS_PN = "1";
"B":   PN = "2"  !CDS_PN = "2";
DRAWING = "@s9s_mb_2u_lib.s9s_mb_2u(sch_1):page172";
BODY = "Q_RES","I10": LOCATION = "R496" #&CDS_LOCATION = "R496" &SEC = "1" #&CDS_SEC = "1";
"A":   PN = "1"  !CDS_PN = "1";
"B":   PN = "2"  !CDS_PN = "2";
BODY = "EMMITSBURG_REV0P9","I11": LOCATION = "U4" #&CDS_LOCATION = "U4" &SEC = "2" #&CDS_SEC = "2";
"RSVD_BC40":   PN = "BC40"  !CDS_PN = "BC40";
"USB2_COMP":   PN = "BB41"  !CDS_PN = "BB41";
"USB2N_0":   PN = "AR42"  !CDS_PN = "AR42";
"USB2N_1":   PN = "AP43"  !CDS_PN = "AP43";
"USB2N_2":   PN = "AT43"  !CDS_PN = "AT43";
"USB2N_3":   PN = "AN42"  !CDS_PN = "AN42";
"USB2N_4":   PN = "AU42"  !CDS_PN = "AU42";
"USB2N_5":   PN = "AL43"  !CDS_PN = "AL43";
"USB2N_6":   PN = "AV43"  !CDS_PN = "AV43";
"USB2N_7":   PN = "AK42"  !CDS_PN = "AK42";
"USB2N_8":   PN = "AW42"  !CDS_PN = "AW42";
"USB2N_9":   PN = "AJ43"  !CDS_PN = "AJ43";
"USB2N_10":   PN = "AY43"  !CDS_PN = "AY43";
"USB2N_11":   PN = "AH42"  !CDS_PN = "AH42";
"USB2N_12":   PN = "BA42"  !CDS_PN = "BA42";
"USB2N_13":   PN = "AG43"  !CDS_PN = "AG43";
"USB2P_0":   PN = "AR40"  !CDS_PN = "AR40";
"USB2P_1":   PN = "AP41"  !CDS_PN = "AP41";
"USB2P_2":   PN = "AT41"  !CDS_PN = "AT41";
"USB2P_3":   PN = "AN40"  !CDS_PN = "AN40";
"USB2P_4":   PN = "AU40"  !CDS_PN = "AU40";
"USB2P_5":   PN = "AL41"  !CDS_PN = "AL41";
"USB2P_6":   PN = "AV41"  !CDS_PN = "AV41";
"USB2P_7":   PN = "AK40"  !CDS_PN = "AK40";
"USB2P_8":   PN = "AW40"  !CDS_PN = "AW40";
"USB2P_9":   PN = "AJ41"  !CDS_PN = "AJ41";
"USB2P_10":   PN = "AY41"  !CDS_PN = "AY41";
"USB2P_11":   PN = "AH40"  !CDS_PN = "AH40";
"USB2P_12":   PN = "BA40"  !CDS_PN = "BA40";
"USB2P_13":   PN = "AG41"  !CDS_PN = "AG41";
DRAWING = "@s9s_mb_2u_lib.s9s_mb_2u(sch_1):page174";
BODY = "EMMITSBURG_REV0P9","I36": LOCATION = "U4" #&CDS_LOCATION = "U4" &SEC = "4" #&CDS_SEC = "4";
"ACPRESENT":   PN = "AN7"  !CDS_PN = "AN7";
"CPU_CATERR_N":   PN = "F8"  !CDS_PN = "F8";
"CPU_ERR0_N":   PN = "J7"  !CDS_PN = "J7";
"CPU_ERR1_N":   PN = "G7"  !CDS_PN = "G7";
"CPU_ERR2_N":   PN = "L7"  !CDS_PN = "L7";
"CPU_MEMTRIP_N":   PN = "E4"  !CDS_PN = "E4";
"CPU_MSMI_N":   PN = "F11"  !CDS_PN = "F11";
"CPU_PWR_DEBUG_N":   PN = "F5"  !CDS_PN = "F5";
"CPU_THRMTRIP_N":   PN = "F3"  !CDS_PN = "F3";
"CPUPWRGD":   PN = "G10"  !CDS_PN = "G10";
"DBG_PMODE":   PN = "BE40"  !CDS_PN = "BE40";
"DSW_PWROK":   PN = "BE8"  !CDS_PN = "BE8";
"GPP_O_0":   PN = "AN10"  !CDS_PN = "AN10";
"GPP_O_7":   PN = "AU10"  !CDS_PN = "AU10";
"INTRUDER_N":   PN = "BG8"  !CDS_PN = "BG8";
"JTAG_TCK":   PN = "BF35"  !CDS_PN = "BF35";
"JTAG_TDI":   PN = "BE38"  !CDS_PN = "BE38";
"JTAG_TDO":   PN = "BE36"  !CDS_PN = "BE36";
"JTAG_TMS":   PN = "BD37"  !CDS_PN = "BD37";
"JTAGX":   PN = "BD35"  !CDS_PN = "BD35";
"LAN_WAKE_N":   PN = "AU7"  !CDS_PN = "AU7";
"LANPHYPC":   PN = "AJ7"  !CDS_PN = "AJ7";
"ME_PECI":   PN = "J10"  !CDS_PN = "J10";
"PCH_PWROK":   PN = "BE4"  !CDS_PN = "BE4";
"PLTRST_CPU_N":   PN = "M8"  !CDS_PN = "M8";
"PRDY_N":   PN = "BB37"  !CDS_PN = "BB37";
"PREQ_N":   PN = "BF37"  !CDS_PN = "BF37";
"PWRBTN_N":   PN = "AR10"  !CDS_PN = "AR10";
"RSMRST_N":   PN = "BD9"  !CDS_PN = "BD9";
"RSVD_AV21":   PN = "AV21"  !CDS_PN = "AV21";
"RSVD_AW23":   PN = "AW26"  !CDS_PN = "AW26";
"RSVD_BF39":   PN = "BF39"  !CDS_PN = "BF39";
"RSVD_BG36":   PN = "BG36"  !CDS_PN = "BG36";
"SLP_A_N":   PN = "AM11"  !CDS_PN = "AM11";
"SLP_LAN_N":   PN = "AK8"  !CDS_PN = "AK8";
"SLP_S3_N":   PN = "AP8"  !CDS_PN = "AP8";
"SLP_S4_N":   PN = "AL13"  !CDS_PN = "AL13";
"SLP_S5_N":   PN = "AJ13"  !CDS_PN = "AJ13";
"SLP_SUS_N":   PN = "AL7"  !CDS_PN = "AL7";
"SUSCLK":   PN = "AR7"  !CDS_PN = "AR7";
"SYS_PWROK":   PN = "AL10"  !CDS_PN = "AL10";
"SYS_RESET_N":   PN = "AJ10"  !CDS_PN = "AJ10";
"TRIGGER0_N":   PN = "H11"  !CDS_PN = "H11";
"TRIGGER1_N":   PN = "K8"  !CDS_PN = "K8";
"WAKE_N":   PN = "AH11"  !CDS_PN = "AH11";
BODY = "Q_RES","I37": LOCATION = "R1026" #&CDS_LOCATION = "R1026" &SEC = "1" #&CDS_SEC = "1";
"A":   PN = "1"  !CDS_PN = "1";
"B":   PN = "2"  !CDS_PN = "2";
BODY = "Q_RES","I38": LOCATION = "R1025" #&CDS_LOCATION = "R1025" &SEC = "1" #&CDS_SEC = "1";
"A":   PN = "1"  !CDS_PN = "1";
"B":   PN = "2"  !CDS_PN = "2";
BODY = "Q_RES","I41": LOCATION = "R1024" #&CDS_LOCATION = "R1024" &SEC = "1" #&CDS_SEC = "1";
"A":   PN = "1"  !CDS_PN = "1";
"B":   PN = "2"  !CDS_PN = "2";
BODY = "Q_RES","I48": LOCATION = "R1198" #&CDS_LOCATION = "R1198" &SEC = "1" #&CDS_SEC = "1";
"A":   PN = "1"  !CDS_PN = "1";
"B":   PN = "2"  !CDS_PN = "2";
BODY = "Q_RES","I50": LOCATION = "R1197" #&CDS_LOCATION = "R1197" &SEC = "1" #&CDS_SEC = "1";
"A":   PN = "1"  !CDS_PN = "1";
"B":   PN = "2"  !CDS_PN = "2";
BODY = "Q_RES","I58": LOCATION = "R1201" #&CDS_LOCATION = "R1201" &SEC = "1" #&CDS_SEC = "1";
"A":   PN = "1"  !CDS_PN = "1";
"B":   PN = "2"  !CDS_PN = "2";
BODY = "Q_RES","I60": LOCATION = "R1200" #&CDS_LOCATION = "R1200" &SEC = "1" #&CDS_SEC = "1";
"A":   PN = "1"  !CDS_PN = "1";
"B":   PN = "2"  !CDS_PN = "2";
BODY = "Q_RES","I63": LOCATION = "R696" #&CDS_LOCATION = "R696" &SEC = "1" #&CDS_SEC = "1";
"A":   PN = "1"  !CDS_PN = "1";
"B":   PN = "2"  !CDS_PN = "2";
BODY = "Q_RES","I66": LOCATION = "R697" #&CDS_LOCATION = "R697" &SEC = "1" #&CDS_SEC = "1";
"A":   PN = "1"  !CDS_PN = "1";
"B":   PN = "2"  !CDS_PN = "2";
BODY = "Q_RES","I74": LOCATION = "R1486" #&CDS_LOCATION = "R1486" &SEC = "1" #&CDS_SEC = "1";
"A":   PN = "1"  !CDS_PN = "1";
"B":   PN = "2"  !CDS_PN = "2";
BODY = "Q_RES","I75": LOCATION = "R1485" #&CDS_LOCATION = "R1485" &SEC = "1" #&CDS_SEC = "1";
"A":   PN = "1"  !CDS_PN = "1";
"B":   PN = "2"  !CDS_PN = "2";
BODY = "Q_RES","I77": LOCATION = "R453" #&CDS_LOCATION = "R453" &SEC = "1" #&CDS_SEC = "1";
"A":   PN = "1"  !CDS_PN = "1";
"B":   PN = "2"  !CDS_PN = "2";
BODY = "Q_RES","I82": LOCATION = "R1675" #&CDS_LOCATION = "R1675" &SEC = "1" #&CDS_SEC = "1";
"A":   PN = "1"  !CDS_PN = "1";
"B":   PN = "2"  !CDS_PN = "2";
BODY = "Q_RES","I94": #LOCATION = "R1676" !CDS_LOCATION = "R1676" &SEC = "1" #&CDS_SEC = "1";
"A":   PN = "1"  !CDS_PN = "1";
"B":   PN = "2"  !CDS_PN = "2";
BODY = "Q_RES","I96": LOCATION = "R2966" #&CDS_LOCATION = "R2966" &SEC = "1" #&CDS_SEC = "1";
"A":   PN = "1"  !CDS_PN = "1";
"B":   PN = "2"  !CDS_PN = "2";
BODY = "Q_RES","I98": #LOCATION = "R494" !CDS_LOCATION = "R494" &SEC = "1" #&CDS_SEC = "1";
"A":   PN = "1"  !CDS_PN = "1";
"B":   PN = "2"  !CDS_PN = "2";
BODY = "Q_RES","I99": #LOCATION = "R1736" !CDS_LOCATION = "R1736" &SEC = "1" #&CDS_SEC = "1";
"A":   PN = "1"  !CDS_PN = "1";
"B":   PN = "2"  !CDS_PN = "2";
DRAWING = "@s9s_mb_2u_lib.s9s_mb_2u(sch_1):page175";
BODY = "EMMITSBURG_REV0P9","I93": LOCATION = "U4" #&CDS_LOCATION = "U4" &SEC = "5" #&CDS_SEC = "5";
"GPP_D_0_HS_SMBCLK_DMA_SMBCLK":   PN = "AF2"  !CDS_PN = "AF2";
"GPP_D_1_HS_SMBDATA_DMA_SMBDATA":   PN = "AE1"  !CDS_PN = "AE1";
"GPP_D_2_HS_SMBALERT_N_DMA_SMBALERT_N":   PN = "AD2"  !CDS_PN = "AD2";
"GPP_D_6":   PN = "AJ1"  !CDS_PN = "AJ1";
"GPP_D_7":   PN = "AG1"  !CDS_PN = "AG1";
"GPP_D_8_CRASHLOG_TRIG_N":   PN = "AE3"  !CDS_PN = "AE3";
"GPP_D_9_PME_N":   PN = "AJ3"  !CDS_PN = "AJ3";
"GPP_D_10_BM_BUSY_N_SX_EXIT_HOLDOFF_N":   PN = "AB2"  !CDS_PN = "AB2";
"GPP_D_11_PLTRST_N":   PN = "AB4"  !CDS_PN = "AB4";
"GPP_D_12_PCHHOT_N":   PN = "AH2"  !CDS_PN = "AH2";
"GPP_D_13_ADR_COMPLETE":   PN = "AC1"  !CDS_PN = "AC1";
"GPP_D_14_ADR_TRIGGER_N":   PN = "AH4"  !CDS_PN = "AH4";
"GPP_D_15_VRALERT_N":   PN = "AC3"  !CDS_PN = "AC3";
"GPP_D_16_ADR_ACK":   PN = "AD4"  !CDS_PN = "AD4";
"GPP_D_17_THERMTRIP_N":   PN = "Y2"  !CDS_PN = "Y2";
"GPP_D_18_MEMTRIP_N":   PN = "AF4"  !CDS_PN = "AF4";
"GPP_D_19_MSMI_N":   PN = "Y4"  !CDS_PN = "Y4";
"GPP_D_20_CATERR_N":   PN = "AG3"  !CDS_PN = "AG3";
"GPP_D_21_GLB_RST_WARN_N":   PN = "AA1"  !CDS_PN = "AA1";
"GPP_D_22_USB2_OCB_7":   PN = "AA3"  !CDS_PN = "AA3";
"GPP_D_23":   PN = "W1"  !CDS_PN = "W1";
"GPPC_A_0_ESPI_ALERT0_N":   PN = "BG20"  !CDS_PN = "BG20";
"GPPC_A_1_ESPI_ALERT1_N":   PN = "BD15"  !CDS_PN = "BD15";
"GPPC_A_2_ESPI_IO_0":   PN = "BG12"  !CDS_PN = "BG12";
"GPPC_A_3_ESPI_IO_1":   PN = "BF19"  !CDS_PN = "BF19";
"GPPC_A_4_ESPI_IO_2":   PN = "BE18"  !CDS_PN = "BE18";
"GPPC_A_5_ESPI_IO_3":   PN = "BD19"  !CDS_PN = "BD19";
"GPPC_A_6_ESPI_CS0_N":   PN = "BE20"  !CDS_PN = "BE20";
"GPPC_A_7_ESPI_CS1_N":   PN = "BE16"  !CDS_PN = "BE16";
"GPPC_A_8_ESPI_RESET_N":   PN = "BF17"  !CDS_PN = "BF17";
"GPPC_A_9_ESPI_CLK":   PN = "BD13"  !CDS_PN = "BD13";
"GPPC_A_10_SRCCLKREQ_N_0":   PN = "BD17"  !CDS_PN = "BD17";
"GPPC_A_11_SRCCLKREQ_N_1":   PN = "BG18"  !CDS_PN = "BG18";
"GPPC_A_12_SRCCLKREQ_N_2":   PN = "BG16"  !CDS_PN = "BG16";
"GPPC_A_13_SRCCLKREQ_N_3":   PN = "BF15"  !CDS_PN = "BF15";
"GPPC_A_14_SRCCLKREQ_N_4":   PN = "BE12"  !CDS_PN = "BE12";
"GPPC_A_15_SRCCLKREQ_N_5":   PN = "BE14"  !CDS_PN = "BE14";
"GPPC_A_16_SRCCLKREQ_N_6":   PN = "BD11"  !CDS_PN = "BD11";
"GPPC_A_17_SRCCLKREQ_N_7":   PN = "BF13"  !CDS_PN = "BF13";
"GPPC_A_18_SRCCLKREQ_N_8":   PN = "BF11"  !CDS_PN = "BF11";
"GPPC_A_19_SRCCLKREQ_N_9":   PN = "BG14"  !CDS_PN = "BG14";
"GPPC_B_0_GSXDOUT":   PN = "BD33"  !CDS_PN = "BD33";
"GPPC_B_1_GSXSLOAD":   PN = "BE32"  !CDS_PN = "BE32";
"GPPC_B_2_GSXDIN":   PN = "BF33"  !CDS_PN = "BF33";
"GPPC_B_3_GSXRESET_N":   PN = "BD31"  !CDS_PN = "BD31";
"GPPC_B_4_GSXCLK":   PN = "BE30"  !CDS_PN = "BE30";
"GPPC_B_5_USB2_OCB_0":   PN = "BF31"  !CDS_PN = "BF31";
"GPPC_B_6_USB2_OCB_1":   PN = "BG32"  !CDS_PN = "BG32";
"GPPC_B_7_USB2_OCB_2":   PN = "BG30"  !CDS_PN = "BG30";
"GPPC_B_8_USB2_OCB_3":   PN = "BG28"  !CDS_PN = "BG28";
"GPPC_B_9_USB2_OCB_4":   PN = "BG26"  !CDS_PN = "BG26";
"GPPC_B_10_USB2_OCB_5":   PN = "BG24"  !CDS_PN = "BG24";
"GPPC_B_11_USB2_OCB_6":   PN = "BG22"  !CDS_PN = "BG22";
"GPPC_B_12_HS_UART0_RXD":   PN = "BD29"  !CDS_PN = "BD29";
"GPPC_B_13_HS_UART0_TXD":   PN = "BE28"  !CDS_PN = "BE28";
"GPPC_B_14_HS_UART0_RTS_N":   PN = "BF29"  !CDS_PN = "BF29";
"GPPC_B_15_HS_UART0_CTS_N":   PN = "BD27"  !CDS_PN = "BD27";
"GPPC_B_16_HS_UART1_RXD":   PN = "BE26"  !CDS_PN = "BE26";
"GPPC_B_17_HS_UART1_TXD":   PN = "BF27"  !CDS_PN = "BF27";
"GPPC_B_18_HS_UART1_RTS_N":   PN = "BD25"  !CDS_PN = "BD25";
"GPPC_B_19_HS_UART1_CTS_N":   PN = "BF25"  !CDS_PN = "BF25";
"GPPC_B_20":   PN = "BE24"  !CDS_PN = "BE24";
"GPPC_B_21":   PN = "BF23"  !CDS_PN = "BF23";
"GPPC_B_22":   PN = "BE22"  !CDS_PN = "BE22";
"GPPC_B_23":   PN = "BD23"  !CDS_PN = "BD23";
"GPPC_C_0_ME_SML0CLK":   PN = "BC4"  !CDS_PN = "BC4";
"GPPC_C_1_ME_SML0DATA":   PN = "BA4"  !CDS_PN = "BA4";
"GPPC_C_2_ME_SML0ALERT_N":   PN = "AU2"  !CDS_PN = "AU2";
"GPPC_C_3_ME_SML0BDATA":   PN = "AU4"  !CDS_PN = "AU4";
"GPPC_C_4_ME_SML0BCLK":   PN = "BB3"  !CDS_PN = "BB3";
"GPPC_C_5_ME_SML0BALERT_N":   PN = "AT3"  !CDS_PN = "AT3";
"GPPC_C_6_ME_SML1CLK":   PN = "AP1"  !CDS_PN = "AP1";
"GPPC_C_7_ME_SML1DATA":   PN = "AW4"  !CDS_PN = "AW4";
"GPPC_C_8_ME_SML1ALERT_N":   PN = "AR4"  !CDS_PN = "AR4";
"GPPC_C_9_ME_SML2CLK":   PN = "AR2"  !CDS_PN = "AR2";
"GPPC_C_10_ME_SML2DATA":   PN = "AP3"  !CDS_PN = "AP3";
"GPPC_C_11_ME_SML2ALERT_N":   PN = "AV3"  !CDS_PN = "AV3";
"GPPC_C_12_ME_SML3CLK":   PN = "AN4"  !CDS_PN = "AN4";
"GPPC_C_13_ME_SML3DATA":   PN = "AY1"  !CDS_PN = "AY1";
"GPPC_C_14_ME_SML3ALERT_N":   PN = "AW2"  !CDS_PN = "AW2";
"GPPC_C_15_ME_SML4CLK":   PN = "BA2"  !CDS_PN = "BA2";
"GPPC_C_16_ME_SML4DATA":   PN = "AV1"  !CDS_PN = "AV1";
"GPPC_C_17_ME_SML4ALERT_N":   PN = "AL3"  !CDS_PN = "AL3";
"GPPC_C_18":   PN = "AL5"  !CDS_PN = "AL5";
"GPPC_C_19_MC_SMBCLK":   PN = "AL1"  !CDS_PN = "AL1";
"GPPC_C_20_MC_SMBDATA":   PN = "AT1"  !CDS_PN = "AT1";
"GPPC_C_21_MC_SMBALERT_N":   PN = "AN2"  !CDS_PN = "AN2";
BODY = "Q_RES","I102": LOCATION = "R699" #&CDS_LOCATION = "R699" &SEC = "1" #&CDS_SEC = "1";
"A":   PN = "1"  !CDS_PN = "1";
"B":   PN = "2"  !CDS_PN = "2";
BODY = "Q_RES","I109": LOCATION = "R1451" #&CDS_LOCATION = "R1451" &SEC = "1" #&CDS_SEC = "1";
"A":   PN = "1"  !CDS_PN = "1";
"B":   PN = "2"  !CDS_PN = "2";
BODY = "Q_RES","I112": LOCATION = "R1452" #&CDS_LOCATION = "R1452" &SEC = "1" #&CDS_SEC = "1";
"A":   PN = "1"  !CDS_PN = "1";
"B":   PN = "2"  !CDS_PN = "2";
BODY = "Q_RES","I120": LOCATION = "R1453" #&CDS_LOCATION = "R1453" &SEC = "1" #&CDS_SEC = "1";
"A":   PN = "1"  !CDS_PN = "1";
"B":   PN = "2"  !CDS_PN = "2";
BODY = "Q_RES","I121": LOCATION = "R1454" #&CDS_LOCATION = "R1454" &SEC = "1" #&CDS_SEC = "1";
"A":   PN = "1"  !CDS_PN = "1";
"B":   PN = "2"  !CDS_PN = "2";
BODY = "Q_RES","I125": LOCATION = "R1487" #&CDS_LOCATION = "R1487" &SEC = "1" #&CDS_SEC = "1";
"A":   PN = "1"  !CDS_PN = "1";
"B":   PN = "2"  !CDS_PN = "2";
BODY = "Q_RES","I137": LOCATION = "R1545" #&CDS_LOCATION = "R1545" &SEC = "1" #&CDS_SEC = "1";
"A":   PN = "1"  !CDS_PN = "1";
"B":   PN = "2"  !CDS_PN = "2";
BODY = "Q_RES","I138": LOCATION = "R1546" #&CDS_LOCATION = "R1546" &SEC = "1" #&CDS_SEC = "1";
"A":   PN = "1"  !CDS_PN = "1";
"B":   PN = "2"  !CDS_PN = "2";
BODY = "Q_RES","I141": LOCATION = "R1582" #&CDS_LOCATION = "R1582" &SEC = "1" #&CDS_SEC = "1";
"A":   PN = "1"  !CDS_PN = "1";
"B":   PN = "2"  !CDS_PN = "2";
BODY = "Q_RES","I142": LOCATION = "R1581" #&CDS_LOCATION = "R1581" &SEC = "1" #&CDS_SEC = "1";
"A":   PN = "1"  !CDS_PN = "1";
"B":   PN = "2"  !CDS_PN = "2";
BODY = "Q_RES","I144": LOCATION = "R1583" #&CDS_LOCATION = "R1583" &SEC = "1" #&CDS_SEC = "1";
"A":   PN = "1"  !CDS_PN = "1";
"B":   PN = "2"  !CDS_PN = "2";
BODY = "Q_RES","I148": LOCATION = "R1600" #&CDS_LOCATION = "R1600" &SEC = "1" #&CDS_SEC = "1";
"A":   PN = "1"  !CDS_PN = "1";
"B":   PN = "2"  !CDS_PN = "2";
BODY = "Q_RES","I151": LOCATION = "R1601" #&CDS_LOCATION = "R1601" &SEC = "1" #&CDS_SEC = "1";
"A":   PN = "1"  !CDS_PN = "1";
"B":   PN = "2"  !CDS_PN = "2";
BODY = "Q_RES","I178": LOCATION = "R1656" #&CDS_LOCATION = "R1656" &SEC = "1" #&CDS_SEC = "1";
"A":   PN = "1"  !CDS_PN = "1";
"B":   PN = "2"  !CDS_PN = "2";
BODY = "Q_RES","I180": LOCATION = "R1657" #&CDS_LOCATION = "R1657" &SEC = "1" #&CDS_SEC = "1";
"A":   PN = "1"  !CDS_PN = "1";
"B":   PN = "2"  !CDS_PN = "2";
BODY = "Q_RES","I181": LOCATION = "R1659" #&CDS_LOCATION = "R1659" &SEC = "1" #&CDS_SEC = "1";
"A":   PN = "1"  !CDS_PN = "1";
"B":   PN = "2"  !CDS_PN = "2";
BODY = "Q_RES","I188": LOCATION = "R1828" #&CDS_LOCATION = "R1828" &SEC = "1" #&CDS_SEC = "1";
"A":   PN = "1"  !CDS_PN = "1";
"B":   PN = "2"  !CDS_PN = "2";
BODY = "Q_RES","I193": LOCATION = "R1827" #&CDS_LOCATION = "R1827" &SEC = "1" #&CDS_SEC = "1";
"A":   PN = "1"  !CDS_PN = "1";
"B":   PN = "2"  !CDS_PN = "2";
BODY = "Q_RES","I213": LOCATION = "R474" #&CDS_LOCATION = "R474" &SEC = "1" #&CDS_SEC = "1";
"A":   PN = "1"  !CDS_PN = "1";
"B":   PN = "2"  !CDS_PN = "2";
BODY = "Q_RES","I222": LOCATION = "R1268" #&CDS_LOCATION = "R1268" &SEC = "1" #&CDS_SEC = "1";
"A":   PN = "1"  !CDS_PN = "1";
"B":   PN = "2"  !CDS_PN = "2";
BODY = "Q_RES","I225": LOCATION = "R1269" #&CDS_LOCATION = "R1269" &SEC = "1" #&CDS_SEC = "1";
"A":   PN = "1"  !CDS_PN = "1";
"B":   PN = "2"  !CDS_PN = "2";
BODY = "Q_RES","I234": LOCATION = "R635" #&CDS_LOCATION = "R635" &SEC = "1" #&CDS_SEC = "1";
"A":   PN = "1"  !CDS_PN = "1";
"B":   PN = "2"  !CDS_PN = "2";
BODY = "Q_RES","I236": LOCATION = "R727" #&CDS_LOCATION = "R727" &SEC = "1" #&CDS_SEC = "1";
"A":   PN = "1"  !CDS_PN = "1";
"B":   PN = "2"  !CDS_PN = "2";
BODY = "Q_RES","I239": LOCATION = "R770" #&CDS_LOCATION = "R770" &SEC = "1" #&CDS_SEC = "1";
"A":   PN = "1"  !CDS_PN = "1";
"B":   PN = "2"  !CDS_PN = "2";
BODY = "Q_RES","I241": LOCATION = "R913" #&CDS_LOCATION = "R913" &SEC = "1" #&CDS_SEC = "1";
"A":   PN = "1"  !CDS_PN = "1";
"B":   PN = "2"  !CDS_PN = "2";
BODY = "Q_RES","I253": LOCATION = "R2971" #&CDS_LOCATION = "R2971" &SEC = "1" #&CDS_SEC = "1";
"A":   PN = "1"  !CDS_PN = "1";
"B":   PN = "2"  !CDS_PN = "2";
BODY = "CONN3_210HP1030BR1","I256": LOCATION = "JP4" #&CDS_LOCATION = "JP4" &SEC = "1" #&CDS_SEC = "1";
"1":   PN = "1"  !CDS_PN = "1";
"2":   PN = "2"  !CDS_PN = "2";
"3":   PN = "3"  !CDS_PN = "3";
BODY = "CONN3_210HP1030BR1","I263": LOCATION = "JP9" #&CDS_LOCATION = "JP9" &SEC = "1" #&CDS_SEC = "1";
"1":   PN = "1"  !CDS_PN = "1";
"2":   PN = "2"  !CDS_PN = "2";
"3":   PN = "3"  !CDS_PN = "3";
BODY = "Q_RES","I272": LOCATION = "R3938" #&CDS_LOCATION = "R3938" &SEC = "1" #&CDS_SEC = "1";
"A":   PN = "1"  !CDS_PN = "1";
"B":   PN = "2"  !CDS_PN = "2";
BODY = "Q_RES","I275": LOCATION = "R4084" #&CDS_LOCATION = "R4084" &SEC = "1" #&CDS_SEC = "1";
"A":   PN = "1"  !CDS_PN = "1";
"B":   PN = "2"  !CDS_PN = "2";
BODY = "Q_RES","I274": LOCATION = "R4083" #&CDS_LOCATION = "R4083" &SEC = "1" #&CDS_SEC = "1";
"A":   PN = "1"  !CDS_PN = "1";
"B":   PN = "2"  !CDS_PN = "2";
BODY = "Q_RES","I284": LOCATION = "R4095" #&CDS_LOCATION = "R4095" &SEC = "1" #&CDS_SEC = "1";
"A":   PN = "1"  !CDS_PN = "1";
"B":   PN = "2"  !CDS_PN = "2";
BODY = "Q_RES","I285": LOCATION = "R4096" #&CDS_LOCATION = "R4096" &SEC = "1" #&CDS_SEC = "1";
"A":   PN = "1"  !CDS_PN = "1";
"B":   PN = "2"  !CDS_PN = "2";
BODY = "Q_RES","I286": LOCATION = "R4097" #&CDS_LOCATION = "R4097" &SEC = "1" #&CDS_SEC = "1";
"A":   PN = "1"  !CDS_PN = "1";
"B":   PN = "2"  !CDS_PN = "2";
BODY = "Q_RES","I287": LOCATION = "R4098" #&CDS_LOCATION = "R4098" &SEC = "1" #&CDS_SEC = "1";
"A":   PN = "1"  !CDS_PN = "1";
"B":   PN = "2"  !CDS_PN = "2";
BODY = "Q_RES","I288": LOCATION = "R4099" #&CDS_LOCATION = "R4099" &SEC = "1" #&CDS_SEC = "1";
"A":   PN = "1"  !CDS_PN = "1";
"B":   PN = "2"  !CDS_PN = "2";
BODY = "Q_RES","I298": LOCATION = "R4102" #&CDS_LOCATION = "R4102" &SEC = "1" #&CDS_SEC = "1";
"A":   PN = "1"  !CDS_PN = "1";
"B":   PN = "2"  !CDS_PN = "2";
BODY = "Q_RES","I299": LOCATION = "R4101" #&CDS_LOCATION = "R4101" &SEC = "1" #&CDS_SEC = "1";
"A":   PN = "1"  !CDS_PN = "1";
"B":   PN = "2"  !CDS_PN = "2";
BODY = "Q_RES","I300": LOCATION = "R4100" #&CDS_LOCATION = "R4100" &SEC = "1" #&CDS_SEC = "1";
"A":   PN = "1"  !CDS_PN = "1";
"B":   PN = "2"  !CDS_PN = "2";
BODY = "Q_RES","I305": LOCATION = "R4505" #&CDS_LOCATION = "R4505" &SEC = "1" #&CDS_SEC = "1";
"A":   PN = "1"  !CDS_PN = "1";
"B":   PN = "2"  !CDS_PN = "2";
BODY = "Q_RES","I308": LOCATION = "R4504" #&CDS_LOCATION = "R4504" &SEC = "1" #&CDS_SEC = "1";
"A":   PN = "1"  !CDS_PN = "1";
"B":   PN = "2"  !CDS_PN = "2";
BODY = "Q_RES","I314": #LOCATION = "R4766" !CDS_LOCATION = "R4766" &SEC = "1" #&CDS_SEC = "1";
"A":   PN = "1"  !CDS_PN = "1";
"B":   PN = "2"  !CDS_PN = "2";
BODY = "Q_RES","I315": LOCATION = "R4768" #&CDS_LOCATION = "R4768" &SEC = "1" #&CDS_SEC = "1";
"A":   PN = "1"  !CDS_PN = "1";
"B":   PN = "2"  !CDS_PN = "2";
DRAWING = "@s9s_mb_2u_lib.s9s_mb_2u(sch_1):page176";
BODY = "EMMITSBURG_REV0P9","I22": LOCATION = "U4" #&CDS_LOCATION = "U4" &SEC = "6" #&CDS_SEC = "6";
"GPP_E_0_SATA1_XPCIE_0":   PN = "BA26"  !CDS_PN = "BA26";
"GPP_E_1_SATA1_XPCIE_1":   PN = "BA23"  !CDS_PN = "BA23";
"GPP_E_2_SATA1_XPCIE_2":   PN = "AW23"  !CDS_PN = "AW23";
"GPP_E_3_SATA1_XPCIE_3":   PN = "BB21"  !CDS_PN = "BB21";
"GPP_E_4_SATA0_XPCIE_2":   PN = "AV24"  !CDS_PN = "AV24";
"GPP_E_5_SATA0_XPCIE_3":   PN = "AV28"  !CDS_PN = "AV28";
"GPP_E_6_SATA0_USB3_XPCIE_0":   PN = "BB24"  !CDS_PN = "BB24";
"GPP_E_7_SATA0_USB3_XPCIE_1":   PN = "AW32"  !CDS_PN = "AW32";
"GPP_E_8_SATA0_SCLOCK_SATA0_LED_N":   PN = "AW36"  !CDS_PN = "AW36";
"GPP_E_9_SATA0_SLOAD_SATA0_DEVSLP":   PN = "BA29"  !CDS_PN = "BA29";
"GPP_E_10_SATA0_SDATAOUT_SATA0_GP":   PN = "AV31"  !CDS_PN = "AV31";
"GPP_E_11_SATA1_SCLOCK_SATA1_LED_N":   PN = "AV34"  !CDS_PN = "AV34";
"GPP_E_12_SATA1_SLOAD_SATA1_GP":   PN = "BB28"  !CDS_PN = "BB28";
"GPP_E_13_SATA1_SDATAOUT_SATA1_DEVSLP":   PN = "BA32"  !CDS_PN = "BA32";
"GPP_E_14_SATA2_SCLOCK_SATA2_LED_N":   PN = "BB34"  !CDS_PN = "BB34";
"GPP_E_15_SATA2_SLOAD_SATA2_GP":   PN = "AW20"  !CDS_PN = "AW20";
"GPP_E_16_SATA2_SDATAOUT_SATA2_DEVSLP":   PN = "AW29"  !CDS_PN = "AW29";
"GPP_E_17_ERR0_N":   PN = "BA36"  !CDS_PN = "BA36";
"GPP_E_18_ERR1_N":   PN = "BA20"  !CDS_PN = "BA20";
"GPP_E_19_ERR2_N":   PN = "BB31"  !CDS_PN = "BB31";
"GPP_I_12_HDA_BCLK":   PN = "U3"  !CDS_PN = "U3";
"GPP_I_13_HDA_RST_N":   PN = "N2"  !CDS_PN = "N2";
"GPP_I_14_HDA_SYNC":   PN = "P1"  !CDS_PN = "P1";
"GPP_I_15_HDA_SDO":   PN = "R2"  !CDS_PN = "R2";
"GPP_I_16_HDA_SDI_0":   PN = "U1"  !CDS_PN = "U1";
"GPP_I_17_HDA_SDI_1":   PN = "V4"  !CDS_PN = "V4";
"GPP_I_21":   PN = "N4"  !CDS_PN = "N4";
"GPP_I_22":   PN = "P3"  !CDS_PN = "P3";
"GPP_I_23":   PN = "R4"  !CDS_PN = "R4";
"GPP_L_0_PM_SYNC_0":   PN = "AF8"  !CDS_PN = "AF8";
"GPP_L_1_PM_DOWN_0":   PN = "AE7"  !CDS_PN = "AE7";
"GPP_L_2":   PN = "AC10"  !CDS_PN = "AC10";
"GPP_L_3":   PN = "AF11"  !CDS_PN = "AF11";
"GPP_L_4":   PN = "AG7"  !CDS_PN = "AG7";
"GPP_L_5":   PN = "AB8"  !CDS_PN = "AB8";
"GPP_L_6":   PN = "AG10"  !CDS_PN = "AG10";
"GPP_L_7":   PN = "AC7"  !CDS_PN = "AC7";
"GPP_L_8":   PN = "AE10"  !CDS_PN = "AE10";
"GPP_M_0":   PN = "N7"  !CDS_PN = "N7";
"GPP_M_1":   PN = "AA13"  !CDS_PN = "AA13";
"GPP_M_2":   PN = "AA7"  !CDS_PN = "AA7";
"GPP_M_3":   PN = "AA10"  !CDS_PN = "AA10";
"GPP_M_4":   PN = "W7"  !CDS_PN = "W7";
"GPP_M_5":   PN = "V8"  !CDS_PN = "V8";
"GPP_M_6":   PN = "R10"  !CDS_PN = "R10";
"GPP_M_7":   PN = "AB11"  !CDS_PN = "AB11";
"GPP_M_8":   PN = "W10"  !CDS_PN = "W10";
"GPP_M_11":   PN = "R7"  !CDS_PN = "R7";
"GPP_M_12":   PN = "U7"  !CDS_PN = "U7";
"GPP_M_15":   PN = "T8"  !CDS_PN = "T8";
"GPP_M_16":   PN = "N10"  !CDS_PN = "N10";
"GPP_M_17":   PN = "W13"  !CDS_PN = "W13";
"GPPC_H_0":   PN = "G4"  !CDS_PN = "G4";
"GPPC_H_1":   PN = "K1"  !CDS_PN = "K1";
"GPPC_H_6":   PN = "L2"  !CDS_PN = "L2";
"GPPC_H_7":   PN = "K3"  !CDS_PN = "K3";
"GPPC_H_15_FLEX_CLK_OUT_0":   PN = "J2"  !CDS_PN = "J2";
"GPPC_H_16_FLEX_CLK_OUT_1":   PN = "G2"  !CDS_PN = "G2";
"GPPC_H_17_FLEX_CLK_OUT_2":   PN = "H3"  !CDS_PN = "H3";
"GPPC_H_18_PMCALERT_N":   PN = "J4"  !CDS_PN = "J4";
"GPPC_H_19":   PN = "L4"  !CDS_PN = "L4";
BODY = "Q_RES","I173": LOCATION = "R2508" #&CDS_LOCATION = "R2508" &SEC = "1" #&CDS_SEC = "1";
"A":   PN = "1"  !CDS_PN = "1";
"B":   PN = "2"  !CDS_PN = "2";
BODY = "Q_RES","I174": LOCATION = "R2509" #&CDS_LOCATION = "R2509" &SEC = "1" #&CDS_SEC = "1";
"A":   PN = "1"  !CDS_PN = "1";
"B":   PN = "2"  !CDS_PN = "2";
BODY = "Q_RES","I175": LOCATION = "R2510" #&CDS_LOCATION = "R2510" &SEC = "1" #&CDS_SEC = "1";
"A":   PN = "1"  !CDS_PN = "1";
"B":   PN = "2"  !CDS_PN = "2";
BODY = "Q_RES","I176": LOCATION = "R2511" #&CDS_LOCATION = "R2511" &SEC = "1" #&CDS_SEC = "1";
"A":   PN = "1"  !CDS_PN = "1";
"B":   PN = "2"  !CDS_PN = "2";
BODY = "Q_RES","I183": LOCATION = "R4105" #&CDS_LOCATION = "R4105" &SEC = "1" #&CDS_SEC = "1";
"A":   PN = "1"  !CDS_PN = "1";
"B":   PN = "2"  !CDS_PN = "2";
BODY = "Q_RES","I184": LOCATION = "R4106" #&CDS_LOCATION = "R4106" &SEC = "1" #&CDS_SEC = "1";
"A":   PN = "1"  !CDS_PN = "1";
"B":   PN = "2"  !CDS_PN = "2";
BODY = "Q_RES","I185": LOCATION = "R4104" #&CDS_LOCATION = "R4104" &SEC = "1" #&CDS_SEC = "1";
"A":   PN = "1"  !CDS_PN = "1";
"B":   PN = "2"  !CDS_PN = "2";
BODY = "Q_RES","I186": LOCATION = "R4103" #&CDS_LOCATION = "R4103" &SEC = "1" #&CDS_SEC = "1";
"A":   PN = "1"  !CDS_PN = "1";
"B":   PN = "2"  !CDS_PN = "2";
BODY = "Q_RES","I195": LOCATION = "R4109" #&CDS_LOCATION = "R4109" &SEC = "1" #&CDS_SEC = "1";
"A":   PN = "1"  !CDS_PN = "1";
"B":   PN = "2"  !CDS_PN = "2";
BODY = "Q_RES","I196": LOCATION = "R4108" #&CDS_LOCATION = "R4108" &SEC = "1" #&CDS_SEC = "1";
"A":   PN = "1"  !CDS_PN = "1";
"B":   PN = "2"  !CDS_PN = "2";
BODY = "Q_RES","I197": LOCATION = "R4107" #&CDS_LOCATION = "R4107" &SEC = "1" #&CDS_SEC = "1";
"A":   PN = "1"  !CDS_PN = "1";
"B":   PN = "2"  !CDS_PN = "2";
BODY = "Q_RES","I201": LOCATION = "R4115" #&CDS_LOCATION = "R4115" &SEC = "1" #&CDS_SEC = "1";
"A":   PN = "1"  !CDS_PN = "1";
"B":   PN = "2"  !CDS_PN = "2";
BODY = "Q_RES","I202": LOCATION = "R4110" #&CDS_LOCATION = "R4110" &SEC = "1" #&CDS_SEC = "1";
"A":   PN = "1"  !CDS_PN = "1";
"B":   PN = "2"  !CDS_PN = "2";
BODY = "Q_RES","I203": LOCATION = "R4112" #&CDS_LOCATION = "R4112" &SEC = "1" #&CDS_SEC = "1";
"A":   PN = "1"  !CDS_PN = "1";
"B":   PN = "2"  !CDS_PN = "2";
BODY = "Q_RES","I204": LOCATION = "R4111" #&CDS_LOCATION = "R4111" &SEC = "1" #&CDS_SEC = "1";
"A":   PN = "1"  !CDS_PN = "1";
"B":   PN = "2"  !CDS_PN = "2";
BODY = "Q_RES","I205": LOCATION = "R4114" #&CDS_LOCATION = "R4114" &SEC = "1" #&CDS_SEC = "1";
"A":   PN = "1"  !CDS_PN = "1";
"B":   PN = "2"  !CDS_PN = "2";
BODY = "Q_RES","I206": LOCATION = "R4113" #&CDS_LOCATION = "R4113" &SEC = "1" #&CDS_SEC = "1";
"A":   PN = "1"  !CDS_PN = "1";
"B":   PN = "2"  !CDS_PN = "2";
BODY = "Q_RES","I207": LOCATION = "R4116" #&CDS_LOCATION = "R4116" &SEC = "1" #&CDS_SEC = "1";
"A":   PN = "1"  !CDS_PN = "1";
"B":   PN = "2"  !CDS_PN = "2";
BODY = "Q_RES","I209": LOCATION = "R4117" #&CDS_LOCATION = "R4117" &SEC = "1" #&CDS_SEC = "1";
"A":   PN = "1"  !CDS_PN = "1";
"B":   PN = "2"  !CDS_PN = "2";
BODY = "Q_RES","I239": LOCATION = "R4564" #&CDS_LOCATION = "R4564" &SEC = "1" #&CDS_SEC = "1";
"A":   PN = "1"  !CDS_PN = "1";
"B":   PN = "2"  !CDS_PN = "2";
BODY = "Q_RES","I240": LOCATION = "R4565" #&CDS_LOCATION = "R4565" &SEC = "1" #&CDS_SEC = "1";
"A":   PN = "1"  !CDS_PN = "1";
"B":   PN = "2"  !CDS_PN = "2";
BODY = "Q_RES","I246": LOCATION = "R4722" #&CDS_LOCATION = "R4722" &SEC = "1" #&CDS_SEC = "1";
"A":   PN = "1"  !CDS_PN = "1";
"B":   PN = "2"  !CDS_PN = "2";
DRAWING = "@s9s_mb_2u_lib.s9s_mb_2u(sch_1):page177";
BODY = "Q_RES","I24": LOCATION = "R498" #&CDS_LOCATION = "R498" &SEC = "1" #&CDS_SEC = "1";
"A":   PN = "1"  !CDS_PN = "1";
"B":   PN = "2"  !CDS_PN = "2";
BODY = "EMMITSBURG_REV0P9","I27": LOCATION = "U4" #&CDS_LOCATION = "U4" &SEC = "7" #&CDS_SEC = "7";
"GPP_N_1":   PN = "T11"  !CDS_PN = "T11";
"GPP_N_4":   PN = "V11"  !CDS_PN = "V11";
"GPPC_S_0_TIME_SYNC_0":   PN = "BB18"  !CDS_PN = "BB18";
"GPPC_S_1_SPKR_TIME_SYNC_1":   PN = "AU16"  !CDS_PN = "AU16";
"GPPC_S_2_CPU_GP_0":   PN = "AR16"  !CDS_PN = "AR16";
"GPPC_S_3_CPU_GP_1":   PN = "AV11"  !CDS_PN = "AV11";
"GPPC_S_4_CPU_GP_2":   PN = "AU13"  !CDS_PN = "AU13";
"GPPC_S_5_CPU_GP_3":   PN = "AT18"  !CDS_PN = "AT18";
"GPPC_S_6_SUSWARN_N_SUSPWRDNACK":   PN = "AR13"  !CDS_PN = "AR13";
"GPPC_S_7_SUSACK_N":   PN = "BA7"  !CDS_PN = "BA7";
"GPPC_S_8_NMI_N":   PN = "AP15"  !CDS_PN = "AP15";
"GPPC_S_9_SMI_N":   PN = "AV18"  !CDS_PN = "AV18";
"GPPC_S_10":   PN = "AW10"  !CDS_PN = "AW10";
"GPPC_S_11":   PN = "BB8"  !CDS_PN = "BB8";
"NC_CGC_DUT_DETECT_N":   PN = "BG3"  !CDS_PN = "BG3";
"RCTRST_N":   PN = "BD7"  !CDS_PN = "BD7";
"SPI0_CLK":   PN = "BB15"  !CDS_PN = "BB15";
"SPI0_FLASH_0_CS_N":   PN = "AW13"  !CDS_PN = "AW13";
"SPI0_FLASH_1_CS_N":   PN = "BA10"  !CDS_PN = "BA10";
"SPI0_IO_2":   PN = "AV15"  !CDS_PN = "AV15";
"SPI0_IO_3":   PN = "BA16"  !CDS_PN = "BA16";
"SPI0_MISO_IO_1":   PN = "AW16"  !CDS_PN = "AW16";
"SPI0_MOSI_IO_0":   PN = "BA13"  !CDS_PN = "BA13";
"SPI0_TPM_CS_N":   PN = "BB11"  !CDS_PN = "BB11";
"SRTCRST_N":   PN = "BF9"  !CDS_PN = "BF9";
"VSS_A41":   PN = "A41"  !CDS_PN = "A41";
BODY = "Q_RES","I62": LOCATION = "R1203" #&CDS_LOCATION = "R1203" &SEC = "1" #&CDS_SEC = "1";
"A":   PN = "1"  !CDS_PN = "1";
"B":   PN = "2"  !CDS_PN = "2";
BODY = "CONN2_AAABAT029Y19","I63": LOCATION = "BT1" #&CDS_LOCATION = "BT1" &SEC = "1" #&CDS_SEC = "1";
"1":   PN = "1"  !CDS_PN = "1";
"2":   PN = "2"  !CDS_PN = "2";
BODY = "BAS70057F","I64": LOCATION = "U62" #&CDS_LOCATION = "U62" &SEC = "1" #&CDS_SEC = "1";
"A":   PN = "2"  !CDS_PN = "2";
"B":   PN = "1"  !CDS_PN = "1";
"C":   PN = "3"  !CDS_PN = "3";
BODY = "Q_CAP","I65": LOCATION = "C611" #&CDS_LOCATION = "C611" &SEC = "1" #&CDS_SEC = "1";
"A":   PN = "1"  !CDS_PN = "1";
"B":   PN = "2"  !CDS_PN = "2";
BODY = "Q_CAP","I68": LOCATION = "C610" #&CDS_LOCATION = "C610" &SEC = "1" #&CDS_SEC = "1";
"A":   PN = "1"  !CDS_PN = "1";
"B":   PN = "2"  !CDS_PN = "2";
BODY = "Q_RES","I70": LOCATION = "R1202" #&CDS_LOCATION = "R1202" &SEC = "1" #&CDS_SEC = "1";
"A":   PN = "1"  !CDS_PN = "1";
"B":   PN = "2"  !CDS_PN = "2";
BODY = "Q_RES","I80": LOCATION = "R1461" #&CDS_LOCATION = "R1461" &SEC = "1" #&CDS_SEC = "1";
"A":   PN = "1"  !CDS_PN = "1";
"B":   PN = "2"  !CDS_PN = "2";
BODY = "Q_RES","I85": LOCATION = "R1839" #&CDS_LOCATION = "R1839" &SEC = "1" #&CDS_SEC = "1";
"A":   PN = "1"  !CDS_PN = "1";
"B":   PN = "2"  !CDS_PN = "2";
BODY = "Q_RES","I89": LOCATION = "R1840" #&CDS_LOCATION = "R1840" &SEC = "1" #&CDS_SEC = "1";
"A":   PN = "1"  !CDS_PN = "1";
"B":   PN = "2"  !CDS_PN = "2";
BODY = "Q_RES","I100": LOCATION = "R501" #&CDS_LOCATION = "R501" &SEC = "1" #&CDS_SEC = "1";
"A":   PN = "1"  !CDS_PN = "1";
"B":   PN = "2"  !CDS_PN = "2";
BODY = "Q_RES","I102": LOCATION = "R1395" #&CDS_LOCATION = "R1395" &SEC = "1" #&CDS_SEC = "1";
"A":   PN = "1"  !CDS_PN = "1";
"B":   PN = "2"  !CDS_PN = "2";
BODY = "Q_RES","I106": LOCATION = "R499" #&CDS_LOCATION = "R499" &SEC = "1" #&CDS_SEC = "1";
"A":   PN = "1"  !CDS_PN = "1";
"B":   PN = "2"  !CDS_PN = "2";
BODY = "Q_RES","I118": #LOCATION = "R915" !CDS_LOCATION = "R915" &SEC = "1" #&CDS_SEC = "1";
"A":   PN = "1"  !CDS_PN = "1";
"B":   PN = "2"  !CDS_PN = "2";
BODY = "Q_RES","I119": #LOCATION = "R916" !CDS_LOCATION = "R916" &SEC = "1" #&CDS_SEC = "1";
"A":   PN = "1"  !CDS_PN = "1";
"B":   PN = "2"  !CDS_PN = "2";
BODY = "Q_RES","I120": #LOCATION = "R918" !CDS_LOCATION = "R918" &SEC = "1" #&CDS_SEC = "1";
"A":   PN = "1"  !CDS_PN = "1";
"B":   PN = "2"  !CDS_PN = "2";
BODY = "Q_RES","I121": #LOCATION = "R917" !CDS_LOCATION = "R917" &SEC = "1" #&CDS_SEC = "1";
"A":   PN = "1"  !CDS_PN = "1";
"B":   PN = "2"  !CDS_PN = "2";
BODY = "MOSFET_NCH_GDS_ESD_PROTECTED","I123": #LOCATION = "Q34" !CDS_LOCATION = "Q34" &SEC = "1" #&CDS_SEC = "1";
"D":   PN = "D"  !CDS_PN = "D";
"G":   PN = "G"  !CDS_PN = "G";
"S":   PN = "S"  !CDS_PN = "S";
BODY = "MOSFET_NCH_GDS_ESD_PROTECTED","I124": #LOCATION = "Q35" !CDS_LOCATION = "Q35" &SEC = "1" #&CDS_SEC = "1";
"D":   PN = "D"  !CDS_PN = "D";
"G":   PN = "G"  !CDS_PN = "G";
"S":   PN = "S"  !CDS_PN = "S";
BODY = "Q_RES","I125": LOCATION = "R4712" #&CDS_LOCATION = "R4712" &SEC = "1" #&CDS_SEC = "1";
"A":   PN = "1"  !CDS_PN = "1";
"B":   PN = "2"  !CDS_PN = "2";
BODY = "Q_RES","I127": LOCATION = "R4713" #&CDS_LOCATION = "R4713" &SEC = "1" #&CDS_SEC = "1";
"A":   PN = "1"  !CDS_PN = "1";
"B":   PN = "2"  !CDS_PN = "2";
DRAWING = "@s9s_mb_2u_lib.s9s_mb_2u(sch_1):page178";
BODY = "EMMITSBURG_REV0P9","I11": LOCATION = "U4" #&CDS_LOCATION = "U4" &SEC = "8" #&CDS_SEC = "8";
"RSVD_AF15":   PN = "AF15"  !CDS_PN = "AF15";
"RSVD_AN26":   PN = "AN26"  !CDS_PN = "AN26";
"VCCP_1P05_AB19":   PN = "AB19"  !CDS_PN = "AB19";
"VCCP_1P05_AB20":   PN = "AB20"  !CDS_PN = "AB20";
"VCCP_1P05_AB22":   PN = "AB22"  !CDS_PN = "AB22";
"VCCP_1P05_AB24":   PN = "AB24"  !CDS_PN = "AB24";
"VCCP_1P05_AD25":   PN = "AD25"  !CDS_PN = "AD25";
"VCCP_1P05_AD27":   PN = "AD27"  !CDS_PN = "AD27";
"VCCP_1P05_AF25":   PN = "AF25"  !CDS_PN = "AF25";
"VCCP_1P05_AF27":   PN = "AF27"  !CDS_PN = "AF27";
"VCCP_1P05_AG25":   PN = "AG25"  !CDS_PN = "AG25";
"VCCP_1P05_AG27":   PN = "AG27"  !CDS_PN = "AG27";
"VCCP_1P05_AJ25":   PN = "AJ25"  !CDS_PN = "AJ25";
"VCCP_1P05_AJ27":   PN = "AJ27"  !CDS_PN = "AJ27";
"VCCP_1P05_AR26":   PN = "AR26"  !CDS_PN = "AR26";
"VCCP_1P05_FILTERED_AA29":   PN = "AA29"  !CDS_PN = "AA29";
"VCCP_1P05_FILTERED_AB27":   PN = "AB27"  !CDS_PN = "AB27";
"VCCP_1P05_FILTERED_AE29":   PN = "AE29"  !CDS_PN = "AE29";
"VCCP_1P05_FILTERED_AG29":   PN = "AG29"  !CDS_PN = "AG29";
"VCCP_1P05_FILTERED_AL25":   PN = "AL25"  !CDS_PN = "AL25";
"VCCP_1P05_FILTERED_R23":   PN = "R23"  !CDS_PN = "R23";
"VCCP_1P05_FILTERED_R26":   PN = "R26"  !CDS_PN = "R26";
"VCCP_1P05_FILTERED_R29":   PN = "R29"  !CDS_PN = "R29";
"VCCP_1P05_FILTERED_U27":   PN = "U27"  !CDS_PN = "U27";
"VCCP_1P05_M24":   PN = "M24"  !CDS_PN = "M24";
"VCCP_1P05_N23":   PN = "N23"  !CDS_PN = "N23";
"VCCP_1P05_N26":   PN = "N26"  !CDS_PN = "N26";
"VCCP_1P05_P15":   PN = "P15"  !CDS_PN = "P15";
"VCCP_1P05_W17":   PN = "W17"  !CDS_PN = "W17";
"VCCP_1P05_W19":   PN = "W19"  !CDS_PN = "W19";
"VCCP_1P05_W20":   PN = "W20"  !CDS_PN = "W20";
"VCCP_1P05_W22":   PN = "W22"  !CDS_PN = "W22";
"VCCP_1P05_W24":   PN = "W24"  !CDS_PN = "W24";
"VCCP_1P8_FILTERED_AB31":   PN = "AB31"  !CDS_PN = "AB31";
"VCCP_1P8_FILTERED_AB34":   PN = "AB34"  !CDS_PN = "AB34";
"VCCP_1P8_FILTERED_U29":   PN = "U29"  !CDS_PN = "U29";
"VCCP_1P8_FILTERED_W27":   PN = "W27"  !CDS_PN = "W27";
"VCCP_1P8_FILTERED_W29":   PN = "W29"  !CDS_PN = "W29";
"VCCP_1P8_N20":   PN = "N20"  !CDS_PN = "N20";
"VCCP_1P8_U17":   PN = "U17"  !CDS_PN = "U17";
"VCCP_1P8_U19":   PN = "U19"  !CDS_PN = "U19";
"VCCP_1P8_U20":   PN = "U20"  !CDS_PN = "U20";
"VCCP_1P8_U22":   PN = "U22"  !CDS_PN = "U22";
"VCCP_1P8_U24":   PN = "U24"  !CDS_PN = "U24";
"VCCP_3P3_AF17":   PN = "AF17"  !CDS_PN = "AF17";
"VCCP_3P3_AG17":   PN = "AG17"  !CDS_PN = "AG17";
"VCCP_3P3_AJ17":   PN = "AJ17"  !CDS_PN = "AJ17";
"VCCP_3P3_AK15":   PN = "AK15"  !CDS_PN = "AK15";
"VCCP_3P3_AL17":   PN = "AL17"  !CDS_PN = "AL17";
"VCCP_3P3_DSW_AD15":   PN = "AD15"  !CDS_PN = "AD15";
"VCCP_3P3_DSW_V15":   PN = "V15"  !CDS_PN = "V15";
"VCCP_3P3_P21":   PN = "P21"  !CDS_PN = "P21";
"VCCP_GPPD_1P8_3P3":   PN = "T15"  !CDS_PN = "T15";
"VCCP_GPPE_1P8_3P3":   PN = "AN20"  !CDS_PN = "AN20";
"VCCP_GPPI_1P8_3P3":   PN = "AD17"  !CDS_PN = "AD17";
"VCCP_VNN_AF20":   PN = "AF20"  !CDS_PN = "AF20";
"VCCP_VNN_AF22":   PN = "AF22"  !CDS_PN = "AF22";
"VCCP_VNN_AG20":   PN = "AG20"  !CDS_PN = "AG20";
"VCCP_VNN_AG22":   PN = "AG22"  !CDS_PN = "AG22";
"VCCP_VNN_AJ20":   PN = "AJ20"  !CDS_PN = "AJ20";
"VCCP_VNN_AJ22":   PN = "AJ22"  !CDS_PN = "AJ22";
"VCCP_VNN_AL20":   PN = "AL20"  !CDS_PN = "AL20";
"VCCP_VNN_AL22":   PN = "AL22"  !CDS_PN = "AL22";
"VCCP_VNN_AN23":   PN = "AN23"  !CDS_PN = "AN23";
"VCCP_VNN_AP21":   PN = "AP21"  !CDS_PN = "AP21";
"VCCP_VNN_AR23":   PN = "AR23"  !CDS_PN = "AR23";
"VCCRTC":   PN = "AH15"  !CDS_PN = "AH15";
"VSS_BG40":   PN = "BG40"  !CDS_PN = "BG40";
DRAWING = "@s9s_mb_2u_lib.s9s_mb_2u(sch_1):page179";
BODY = "Q_RES","I2": LOCATION = "R497" #&CDS_LOCATION = "R497" &SEC = "1" #&CDS_SEC = "1";
"A":   PN = "1"  !CDS_PN = "1";
"B":   PN = "2"  !CDS_PN = "2";
BODY = "EMMITSBURG_REV0P9","I4": LOCATION = "U4" #&CDS_LOCATION = "U4" &SEC = "9" #&CDS_SEC = "9";
"GPIO_RCOMP_1P8_3P3":   PN = "AC13"  !CDS_PN = "AC13";
"RSVD_A4":   PN = "A4"  !CDS_PN = "A4";
"RSVD_BB43":   PN = "BB43"  !CDS_PN = "BB43";
"RSVD_F1":   PN = "F1"  !CDS_PN = "F1";
"RSVD_H1":   PN = "H1"  !CDS_PN = "H1";
"RSVD_L13":   PN = "L13"  !CDS_PN = "L13";
"RSVD_N13":   PN = "N13"  !CDS_PN = "N13";
"RSVD_P18":   PN = "P18"  !CDS_PN = "P18";
DRAWING = "@s9s_mb_2u_lib.s9s_mb_2u(sch_1):page180";
BODY = "EMMITSBURG_REV0P9","I7": LOCATION = "U4" #&CDS_LOCATION = "U4" &SEC = "10" #&CDS_SEC = "10";
"VSS_AY3":   PN = "AY3"  !CDS_PN = "AY3";
"VSS_AY5":   PN = "AY5"  !CDS_PN = "AY5";
"VSS_AY8":   PN = "AY8"  !CDS_PN = "AY8";
"VSS_AY28":   PN = "AY28"  !CDS_PN = "AY28";
"VSS_AY31":   PN = "AY31"  !CDS_PN = "AY31";
"VSS_AY34":   PN = "AY34"  !CDS_PN = "AY34";
"VSS_AY37":   PN = "AY37"  !CDS_PN = "AY37";
"VSS_AY39":   PN = "AY39"  !CDS_PN = "AY39";
"VSS_B9":   PN = "B9"  !CDS_PN = "B9";
"VSS_B13":   PN = "B13"  !CDS_PN = "B13";
"VSS_B29":   PN = "B29"  !CDS_PN = "B29";
"VSS_B39":   PN = "B39"  !CDS_PN = "B39";
"VSS_BB5":   PN = "BB5"  !CDS_PN = "BB5";
"VSS_BB39":   PN = "BB39"  !CDS_PN = "BB39";
"VSS_BC6":   PN = "BC6"  !CDS_PN = "BC6";
"VSS_BC8":   PN = "BC8"  !CDS_PN = "BC8";
"VSS_BC10":   PN = "BC10"  !CDS_PN = "BC10";
"VSS_BC12":   PN = "BC12"  !CDS_PN = "BC12";
"VSS_BC14":   PN = "BC14"  !CDS_PN = "BC14";
"VSS_BC16":   PN = "BC16"  !CDS_PN = "BC16";
"VSS_BC18":   PN = "BC18"  !CDS_PN = "BC18";
"VSS_BC20":   PN = "BC20"  !CDS_PN = "BC20";
"VSS_BC22":   PN = "BC22"  !CDS_PN = "BC22";
"VSS_BC24":   PN = "BC24"  !CDS_PN = "BC24";
"VSS_BC26":   PN = "BC26"  !CDS_PN = "BC26";
"VSS_BC28":   PN = "BC28"  !CDS_PN = "BC28";
"VSS_BC30":   PN = "BC30"  !CDS_PN = "BC30";
"VSS_BC32":   PN = "BC32"  !CDS_PN = "BC32";
"VSS_BC34":   PN = "BC34"  !CDS_PN = "BC34";
"VSS_BC36":   PN = "BC36"  !CDS_PN = "BC36";
"VSS_BC38":   PN = "BC38"  !CDS_PN = "BC38";
"VSS_BD5":   PN = "BD5"  !CDS_PN = "BD5";
"VSS_BD21":   PN = "BD21"  !CDS_PN = "BD21";
"VSS_BD39":   PN = "BD39"  !CDS_PN = "BD39";
"VSS_BE10":   PN = "BE10"  !CDS_PN = "BE10";
"VSS_BE34":   PN = "BE34"  !CDS_PN = "BE34";
"VSS_BF21":   PN = "BF21"  !CDS_PN = "BF21";
"VSS_BG10":   PN = "BG10"  !CDS_PN = "BG10";
"VSS_BG34":   PN = "BG34"  !CDS_PN = "BG34";
"VSS_C4":   PN = "C4"  !CDS_PN = "C4";
"VSS_C20":   PN = "C20"  !CDS_PN = "C20";
"VSS_C22":   PN = "C22"  !CDS_PN = "C22";
"VSS_C24":   PN = "C24"  !CDS_PN = "C24";
"VSS_C26":   PN = "C26"  !CDS_PN = "C26";
"VSS_C38":   PN = "C38"  !CDS_PN = "C38";
"VSS_D5":   PN = "D5"  !CDS_PN = "D5";
"VSS_D9":   PN = "D9"  !CDS_PN = "D9";
"VSS_D13":   PN = "D13"  !CDS_PN = "D13";
"VSS_D29":   PN = "D29"  !CDS_PN = "D29";
"VSS_E6":   PN = "E6"  !CDS_PN = "E6";
"VSS_E8":   PN = "E8"  !CDS_PN = "E8";
"VSS_E10":   PN = "E10"  !CDS_PN = "E10";
"VSS_E12":   PN = "E12"  !CDS_PN = "E12";
"VSS_E14":   PN = "E14"  !CDS_PN = "E14";
"VSS_E16":   PN = "E16"  !CDS_PN = "E16";
"VSS_E18":   PN = "E18"  !CDS_PN = "E18";
"VSS_E20":   PN = "E20"  !CDS_PN = "E20";
"VSS_E22":   PN = "E22"  !CDS_PN = "E22";
"VSS_E24":   PN = "E24"  !CDS_PN = "E24";
"VSS_E26":   PN = "E26"  !CDS_PN = "E26";
"VSS_E28":   PN = "E28"  !CDS_PN = "E28";
"VSS_E30":   PN = "E30"  !CDS_PN = "E30";
"VSS_E32":   PN = "E32"  !CDS_PN = "E32";
"VSS_E34":   PN = "E34"  !CDS_PN = "E34";
"VSS_E36":   PN = "E36"  !CDS_PN = "E36";
"VSS_E38":   PN = "E38"  !CDS_PN = "E38";
"VSS_E40":   PN = "E40"  !CDS_PN = "E40";
"VSS_F15":   PN = "F15"  !CDS_PN = "F15";
"VSS_F24":   PN = "F24"  !CDS_PN = "F24";
"VSS_F31":   PN = "F31"  !CDS_PN = "F31";
"VSS_F34":   PN = "F34"  !CDS_PN = "F34";
"VSS_F39":   PN = "F39"  !CDS_PN = "F39";
"VSS_F41":   PN = "F41"  !CDS_PN = "F41";
"VSS_G13":   PN = "G13"  !CDS_PN = "G13";
"VSS_G20":   PN = "G20"  !CDS_PN = "G20";
"VSS_G26":   PN = "G26"  !CDS_PN = "G26";
"VSS_H5":   PN = "H5"  !CDS_PN = "H5";
"VSS_H8":   PN = "H8"  !CDS_PN = "H8";
"VSS_H39":   PN = "H39"  !CDS_PN = "H39";
"VSS_J13":   PN = "J13"  !CDS_PN = "J13";
"VSS_J20":   PN = "J20"  !CDS_PN = "J20";
"VSS_J26":   PN = "J26"  !CDS_PN = "J26";
"VSS_K5":   PN = "K5"  !CDS_PN = "K5";
"VSS_K11":   PN = "K11"  !CDS_PN = "K11";
"VSS_K15":   PN = "K15"  !CDS_PN = "K15";
"VSS_K24":   PN = "K24"  !CDS_PN = "K24";
"VSS_K34":   PN = "K34"  !CDS_PN = "K34";
"VSS_K39":   PN = "K39"  !CDS_PN = "K39";
"VSS_L10":   PN = "L10"  !CDS_PN = "L10";
"VSS_L16":   PN = "L16"  !CDS_PN = "L16";
"VSS_L20":   PN = "L20"  !CDS_PN = "L20";
"VSS_L23":   PN = "L23"  !CDS_PN = "L23";
"VSS_L26":   PN = "L26"  !CDS_PN = "L26";
"VSS_L29":   PN = "L29"  !CDS_PN = "L29";
"VSS_L36":   PN = "L36"  !CDS_PN = "L36";
"VSS_M1":   PN = "M1"  !CDS_PN = "M1";
"VSS_M3":   PN = "M3"  !CDS_PN = "M3";
"VSS_M5":   PN = "M5"  !CDS_PN = "M5";
"VSS_M11":   PN = "M11"  !CDS_PN = "M11";
"VSS_M15":   PN = "M15"  !CDS_PN = "M15";
"VSS_M18":   PN = "M18"  !CDS_PN = "M18";
"VSS_M21":   PN = "M21"  !CDS_PN = "M21";
"VSS_M28":   PN = "M28"  !CDS_PN = "M28";
"VSS_M31":   PN = "M31"  !CDS_PN = "M31";
"VSS_M34":   PN = "M34"  !CDS_PN = "M34";
"VSS_M37":   PN = "M37"  !CDS_PN = "M37";
"VSS_M39":   PN = "M39"  !CDS_PN = "M39";
"VSS_N16":   PN = "N16"  !CDS_PN = "N16";
"VSS_N32":   PN = "N32"  !CDS_PN = "N32";
"VSS_P5":   PN = "P5"  !CDS_PN = "P5";
"VSS_P8":   PN = "P8"  !CDS_PN = "P8";
"VSS_P11":   PN = "P11"  !CDS_PN = "P11";
"VSS_P24":   PN = "P24"  !CDS_PN = "P24";
"VSS_P28":   PN = "P28"  !CDS_PN = "P28";
"VSS_P31":   PN = "P31"  !CDS_PN = "P31";
"VSS_P37":   PN = "P37"  !CDS_PN = "P37";
"VSS_P39":   PN = "P39"  !CDS_PN = "P39";
"VSS_P41":   PN = "P41"  !CDS_PN = "P41";
"VSS_P43":   PN = "P43"  !CDS_PN = "P43";
"VSS_R13":   PN = "R13"  !CDS_PN = "R13";
"VSS_R16":   PN = "R16"  !CDS_PN = "R16";
"VSS_R20":   PN = "R20"  !CDS_PN = "R20";
"VSS_R36":   PN = "R36"  !CDS_PN = "R36";
"VSS_T31":   PN = "T31"  !CDS_PN = "T31";
"VSS_U5":   PN = "U5"  !CDS_PN = "U5";
"VSS_U10":   PN = "U10"  !CDS_PN = "U10";
"VSS_U13":   PN = "U13"  !CDS_PN = "U13";
"VSS_U25":   PN = "U25"  !CDS_PN = "U25";
"VSS_U39":   PN = "U39"  !CDS_PN = "U39";
"VSS_V2":   PN = "V2"  !CDS_PN = "V2";
"VSS_V31":   PN = "V31"  !CDS_PN = "V31";
"VSS_W3":   PN = "W3"  !CDS_PN = "W3";
"VSS_W5":   PN = "W5"  !CDS_PN = "W5";
"VSS_W25":   PN = "W25"  !CDS_PN = "W25";
"VSS_W39":   PN = "W39"  !CDS_PN = "W39";
"VSS_Y8":   PN = "Y8"  !CDS_PN = "Y8";
"VSS_Y11":   PN = "Y11"  !CDS_PN = "Y11";
"VSS_Y15":   PN = "Y15"  !CDS_PN = "Y15";
"VSS_Y31":   PN = "Y31"  !CDS_PN = "Y31";
"VSS_Y34":   PN = "Y34"  !CDS_PN = "Y34";
BODY = "EMMITSBURG_REV0P9","I9": LOCATION = "U4" #&CDS_LOCATION = "U4" &SEC = "11" #&CDS_SEC = "11";
"VSS_A6":   PN = "A6"  !CDS_PN = "A6";
"VSS_A20":   PN = "A20"  !CDS_PN = "A20";
"VSS_A22":   PN = "A22"  !CDS_PN = "A22";
"VSS_A24":   PN = "A24"  !CDS_PN = "A24";
"VSS_A26":   PN = "A26"  !CDS_PN = "A26";
"VSS_A38":   PN = "A38"  !CDS_PN = "A38";
"VSS_A40":   PN = "A40"  !CDS_PN = "A40";
"VSS_AA5":   PN = "AA5"  !CDS_PN = "AA5";
"VSS_AA17":   PN = "AA17"  !CDS_PN = "AA17";
"VSS_AA19":   PN = "AA19"  !CDS_PN = "AA19";
"VSS_AA20":   PN = "AA20"  !CDS_PN = "AA20";
"VSS_AA22":   PN = "AA22"  !CDS_PN = "AA22";
"VSS_AA24":   PN = "AA24"  !CDS_PN = "AA24";
"VSS_AA25":   PN = "AA25"  !CDS_PN = "AA25";
"VSS_AA27":   PN = "AA27"  !CDS_PN = "AA27";
"VSS_AA32":   PN = "AA32"  !CDS_PN = "AA32";
"VSS_AA36":   PN = "AA36"  !CDS_PN = "AA36";
"VSS_AA39":   PN = "AA39"  !CDS_PN = "AA39";
"VSS_AB15":   PN = "AB15"  !CDS_PN = "AB15";
"VSS_AB17":   PN = "AB17"  !CDS_PN = "AB17";
"VSS_AB25":   PN = "AB25"  !CDS_PN = "AB25";
"VSS_AB37":   PN = "AB37"  !CDS_PN = "AB37";
"VSS_AC5":   PN = "AC5"  !CDS_PN = "AC5";
"VSS_AC29":   PN = "AC29"  !CDS_PN = "AC29";
"VSS_AC32":   PN = "AC32"  !CDS_PN = "AC32";
"VSS_AC36":   PN = "AC36"  !CDS_PN = "AC36";
"VSS_AC39":   PN = "AC39"  !CDS_PN = "AC39";
"VSS_AD8":   PN = "AD8"  !CDS_PN = "AD8";
"VSS_AD11":   PN = "AD11"  !CDS_PN = "AD11";
"VSS_AD19":   PN = "AD19"  !CDS_PN = "AD19";
"VSS_AD20":   PN = "AD20"  !CDS_PN = "AD20";
"VSS_AD22":   PN = "AD22"  !CDS_PN = "AD22";
"VSS_AD24":   PN = "AD24"  !CDS_PN = "AD24";
"VSS_AD31":   PN = "AD31"  !CDS_PN = "AD31";
"VSS_AD34":   PN = "AD34"  !CDS_PN = "AD34";
"VSS_AE5":   PN = "AE5"  !CDS_PN = "AE5";
"VSS_AE13":   PN = "AE13"  !CDS_PN = "AE13";
"VSS_AE39":   PN = "AE39"  !CDS_PN = "AE39";
"VSS_AF19":   PN = "AF19"  !CDS_PN = "AF19";
"VSS_AF24":   PN = "AF24"  !CDS_PN = "AF24";
"VSS_AF31":   PN = "AF31"  !CDS_PN = "AF31";
"VSS_AF40":   PN = "AF40"  !CDS_PN = "AF40";
"VSS_AF42":   PN = "AF42"  !CDS_PN = "AF42";
"VSS_AG5":   PN = "AG5"  !CDS_PN = "AG5";
"VSS_AG13":   PN = "AG13"  !CDS_PN = "AG13";
"VSS_AG19":   PN = "AG19"  !CDS_PN = "AG19";
"VSS_AG24":   PN = "AG24"  !CDS_PN = "AG24";
"VSS_AG39":   PN = "AG39"  !CDS_PN = "AG39";
"VSS_AH8":   PN = "AH8"  !CDS_PN = "AH8";
"VSS_AH31":   PN = "AH31"  !CDS_PN = "AH31";
"VSS_AJ5":   PN = "AJ5"  !CDS_PN = "AJ5";
"VSS_AJ19":   PN = "AJ19"  !CDS_PN = "AJ19";
"VSS_AJ24":   PN = "AJ24"  !CDS_PN = "AJ24";
"VSS_AJ29":   PN = "AJ29"  !CDS_PN = "AJ29";
"VSS_AJ36":   PN = "AJ36"  !CDS_PN = "AJ36";
"VSS_AJ39":   PN = "AJ39"  !CDS_PN = "AJ39";
"VSS_AK2":   PN = "AK2"  !CDS_PN = "AK2";
"VSS_AK4":   PN = "AK4"  !CDS_PN = "AK4";
"VSS_AK11":   PN = "AK11"  !CDS_PN = "AK11";
"VSS_AK37":   PN = "AK37"  !CDS_PN = "AK37";
"VSS_AL19":   PN = "AL19"  !CDS_PN = "AL19";
"VSS_AL24":   PN = "AL24"  !CDS_PN = "AL24";
"VSS_AL27":   PN = "AL27"  !CDS_PN = "AL27";
"VSS_AL29":   PN = "AL29"  !CDS_PN = "AL29";
"VSS_AL39":   PN = "AL39"  !CDS_PN = "AL39";
"VSS_AM8":   PN = "AM8"  !CDS_PN = "AM8";
"VSS_AM15":   PN = "AM15"  !CDS_PN = "AM15";
"VSS_AM31":   PN = "AM31"  !CDS_PN = "AM31";
"VSS_AN13":   PN = "AN13"  !CDS_PN = "AN13";
"VSS_AN16":   PN = "AN16"  !CDS_PN = "AN16";
"VSS_AN29":   PN = "AN29"  !CDS_PN = "AN29";
"VSS_AN32":   PN = "AN32"  !CDS_PN = "AN32";
"VSS_AP5":   PN = "AP5"  !CDS_PN = "AP5";
"VSS_AP11":   PN = "AP11"  !CDS_PN = "AP11";
"VSS_AP18":   PN = "AP18"  !CDS_PN = "AP18";
"VSS_AP24":   PN = "AP24"  !CDS_PN = "AP24";
"VSS_AP28":   PN = "AP28"  !CDS_PN = "AP28";
"VSS_AP37":   PN = "AP37"  !CDS_PN = "AP37";
"VSS_AP39":   PN = "AP39"  !CDS_PN = "AP39";
"VSS_AR20":   PN = "AR20"  !CDS_PN = "AR20";
"VSS_AR32":   PN = "AR32"  !CDS_PN = "AR32";
"VSS_AT5":   PN = "AT5"  !CDS_PN = "AT5";
"VSS_AT8":   PN = "AT8"  !CDS_PN = "AT8";
"VSS_AT11":   PN = "AT11"  !CDS_PN = "AT11";
"VSS_AT15":   PN = "AT15"  !CDS_PN = "AT15";
"VSS_AT21":   PN = "AT21"  !CDS_PN = "AT21";
"VSS_AT24":   PN = "AT24"  !CDS_PN = "AT24";
"VSS_AT28":   PN = "AT28"  !CDS_PN = "AT28";
"VSS_AT31":   PN = "AT31"  !CDS_PN = "AT31";
"VSS_AT34":   PN = "AT34"  !CDS_PN = "AT34";
"VSS_AT39":   PN = "AT39"  !CDS_PN = "AT39";
"VSS_AU20":   PN = "AU20"  !CDS_PN = "AU20";
"VSS_AU23":   PN = "AU23"  !CDS_PN = "AU23";
"VSS_AU26":   PN = "AU26"  !CDS_PN = "AU26";
"VSS_AU29":   PN = "AU29"  !CDS_PN = "AU29";
"VSS_AU32":   PN = "AU32"  !CDS_PN = "AU32";
"VSS_AU36":   PN = "AU36"  !CDS_PN = "AU36";
"VSS_AV5":   PN = "AV5"  !CDS_PN = "AV5";
"VSS_AV8":   PN = "AV8"  !CDS_PN = "AV8";
"VSS_AV37":   PN = "AV37"  !CDS_PN = "AV37";
"VSS_AV39":   PN = "AV39"  !CDS_PN = "AV39";
"VSS_AW7":   PN = "AW7"  !CDS_PN = "AW7";
"VSS_AY11":   PN = "AY11"  !CDS_PN = "AY11";
"VSS_AY15":   PN = "AY15"  !CDS_PN = "AY15";
"VSS_AY18":   PN = "AY18"  !CDS_PN = "AY18";
"VSS_AY21":   PN = "AY21"  !CDS_PN = "AY21";
"VSS_AY24":   PN = "AY24"  !CDS_PN = "AY24";
"VSS_BB1":   PN = "BB1"  !CDS_PN = "BB1";
"VSS_BC2":   PN = "BC2"  !CDS_PN = "BC2";
"VSS_BC42":   PN = "BC42"  !CDS_PN = "BC42";
"VSS_BD1":   PN = "BD1"  !CDS_PN = "BD1";
"VSS_BD3":   PN = "BD3"  !CDS_PN = "BD3";
"VSS_BD41":   PN = "BD41"  !CDS_PN = "BD41";
"VSS_BD43":   PN = "BD43"  !CDS_PN = "BD43";
"VSS_BE1":   PN = "BE1"  !CDS_PN = "BE1";
"VSS_BE3":   PN = "BE3"  !CDS_PN = "BE3";
"VSS_BE41":   PN = "BE41"  !CDS_PN = "BE41";
"VSS_BE43":   PN = "BE43"  !CDS_PN = "BE43";
"VSS_BG4":   PN = "BG4"  !CDS_PN = "BG4";
"VSS_BG6":   PN = "BG6"  !CDS_PN = "BG6";
"VSS_BG38":   PN = "BG38"  !CDS_PN = "BG38";
"VSS_BG41":   PN = "BG41"  !CDS_PN = "BG41";
"VSS_C3":   PN = "C3"  !CDS_PN = "C3";
"VSS_C41":   PN = "C41"  !CDS_PN = "C41";
"VSS_C43":   PN = "C43"  !CDS_PN = "C43";
"VSS_D1":   PN = "D1"  !CDS_PN = "D1";
"VSS_D3":   PN = "D3"  !CDS_PN = "D3";
"VSS_D41":   PN = "D41"  !CDS_PN = "D41";
"VSS_D43":   PN = "D43"  !CDS_PN = "D43";
"VSS_E2":   PN = "E2"  !CDS_PN = "E2";
"VSS_E42":   PN = "E42"  !CDS_PN = "E42";
"VSS_F43":   PN = "F43"  !CDS_PN = "F43";
DRAWING = "@s9s_mb_2u_lib.s9s_mb_2u(sch_1):page181";
BODY = "Q_CAP","I6": LOCATION = "C1178" #&CDS_LOCATION = "C1178" &SEC = "1" #&CDS_SEC = "1";
"A":   PN = "1"  !CDS_PN = "1";
"B":   PN = "2"  !CDS_PN = "2";
BODY = "Q_CAP","I7": LOCATION = "C1185" #&CDS_LOCATION = "C1185" &SEC = "1" #&CDS_SEC = "1";
"A":   PN = "1"  !CDS_PN = "1";
"B":   PN = "2"  !CDS_PN = "2";
BODY = "Q_CAP","I8": LOCATION = "C1192" #&CDS_LOCATION = "C1192" &SEC = "1" #&CDS_SEC = "1";
"A":   PN = "1"  !CDS_PN = "1";
"B":   PN = "2"  !CDS_PN = "2";
BODY = "Q_CAP","I12": LOCATION = "C1205" #&CDS_LOCATION = "C1205" &SEC = "1" #&CDS_SEC = "1";
"A":   PN = "1"  !CDS_PN = "1";
"B":   PN = "2"  !CDS_PN = "2";
BODY = "Q_CAP","I13": LOCATION = "C1228" #&CDS_LOCATION = "C1228" &SEC = "1" #&CDS_SEC = "1";
"A":   PN = "1"  !CDS_PN = "1";
"B":   PN = "2"  !CDS_PN = "2";
BODY = "Q_CAP","I25": LOCATION = "C1186" #&CDS_LOCATION = "C1186" &SEC = "1" #&CDS_SEC = "1";
"A":   PN = "1"  !CDS_PN = "1";
"B":   PN = "2"  !CDS_PN = "2";
BODY = "Q_CAP","I27": LOCATION = "C1181" #&CDS_LOCATION = "C1181" &SEC = "1" #&CDS_SEC = "1";
"A":   PN = "1"  !CDS_PN = "1";
"B":   PN = "2"  !CDS_PN = "2";
BODY = "Q_CAP","I29": LOCATION = "C1202" #&CDS_LOCATION = "C1202" &SEC = "1" #&CDS_SEC = "1";
"A":   PN = "1"  !CDS_PN = "1";
"B":   PN = "2"  !CDS_PN = "2";
BODY = "Q_CAP","I30": LOCATION = "C1197" #&CDS_LOCATION = "C1197" &SEC = "1" #&CDS_SEC = "1";
"A":   PN = "1"  !CDS_PN = "1";
"B":   PN = "2"  !CDS_PN = "2";
BODY = "Q_CAP","I32": LOCATION = "C1207" #&CDS_LOCATION = "C1207" &SEC = "1" #&CDS_SEC = "1";
"A":   PN = "1"  !CDS_PN = "1";
"B":   PN = "2"  !CDS_PN = "2";
BODY = "Q_CAP","I40": LOCATION = "C1187" #&CDS_LOCATION = "C1187" &SEC = "1" #&CDS_SEC = "1";
"A":   PN = "1"  !CDS_PN = "1";
"B":   PN = "2"  !CDS_PN = "2";
BODY = "Q_CAP","I42": LOCATION = "C1182" #&CDS_LOCATION = "C1182" &SEC = "1" #&CDS_SEC = "1";
"A":   PN = "1"  !CDS_PN = "1";
"B":   PN = "2"  !CDS_PN = "2";
BODY = "Q_CAP","I43": LOCATION = "C1198" #&CDS_LOCATION = "C1198" &SEC = "1" #&CDS_SEC = "1";
"A":   PN = "1"  !CDS_PN = "1";
"B":   PN = "2"  !CDS_PN = "2";
BODY = "Q_CAP","I45": LOCATION = "C1210" #&CDS_LOCATION = "C1210" &SEC = "1" #&CDS_SEC = "1";
"A":   PN = "1"  !CDS_PN = "1";
"B":   PN = "2"  !CDS_PN = "2";
BODY = "Q_CAP","I48": LOCATION = "C1203" #&CDS_LOCATION = "C1203" &SEC = "1" #&CDS_SEC = "1";
"A":   PN = "1"  !CDS_PN = "1";
"B":   PN = "2"  !CDS_PN = "2";
BODY = "Q_CAP","I49": LOCATION = "C1231" #&CDS_LOCATION = "C1231" &SEC = "1" #&CDS_SEC = "1";
"A":   PN = "1"  !CDS_PN = "1";
"B":   PN = "2"  !CDS_PN = "2";
BODY = "Q_CAP","I51": LOCATION = "C1183" #&CDS_LOCATION = "C1183" &SEC = "1" #&CDS_SEC = "1";
"A":   PN = "1"  !CDS_PN = "1";
"B":   PN = "2"  !CDS_PN = "2";
BODY = "Q_CAP","I58": LOCATION = "C1189" #&CDS_LOCATION = "C1189" &SEC = "1" #&CDS_SEC = "1";
"A":   PN = "1"  !CDS_PN = "1";
"B":   PN = "2"  !CDS_PN = "2";
BODY = "Q_CAP","I59": LOCATION = "C1200" #&CDS_LOCATION = "C1200" &SEC = "1" #&CDS_SEC = "1";
"A":   PN = "1"  !CDS_PN = "1";
"B":   PN = "2"  !CDS_PN = "2";
BODY = "Q_CAP","I60": LOCATION = "C1204" #&CDS_LOCATION = "C1204" &SEC = "1" #&CDS_SEC = "1";
"A":   PN = "1"  !CDS_PN = "1";
"B":   PN = "2"  !CDS_PN = "2";
BODY = "Q_CAP","I61": LOCATION = "C1214" #&CDS_LOCATION = "C1214" &SEC = "1" #&CDS_SEC = "1";
"A":   PN = "1"  !CDS_PN = "1";
"B":   PN = "2"  !CDS_PN = "2";
BODY = "Q_CAP","I63": LOCATION = "C1242" #&CDS_LOCATION = "C1242" &SEC = "1" #&CDS_SEC = "1";
"A":   PN = "1"  !CDS_PN = "1";
"B":   PN = "2"  !CDS_PN = "2";
BODY = "Q_CAP","I78": LOCATION = "C1206" #&CDS_LOCATION = "C1206" &SEC = "1" #&CDS_SEC = "1";
"A":   PN = "1"  !CDS_PN = "1";
"B":   PN = "2"  !CDS_PN = "2";
BODY = "Q_CAP","I87": LOCATION = "C1201" #&CDS_LOCATION = "C1201" &SEC = "1" #&CDS_SEC = "1";
"A":   PN = "1"  !CDS_PN = "1";
"B":   PN = "2"  !CDS_PN = "2";
BODY = "Q_CAP","I89": LOCATION = "C1191" #&CDS_LOCATION = "C1191" &SEC = "1" #&CDS_SEC = "1";
"A":   PN = "1"  !CDS_PN = "1";
"B":   PN = "2"  !CDS_PN = "2";
BODY = "Q_CAP","I91": LOCATION = "C1184" #&CDS_LOCATION = "C1184" &SEC = "1" #&CDS_SEC = "1";
"A":   PN = "1"  !CDS_PN = "1";
"B":   PN = "2"  !CDS_PN = "2";
BODY = "Q_CAP","I104": LOCATION = "C1262" #&CDS_LOCATION = "C1262" &SEC = "1" #&CDS_SEC = "1";
"A":   PN = "1"  !CDS_PN = "1";
"B":   PN = "2"  !CDS_PN = "2";
BODY = "Q_CAP","I110": LOCATION = "C1251" #&CDS_LOCATION = "C1251" &SEC = "1" #&CDS_SEC = "1";
"A":   PN = "1"  !CDS_PN = "1";
"B":   PN = "2"  !CDS_PN = "2";
BODY = "Q_CAP","I111": LOCATION = "C1254" #&CDS_LOCATION = "C1254" &SEC = "1" #&CDS_SEC = "1";
"A":   PN = "1"  !CDS_PN = "1";
"B":   PN = "2"  !CDS_PN = "2";
BODY = "Q_CAP","I119": LOCATION = "C1263" #&CDS_LOCATION = "C1263" &SEC = "1" #&CDS_SEC = "1";
"A":   PN = "1"  !CDS_PN = "1";
"B":   PN = "2"  !CDS_PN = "2";
BODY = "Q_CAP","I123": LOCATION = "C1255" #&CDS_LOCATION = "C1255" &SEC = "1" #&CDS_SEC = "1";
"A":   PN = "1"  !CDS_PN = "1";
"B":   PN = "2"  !CDS_PN = "2";
BODY = "Q_CAP","I125": LOCATION = "C1252" #&CDS_LOCATION = "C1252" &SEC = "1" #&CDS_SEC = "1";
"A":   PN = "1"  !CDS_PN = "1";
"B":   PN = "2"  !CDS_PN = "2";
BODY = "Q_CAP","I127": LOCATION = "C1266" #&CDS_LOCATION = "C1266" &SEC = "1" #&CDS_SEC = "1";
"A":   PN = "1"  !CDS_PN = "1";
"B":   PN = "2"  !CDS_PN = "2";
BODY = "Q_RES","I129": LOCATION = "R1463" #&CDS_LOCATION = "R1463" &SEC = "1" #&CDS_SEC = "1";
"A":   PN = "1"  !CDS_PN = "1";
"B":   PN = "2"  !CDS_PN = "2";
BODY = "Q_CAP","I131": LOCATION = "C1260" #&CDS_LOCATION = "C1260" &SEC = "1" #&CDS_SEC = "1";
"A":   PN = "1"  !CDS_PN = "1";
"B":   PN = "2"  !CDS_PN = "2";
BODY = "Q_CAP","I133": LOCATION = "C1264" #&CDS_LOCATION = "C1264" &SEC = "1" #&CDS_SEC = "1";
"A":   PN = "1"  !CDS_PN = "1";
"B":   PN = "2"  !CDS_PN = "2";
BODY = "Q_CAP","I136": LOCATION = "C1256" #&CDS_LOCATION = "C1256" &SEC = "1" #&CDS_SEC = "1";
"A":   PN = "1"  !CDS_PN = "1";
"B":   PN = "2"  !CDS_PN = "2";
BODY = "Q_CAP","I137": LOCATION = "C1250" #&CDS_LOCATION = "C1250" &SEC = "1" #&CDS_SEC = "1";
"A":   PN = "1"  !CDS_PN = "1";
"B":   PN = "2"  !CDS_PN = "2";
BODY = "Q_CAP","I140": LOCATION = "C1265" #&CDS_LOCATION = "C1265" &SEC = "1" #&CDS_SEC = "1";
"A":   PN = "1"  !CDS_PN = "1";
"B":   PN = "2"  !CDS_PN = "2";
BODY = "Q_CAP","I142": LOCATION = "C1261" #&CDS_LOCATION = "C1261" &SEC = "1" #&CDS_SEC = "1";
"A":   PN = "1"  !CDS_PN = "1";
"B":   PN = "2"  !CDS_PN = "2";
BODY = "Q_RES","I144": LOCATION = "R1464" #&CDS_LOCATION = "R1464" &SEC = "1" #&CDS_SEC = "1";
"A":   PN = "1"  !CDS_PN = "1";
"B":   PN = "2"  !CDS_PN = "2";
BODY = "Q_INDUCTOR","I145": LOCATION = "L10" #&CDS_LOCATION = "L10" &SEC = "1" #&CDS_SEC = "1";
"1":   PN = "1"  !CDS_PN = "1";
"2":   PN = "2"  !CDS_PN = "2";
BODY = "Q_CAP","I146": LOCATION = "C1257" #&CDS_LOCATION = "C1257" &SEC = "1" #&CDS_SEC = "1";
"A":   PN = "1"  !CDS_PN = "1";
"B":   PN = "2"  !CDS_PN = "2";
BODY = "Q_CAP","I147": LOCATION = "C1253" #&CDS_LOCATION = "C1253" &SEC = "1" #&CDS_SEC = "1";
"A":   PN = "1"  !CDS_PN = "1";
"B":   PN = "2"  !CDS_PN = "2";
BODY = "Q_CAP","I151": #LOCATION = "C1273" !CDS_LOCATION = "C1273" &SEC = "1" #&CDS_SEC = "1";
"A":   PN = "1"  !CDS_PN = "1";
"B":   PN = "2"  !CDS_PN = "2";
BODY = "Q_CAP","I152": #LOCATION = "C1244" !CDS_LOCATION = "C1244" &SEC = "1" #&CDS_SEC = "1";
"A":   PN = "1"  !CDS_PN = "1";
"B":   PN = "2"  !CDS_PN = "2";
BODY = "Q_CAP","I153": #LOCATION = "C1246" !CDS_LOCATION = "C1246" &SEC = "1" #&CDS_SEC = "1";
"A":   PN = "1"  !CDS_PN = "1";
"B":   PN = "2"  !CDS_PN = "2";
BODY = "Q_CAP","I154": #LOCATION = "C1247" !CDS_LOCATION = "C1247" &SEC = "1" #&CDS_SEC = "1";
"A":   PN = "1"  !CDS_PN = "1";
"B":   PN = "2"  !CDS_PN = "2";
BODY = "Q_CAP","I155": #LOCATION = "C1248" !CDS_LOCATION = "C1248" &SEC = "1" #&CDS_SEC = "1";
"A":   PN = "1"  !CDS_PN = "1";
"B":   PN = "2"  !CDS_PN = "2";
BODY = "Q_CAP","I156": #LOCATION = "C1249" !CDS_LOCATION = "C1249" &SEC = "1" #&CDS_SEC = "1";
"A":   PN = "1"  !CDS_PN = "1";
"B":   PN = "2"  !CDS_PN = "2";
BODY = "Q_CAP","I157": #LOCATION = "C1258" !CDS_LOCATION = "C1258" &SEC = "1" #&CDS_SEC = "1";
"A":   PN = "1"  !CDS_PN = "1";
"B":   PN = "2"  !CDS_PN = "2";
BODY = "Q_CAP","I158": #LOCATION = "C1259" !CDS_LOCATION = "C1259" &SEC = "1" #&CDS_SEC = "1";
"A":   PN = "1"  !CDS_PN = "1";
"B":   PN = "2"  !CDS_PN = "2";
BODY = "Q_CAP","I159": #LOCATION = "C1272" !CDS_LOCATION = "C1272" &SEC = "1" #&CDS_SEC = "1";
"A":   PN = "1"  !CDS_PN = "1";
"B":   PN = "2"  !CDS_PN = "2";
BODY = "Q_CAP","I162": #LOCATION = "C1243" !CDS_LOCATION = "C1243" &SEC = "1" #&CDS_SEC = "1";
"A":   PN = "1"  !CDS_PN = "1";
"B":   PN = "2"  !CDS_PN = "2";
BODY = "Q_CAP","I163": #LOCATION = "C1245" !CDS_LOCATION = "C1245" &SEC = "1" #&CDS_SEC = "1";
"A":   PN = "1"  !CDS_PN = "1";
"B":   PN = "2"  !CDS_PN = "2";
BODY = "Q_INDUCTOR","I164": #LOCATION = "L2" !CDS_LOCATION = "L2" &SEC = "1" #&CDS_SEC = "1";
"1":   PN = "1"  !CDS_PN = "1";
"2":   PN = "2"  !CDS_PN = "2";
BODY = "Q_RES","I165": LOCATION = "R4803" #&CDS_LOCATION = "R4803" &SEC = "1" #&CDS_SEC = "1";
"A":   PN = "1"  !CDS_PN = "1";
"B":   PN = "2"  !CDS_PN = "2";
DRAWING = "@s9s_mb_2u_lib.s9s_mb_2u(sch_1):page182";
BODY = "Q_CAP","I88": #LOCATION = "C1920" !CDS_LOCATION = "C1920" &SEC = "1" #&CDS_SEC = "1";
"A":   PN = "1"  !CDS_PN = "1";
"B":   PN = "2"  !CDS_PN = "2";
BODY = "Q_CAP","I90": #LOCATION = "C1921" !CDS_LOCATION = "C1921" &SEC = "1" #&CDS_SEC = "1";
"A":   PN = "1"  !CDS_PN = "1";
"B":   PN = "2"  !CDS_PN = "2";
BODY = "Q_CAP","I96": #LOCATION = "C1922" !CDS_LOCATION = "C1922" &SEC = "1" #&CDS_SEC = "1";
"A":   PN = "1"  !CDS_PN = "1";
"B":   PN = "2"  !CDS_PN = "2";
BODY = "Q_CAP","I97": #LOCATION = "C1923" !CDS_LOCATION = "C1923" &SEC = "1" #&CDS_SEC = "1";
"A":   PN = "1"  !CDS_PN = "1";
"B":   PN = "2"  !CDS_PN = "2";
BODY = "Q_CAP","I98": #LOCATION = "C1924" !CDS_LOCATION = "C1924" &SEC = "1" #&CDS_SEC = "1";
"A":   PN = "1"  !CDS_PN = "1";
"B":   PN = "2"  !CDS_PN = "2";
BODY = "Q_CAP","I100": #LOCATION = "C1925" !CDS_LOCATION = "C1925" &SEC = "1" #&CDS_SEC = "1";
"A":   PN = "1"  !CDS_PN = "1";
"B":   PN = "2"  !CDS_PN = "2";
BODY = "Q_RES","I105": LOCATION = "R1605" #&CDS_LOCATION = "R1605" &SEC = "1" #&CDS_SEC = "1";
"A":   PN = "1"  !CDS_PN = "1";
"B":   PN = "2"  !CDS_PN = "2";
BODY = "Q_RES","I162": LOCATION = "R486" #&CDS_LOCATION = "R486" &SEC = "1" #&CDS_SEC = "1";
"A":   PN = "1"  !CDS_PN = "1";
"B":   PN = "2"  !CDS_PN = "2";
BODY = "Q_RES","I164": LOCATION = "R491" #&CDS_LOCATION = "R491" &SEC = "1" #&CDS_SEC = "1";
"A":   PN = "1"  !CDS_PN = "1";
"B":   PN = "2"  !CDS_PN = "2";
BODY = "Q_RES","I167": LOCATION = "R1396" #&CDS_LOCATION = "R1396" &SEC = "1" #&CDS_SEC = "1";
"A":   PN = "1"  !CDS_PN = "1";
"B":   PN = "2"  !CDS_PN = "2";
BODY = "Q_RES","I173": LOCATION = "R487" #&CDS_LOCATION = "R487" &SEC = "1" #&CDS_SEC = "1";
"A":   PN = "1"  !CDS_PN = "1";
"B":   PN = "2"  !CDS_PN = "2";
BODY = "Q_RES","I176": LOCATION = "R478" #&CDS_LOCATION = "R478" &SEC = "1" #&CDS_SEC = "1";
"A":   PN = "1"  !CDS_PN = "1";
"B":   PN = "2"  !CDS_PN = "2";
BODY = "SCONN75K_APCI0155P004A","I178": LOCATION = "J59" #&CDS_LOCATION = "J59" &SEC = "1" #&CDS_SEC = "1";
"3.3V_1":   PN = "2"  !CDS_PN = "2";
"3.3V_2":   PN = "4"  !CDS_PN = "4";
"3.3V_3":   PN = "12"  !CDS_PN = "12";
"3.3V_4":   PN = "14"  !CDS_PN = "14";
"3.3V_5":   PN = "16"  !CDS_PN = "16";
"3.3V_6":   PN = "18"  !CDS_PN = "18";
"3.3V_7":   PN = "70"  !CDS_PN = "70";
"3.3V_8":   PN = "72"  !CDS_PN = "72";
"3.3V_9":   PN = "74"  !CDS_PN = "74";
"CLKREQ#":   PN = "52"  !CDS_PN = "52";
"DAS_DSS#||LED1#":   PN = "10"  !CDS_PN = "10";
"DEVSLP":   PN = "38"  !CDS_PN = "38";
"G1":   PN = "G1"  !CDS_PN = "G1";
"G2":   PN = "G2"  !CDS_PN = "G2";
"GND1":   PN = "1"  !CDS_PN = "1";
"GND2":   PN = "3"  !CDS_PN = "3";
"GND3":   PN = "9"  !CDS_PN = "9";
"GND4":   PN = "15"  !CDS_PN = "15";
"GND5":   PN = "21"  !CDS_PN = "21";
"GND6":   PN = "27"  !CDS_PN = "27";
"GND7":   PN = "33"  !CDS_PN = "33";
"GND8":   PN = "39"  !CDS_PN = "39";
"GND9":   PN = "45"  !CDS_PN = "45";
"GND10":   PN = "51"  !CDS_PN = "51";
"GND11":   PN = "57"  !CDS_PN = "57";
"GND12":   PN = "71"  !CDS_PN = "71";
"GND13":   PN = "73"  !CDS_PN = "73";
"GND14":   PN = "75"  !CDS_PN = "75";
"NC1":   PN = "6"  !CDS_PN = "6";
"NC2":   PN = "8"  !CDS_PN = "8";
"NC3":   PN = "20"  !CDS_PN = "20";
"NC4":   PN = "22"  !CDS_PN = "22";
"NC5":   PN = "24"  !CDS_PN = "24";
"NC6":   PN = "26"  !CDS_PN = "26";
"NC7":   PN = "28"  !CDS_PN = "28";
"NC8":   PN = "30"  !CDS_PN = "30";
"NC9":   PN = "32"  !CDS_PN = "32";
"NC10":   PN = "34"  !CDS_PN = "34";
"NC11":   PN = "36"  !CDS_PN = "36";
"NC12":   PN = "40"  !CDS_PN = "40";
"NC13":   PN = "42"  !CDS_PN = "42";
"NC14":   PN = "44"  !CDS_PN = "44";
"NC15":   PN = "46"  !CDS_PN = "46";
"NC16":   PN = "48"  !CDS_PN = "48";
"NC17":   PN = "56"  !CDS_PN = "56";
"NC18":   PN = "58"  !CDS_PN = "58";
"NC19":   PN = "67"  !CDS_PN = "67";
"PEDET":   PN = "69"  !CDS_PN = "69";
"PERN0||SATA-B+":   PN = "41"  !CDS_PN = "41";
"PERN1":   PN = "29"  !CDS_PN = "29";
"PERN2":   PN = "17"  !CDS_PN = "17";
"PERN3":   PN = "5"  !CDS_PN = "5";
"PERP0||SATA-B-":   PN = "43"  !CDS_PN = "43";
"PERP1":   PN = "31"  !CDS_PN = "31";
"PERP2":   PN = "19"  !CDS_PN = "19";
"PERP3":   PN = "7"  !CDS_PN = "7";
"PERST#":   PN = "50"  !CDS_PN = "50";
"PETN0||SATA-A-":   PN = "47"  !CDS_PN = "47";
"PETN1":   PN = "35"  !CDS_PN = "35";
"PETN2":   PN = "23"  !CDS_PN = "23";
"PETN3":   PN = "11"  !CDS_PN = "11";
"PETP0||SATA-A+":   PN = "49"  !CDS_PN = "49";
"PETP1":   PN = "37"  !CDS_PN = "37";
"PETP2":   PN = "25"  !CDS_PN = "25";
"PETP3":   PN = "13"  !CDS_PN = "13";
"PEWAKE#":   PN = "54"  !CDS_PN = "54";
"REFCLKN":   PN = "53"  !CDS_PN = "53";
"REFCLKP":   PN = "55"  !CDS_PN = "55";
"SUSCLK":   PN = "68"  !CDS_PN = "68";
BODY = "Q_RES","I247": LOCATION = "R2526" #&CDS_LOCATION = "R2526" &SEC = "1" #&CDS_SEC = "1";
"A":   PN = "1"  !CDS_PN = "1";
"B":   PN = "2"  !CDS_PN = "2";
BODY = "Q_RES","I299": #LOCATION = "R3301" !CDS_LOCATION = "R3301" &SEC = "1" #&CDS_SEC = "1";
"A":   PN = "1"  !CDS_PN = "1";
"B":   PN = "2"  !CDS_PN = "2";
BODY = "Q_RES","I303": LOCATION = "R3297" #&CDS_LOCATION = "R3297" &SEC = "1" #&CDS_SEC = "1";
"A":   PN = "1"  !CDS_PN = "1";
"B":   PN = "2"  !CDS_PN = "2";
BODY = "Q_RES","I306": LOCATION = "R3298" #&CDS_LOCATION = "R3298" &SEC = "1" #&CDS_SEC = "1";
"A":   PN = "1"  !CDS_PN = "1";
"B":   PN = "2"  !CDS_PN = "2";
BODY = "Q_CAP","I308": LOCATION = "C1873" #&CDS_LOCATION = "C1873" &SEC = "1" #&CDS_SEC = "1";
"A":   PN = "1"  !CDS_PN = "1";
"B":   PN = "2"  !CDS_PN = "2";
BODY = "Q_RES","I312": LOCATION = "R5377" #&CDS_LOCATION = "R5377" &SEC = "1" #&CDS_SEC = "1";
"A":   PN = "1"  !CDS_PN = "1";
"B":   PN = "2"  !CDS_PN = "2";
BODY = "74LVC1G126SE7","I315": LOCATION = "U239" #&CDS_LOCATION = "U239" &SEC = "1" #&CDS_SEC = "1";
"A":   PN = "2"  !CDS_PN = "2";
"GND":   PN = "3"  !CDS_PN = "3";
"OE":   PN = "1"  !CDS_PN = "1";
"VCC":   PN = "5"  !CDS_PN = "5";
"Y":   PN = "4"  !CDS_PN = "4";
BODY = "Q_RES","I317": LOCATION = "R3295" #&CDS_LOCATION = "R3295" &SEC = "1" #&CDS_SEC = "1";
"A":   PN = "1"  !CDS_PN = "1";
"B":   PN = "2"  !CDS_PN = "2";
BODY = "Q_RES","I320": LOCATION = "R3294" #&CDS_LOCATION = "R3294" &SEC = "1" #&CDS_SEC = "1";
"A":   PN = "1"  !CDS_PN = "1";
"B":   PN = "2"  !CDS_PN = "2";
BODY = "Q_RES","I324": LOCATION = "R3296" #&CDS_LOCATION = "R3296" &SEC = "1" #&CDS_SEC = "1";
"A":   PN = "1"  !CDS_PN = "1";
"B":   PN = "2"  !CDS_PN = "2";
BODY = "Q_CAP","I326": LOCATION = "C2007" #&CDS_LOCATION = "C2007" &SEC = "1" #&CDS_SEC = "1";
"A":   PN = "1"  !CDS_PN = "1";
"B":   PN = "2"  !CDS_PN = "2";
BODY = "SN74LVC2G07DCKR","I327": LOCATION = "U259" #&CDS_LOCATION = "U259" &SEC = "1" #&CDS_SEC = "1";
"1A":   PN = "1"  !CDS_PN = "1";
"1Y":   PN = "6"  !CDS_PN = "6";
"2A":   PN = "3"  !CDS_PN = "3";
"2Y":   PN = "4"  !CDS_PN = "4";
"GND":   PN = "2"  !CDS_PN = "2";
"VCC":   PN = "5"  !CDS_PN = "5";
BODY = "Q_RES","I337": LOCATION = "R2121" #&CDS_LOCATION = "R2121" &SEC = "1" #&CDS_SEC = "1";
"A":   PN = "1"  !CDS_PN = "1";
"B":   PN = "2"  !CDS_PN = "2";
BODY = "MOSFET_NCH_DUAL","I342": #LOCATION = "Q95" !CDS_LOCATION = "Q95" &SEC = "1" #&CDS_SEC = "1";
"D1":   PN = "6"  !CDS_PN = "6";
"G1":   PN = "2"  !CDS_PN = "2";
"S1":   PN = "1"  !CDS_PN = "1";
BODY = "MOSFET_NCH_DUAL","I343": #LOCATION = "Q95" !CDS_LOCATION = "Q95" &SEC = "2" #&CDS_SEC = "2";
"D2":   PN = "3"  !CDS_PN = "3";
"G2":   PN = "5"  !CDS_PN = "5";
"S2":   PN = "4"  !CDS_PN = "4";
BODY = "Q_RES","I344": #LOCATION = "R2113" !CDS_LOCATION = "R2113" &SEC = "1" #&CDS_SEC = "1";
"A":   PN = "1"  !CDS_PN = "1";
"B":   PN = "2"  !CDS_PN = "2";
DRAWING = "@s9s_mb_2u_lib.s9s_mb_2u(sch_1):page183";
BODY = "Q_RES","I5": LOCATION = "R1271" #&CDS_LOCATION = "R1271" &SEC = "1" #&CDS_SEC = "1";
"A":   PN = "1"  !CDS_PN = "1";
"B":   PN = "2"  !CDS_PN = "2";
BODY = "PCA9306DP1","I27": LOCATION = "U98" #&CDS_LOCATION = "U98" &SEC = "1" #&CDS_SEC = "1";
"EN":   PN = "8"  !CDS_PN = "8";
"GND":   PN = "1"  !CDS_PN = "1";
"SCL1":   PN = "3"  !CDS_PN = "3";
"SCL2":   PN = "6"  !CDS_PN = "6";
"SDA1":   PN = "4"  !CDS_PN = "4";
"SDA2":   PN = "5"  !CDS_PN = "5";
"VREF1":   PN = "2"  !CDS_PN = "2";
"VREF2":   PN = "7"  !CDS_PN = "7";
BODY = "Q_CAP","I28": LOCATION = "C1323" #&CDS_LOCATION = "C1323" &SEC = "1" #&CDS_SEC = "1";
"A":   PN = "1"  !CDS_PN = "1";
"B":   PN = "2"  !CDS_PN = "2";
BODY = "Q_RES","I43": LOCATION = "R1702" #&CDS_LOCATION = "R1702" &SEC = "1" #&CDS_SEC = "1";
"A":   PN = "1"  !CDS_PN = "1";
"B":   PN = "2"  !CDS_PN = "2";
BODY = "Q_RES","I45": LOCATION = "R1703" #&CDS_LOCATION = "R1703" &SEC = "1" #&CDS_SEC = "1";
"A":   PN = "1"  !CDS_PN = "1";
"B":   PN = "2"  !CDS_PN = "2";
BODY = "Q_CAP","I52": LOCATION = "C1305" #&CDS_LOCATION = "C1305" &SEC = "1" #&CDS_SEC = "1";
"A":   PN = "1"  !CDS_PN = "1";
"B":   PN = "2"  !CDS_PN = "2";
BODY = "Q_RES","I65": LOCATION = "R2410" #&CDS_LOCATION = "R2410" &SEC = "1" #&CDS_SEC = "1";
"A":   PN = "1"  !CDS_PN = "1";
"B":   PN = "2"  !CDS_PN = "2";
BODY = "Q_RES","I66": LOCATION = "R2411" #&CDS_LOCATION = "R2411" &SEC = "1" #&CDS_SEC = "1";
"A":   PN = "1"  !CDS_PN = "1";
"B":   PN = "2"  !CDS_PN = "2";
BODY = "Q_RES","I70": LOCATION = "R2476" #&CDS_LOCATION = "R2476" &SEC = "1" #&CDS_SEC = "1";
"A":   PN = "1"  !CDS_PN = "1";
"B":   PN = "2"  !CDS_PN = "2";
BODY = "Q_RES","I72": LOCATION = "R1700" #&CDS_LOCATION = "R1700" &SEC = "1" #&CDS_SEC = "1";
"A":   PN = "1"  !CDS_PN = "1";
"B":   PN = "2"  !CDS_PN = "2";
BODY = "Q_RES","I76": LOCATION = "R3533" #&CDS_LOCATION = "R3533" &SEC = "1" #&CDS_SEC = "1";
"A":   PN = "1"  !CDS_PN = "1";
"B":   PN = "2"  !CDS_PN = "2";
BODY = "Q_RES","I77": LOCATION = "R3534" #&CDS_LOCATION = "R3534" &SEC = "1" #&CDS_SEC = "1";
"A":   PN = "1"  !CDS_PN = "1";
"B":   PN = "2"  !CDS_PN = "2";
BODY = "Q_RES","I78": LOCATION = "R3532" #&CDS_LOCATION = "R3532" &SEC = "1" #&CDS_SEC = "1";
"A":   PN = "1"  !CDS_PN = "1";
"B":   PN = "2"  !CDS_PN = "2";
BODY = "Q_RES","I80": LOCATION = "R3530" #&CDS_LOCATION = "R3530" &SEC = "1" #&CDS_SEC = "1";
"A":   PN = "1"  !CDS_PN = "1";
"B":   PN = "2"  !CDS_PN = "2";
BODY = "Q_CAP","I82": LOCATION = "C1998" #&CDS_LOCATION = "C1998" &SEC = "1" #&CDS_SEC = "1";
"A":   PN = "1"  !CDS_PN = "1";
"B":   PN = "2"  !CDS_PN = "2";
BODY = "Q_CAP","I89": LOCATION = "C1997" #&CDS_LOCATION = "C1997" &SEC = "1" #&CDS_SEC = "1";
"A":   PN = "1"  !CDS_PN = "1";
"B":   PN = "2"  !CDS_PN = "2";
BODY = "PCA9617ADP","I93": LOCATION = "U279" #&CDS_LOCATION = "U279" &SEC = "1" #&CDS_SEC = "1";
"EN":   PN = "5"  !CDS_PN = "5";
"GND":   PN = "4"  !CDS_PN = "4";
"SCLA":   PN = "2"  !CDS_PN = "2";
"SCLB":   PN = "7"  !CDS_PN = "7";
"SDAA":   PN = "3"  !CDS_PN = "3";
"SDAB":   PN = "6"  !CDS_PN = "6";
"VCCA":   PN = "1"  !CDS_PN = "1";
"VCCB":   PN = "8"  !CDS_PN = "8";
BODY = "Q_RES","I96": LOCATION = "R3531" #&CDS_LOCATION = "R3531" &SEC = "1" #&CDS_SEC = "1";
"A":   PN = "1"  !CDS_PN = "1";
"B":   PN = "2"  !CDS_PN = "2";
BODY = "Q_RES","I99": #LOCATION = "R3529" !CDS_LOCATION = "R3529" &SEC = "1" #&CDS_SEC = "1";
"A":   PN = "1"  !CDS_PN = "1";
"B":   PN = "2"  !CDS_PN = "2";
DRAWING = "@s9s_mb_2u_lib.s9s_mb_2u(sch_1):page185";
BODY = "Q_RES","I24": LOCATION = "R149" #&CDS_LOCATION = "R149" &SEC = "1" #&CDS_SEC = "1";
"A":   PN = "1"  !CDS_PN = "1";
"B":   PN = "2"  !CDS_PN = "2";
BODY = "Q_RES","I26": LOCATION = "R145" #&CDS_LOCATION = "R145" &SEC = "1" #&CDS_SEC = "1";
"A":   PN = "1"  !CDS_PN = "1";
"B":   PN = "2"  !CDS_PN = "2";
BODY = "Q_RES","I30": LOCATION = "R146" #&CDS_LOCATION = "R146" &SEC = "1" #&CDS_SEC = "1";
"A":   PN = "1"  !CDS_PN = "1";
"B":   PN = "2"  !CDS_PN = "2";
BODY = "Q_RES","I32": LOCATION = "R1297" #&CDS_LOCATION = "R1297" &SEC = "1" #&CDS_SEC = "1";
"A":   PN = "1"  !CDS_PN = "1";
"B":   PN = "2"  !CDS_PN = "2";
BODY = "NC7SB3157","I35": LOCATION = "U142" #&CDS_LOCATION = "U142" #SEC = "1" !CDS_SEC = "1";
"A":   PN = "4"  !CDS_PN = "4";
"B0":   PN = "3"  !CDS_PN = "3";
"B1":   PN = "1"  !CDS_PN = "1";
"GND":   PN = "2"  !CDS_PN = "2";
"S":   PN = "6"  !CDS_PN = "6";
"VCC":   PN = "5"  !CDS_PN = "5";
BODY = "Q_CAP","I36": LOCATION = "C1612" #&CDS_LOCATION = "C1612" &SEC = "1" #&CDS_SEC = "1";
"A":   PN = "1"  !CDS_PN = "1";
"B":   PN = "2"  !CDS_PN = "2";
BODY = "Q_RES","I39": LOCATION = "R2253" #&CDS_LOCATION = "R2253" &SEC = "1" #&CDS_SEC = "1";
"A":   PN = "1"  !CDS_PN = "1";
"B":   PN = "2"  !CDS_PN = "2";
BODY = "Q_RES","I41": LOCATION = "R2255" #&CDS_LOCATION = "R2255" &SEC = "1" #&CDS_SEC = "1";
"A":   PN = "1"  !CDS_PN = "1";
"B":   PN = "2"  !CDS_PN = "2";
BODY = "Q_RES","I42": LOCATION = "R2252" #&CDS_LOCATION = "R2252" &SEC = "1" #&CDS_SEC = "1";
"A":   PN = "1"  !CDS_PN = "1";
"B":   PN = "2"  !CDS_PN = "2";
BODY = "Q_RES","I45": LOCATION = "R3064" #&CDS_LOCATION = "R3064" &SEC = "1" #&CDS_SEC = "1";
"A":   PN = "1"  !CDS_PN = "1";
"B":   PN = "2"  !CDS_PN = "2";
BODY = "Q_RES","I47": #LOCATION = "R143" !CDS_LOCATION = "R143" &SEC = "1" #&CDS_SEC = "1";
"A":   PN = "1"  !CDS_PN = "1";
"B":   PN = "2"  !CDS_PN = "2";
BODY = "Q_RES","I49": #LOCATION = "R148" !CDS_LOCATION = "R148" &SEC = "1" #&CDS_SEC = "1";
"A":   PN = "1"  !CDS_PN = "1";
"B":   PN = "2"  !CDS_PN = "2";
BODY = "Q_RES","I50": #LOCATION = "R147" !CDS_LOCATION = "R147" &SEC = "1" #&CDS_SEC = "1";
"A":   PN = "1"  !CDS_PN = "1";
"B":   PN = "2"  !CDS_PN = "2";
BODY = "Q_RES","I51": #LOCATION = "R144" !CDS_LOCATION = "R144" &SEC = "1" #&CDS_SEC = "1";
"A":   PN = "1"  !CDS_PN = "1";
"B":   PN = "2"  !CDS_PN = "2";
DRAWING = "@s9s_mb_2u_lib.s9s_mb_2u(sch_1):page186";
BODY = "Q_RES","I11": LOCATION = "R367" #&CDS_LOCATION = "R367" &SEC = "1" #&CDS_SEC = "1";
"A":   PN = "1"  !CDS_PN = "1";
"B":   PN = "2"  !CDS_PN = "2";
BODY = "Q_RES","I16": LOCATION = "R369" #&CDS_LOCATION = "R369" &SEC = "1" #&CDS_SEC = "1";
"A":   PN = "1"  !CDS_PN = "1";
"B":   PN = "2"  !CDS_PN = "2";
BODY = "Q_RES","I45": LOCATION = "R371" #&CDS_LOCATION = "R371" &SEC = "1" #&CDS_SEC = "1";
"A":   PN = "1"  !CDS_PN = "1";
"B":   PN = "2"  !CDS_PN = "2";
BODY = "Q_RES","I46": LOCATION = "R372" #&CDS_LOCATION = "R372" &SEC = "1" #&CDS_SEC = "1";
"A":   PN = "1"  !CDS_PN = "1";
"B":   PN = "2"  !CDS_PN = "2";
BODY = "Q_RES","I60": LOCATION = "R374" #&CDS_LOCATION = "R374" &SEC = "1" #&CDS_SEC = "1";
"A":   PN = "1"  !CDS_PN = "1";
"B":   PN = "2"  !CDS_PN = "2";
BODY = "Q_RES","I61": LOCATION = "R375" #&CDS_LOCATION = "R375" &SEC = "1" #&CDS_SEC = "1";
"A":   PN = "1"  !CDS_PN = "1";
"B":   PN = "2"  !CDS_PN = "2";
BODY = "Q_RES","I68": LOCATION = "R502" #&CDS_LOCATION = "R502" &SEC = "1" #&CDS_SEC = "1";
"A":   PN = "1"  !CDS_PN = "1";
"B":   PN = "2"  !CDS_PN = "2";
BODY = "Q_RES","I76": LOCATION = "R379" #&CDS_LOCATION = "R379" &SEC = "1" #&CDS_SEC = "1";
"A":   PN = "1"  !CDS_PN = "1";
"B":   PN = "2"  !CDS_PN = "2";
BODY = "Q_RES","I77": LOCATION = "R378" #&CDS_LOCATION = "R378" &SEC = "1" #&CDS_SEC = "1";
"A":   PN = "1"  !CDS_PN = "1";
"B":   PN = "2"  !CDS_PN = "2";
BODY = "Q_RES","I78": LOCATION = "R380" #&CDS_LOCATION = "R380" &SEC = "1" #&CDS_SEC = "1";
"A":   PN = "1"  !CDS_PN = "1";
"B":   PN = "2"  !CDS_PN = "2";
BODY = "Q_RES","I81": LOCATION = "R381" #&CDS_LOCATION = "R381" &SEC = "1" #&CDS_SEC = "1";
"A":   PN = "1"  !CDS_PN = "1";
"B":   PN = "2"  !CDS_PN = "2";
BODY = "Q_RES","I88": LOCATION = "R1810" #&CDS_LOCATION = "R1810" &SEC = "1" #&CDS_SEC = "1";
"A":   PN = "1"  !CDS_PN = "1";
"B":   PN = "2"  !CDS_PN = "2";
BODY = "Q_RES","I89": LOCATION = "R1809" #&CDS_LOCATION = "R1809" &SEC = "1" #&CDS_SEC = "1";
"A":   PN = "1"  !CDS_PN = "1";
"B":   PN = "2"  !CDS_PN = "2";
BODY = "Q_RES","I90": LOCATION = "R1962" #&CDS_LOCATION = "R1962" &SEC = "1" #&CDS_SEC = "1";
"A":   PN = "1"  !CDS_PN = "1";
"B":   PN = "2"  !CDS_PN = "2";
BODY = "Q_RES","I92": LOCATION = "R3325" #&CDS_LOCATION = "R3325" &SEC = "1" #&CDS_SEC = "1";
"A":   PN = "1"  !CDS_PN = "1";
"B":   PN = "2"  !CDS_PN = "2";
DRAWING = "@s9s_mb_2u_lib.s9s_mb_2u(sch_1):page187";
BODY = "Q_RES","I13": LOCATION = "R623" #&CDS_LOCATION = "R623" &SEC = "1" #&CDS_SEC = "1";
"A":   PN = "1"  !CDS_PN = "1";
"B":   PN = "2"  !CDS_PN = "2";
BODY = "Q_RES","I14": LOCATION = "R624" #&CDS_LOCATION = "R624" &SEC = "1" #&CDS_SEC = "1";
"A":   PN = "1"  !CDS_PN = "1";
"B":   PN = "2"  !CDS_PN = "2";
BODY = "Q_RES","I18": LOCATION = "R613" #&CDS_LOCATION = "R613" &SEC = "1" #&CDS_SEC = "1";
"A":   PN = "1"  !CDS_PN = "1";
"B":   PN = "2"  !CDS_PN = "2";
BODY = "Q_RES","I21": LOCATION = "R607" #&CDS_LOCATION = "R607" &SEC = "1" #&CDS_SEC = "1";
"A":   PN = "1"  !CDS_PN = "1";
"B":   PN = "2"  !CDS_PN = "2";
BODY = "Q_RES","I23": LOCATION = "R614" #&CDS_LOCATION = "R614" &SEC = "1" #&CDS_SEC = "1";
"A":   PN = "1"  !CDS_PN = "1";
"B":   PN = "2"  !CDS_PN = "2";
BODY = "Q_RES","I36": LOCATION = "R608" #&CDS_LOCATION = "R608" &SEC = "1" #&CDS_SEC = "1";
"A":   PN = "1"  !CDS_PN = "1";
"B":   PN = "2"  !CDS_PN = "2";
BODY = "Q_RES","I39": LOCATION = "R609" #&CDS_LOCATION = "R609" &SEC = "1" #&CDS_SEC = "1";
"A":   PN = "1"  !CDS_PN = "1";
"B":   PN = "2"  !CDS_PN = "2";
BODY = "Q_RES","I40": LOCATION = "R610" #&CDS_LOCATION = "R610" &SEC = "1" #&CDS_SEC = "1";
"A":   PN = "1"  !CDS_PN = "1";
"B":   PN = "2"  !CDS_PN = "2";
BODY = "Q_RES","I43": LOCATION = "R611" #&CDS_LOCATION = "R611" &SEC = "1" #&CDS_SEC = "1";
"A":   PN = "1"  !CDS_PN = "1";
"B":   PN = "2"  !CDS_PN = "2";
BODY = "Q_RES","I44": LOCATION = "R612" #&CDS_LOCATION = "R612" &SEC = "1" #&CDS_SEC = "1";
"A":   PN = "1"  !CDS_PN = "1";
"B":   PN = "2"  !CDS_PN = "2";
BODY = "Q_RES","I48": LOCATION = "R619" #&CDS_LOCATION = "R619" &SEC = "1" #&CDS_SEC = "1";
"A":   PN = "1"  !CDS_PN = "1";
"B":   PN = "2"  !CDS_PN = "2";
BODY = "Q_RES","I51": LOCATION = "R615" #&CDS_LOCATION = "R615" &SEC = "1" #&CDS_SEC = "1";
"A":   PN = "1"  !CDS_PN = "1";
"B":   PN = "2"  !CDS_PN = "2";
BODY = "Q_RES","I53": LOCATION = "R618" #&CDS_LOCATION = "R618" &SEC = "1" #&CDS_SEC = "1";
"A":   PN = "1"  !CDS_PN = "1";
"B":   PN = "2"  !CDS_PN = "2";
BODY = "Q_RES","I54": LOCATION = "R617" #&CDS_LOCATION = "R617" &SEC = "1" #&CDS_SEC = "1";
"A":   PN = "1"  !CDS_PN = "1";
"B":   PN = "2"  !CDS_PN = "2";
BODY = "Q_RES","I55": LOCATION = "R621" #&CDS_LOCATION = "R621" &SEC = "1" #&CDS_SEC = "1";
"A":   PN = "1"  !CDS_PN = "1";
"B":   PN = "2"  !CDS_PN = "2";
BODY = "Q_RES","I56": LOCATION = "R622" #&CDS_LOCATION = "R622" &SEC = "1" #&CDS_SEC = "1";
"A":   PN = "1"  !CDS_PN = "1";
"B":   PN = "2"  !CDS_PN = "2";
DRAWING = "@s9s_mb_2u_lib.s9s_mb_2u(sch_1):page188";
BODY = "Q_RES","I21": LOCATION = "R1299" #&CDS_LOCATION = "R1299" &SEC = "1" #&CDS_SEC = "1";
"A":   PN = "1"  !CDS_PN = "1";
"B":   PN = "2"  !CDS_PN = "2";
BODY = "Q_RES","I22": LOCATION = "R1298" #&CDS_LOCATION = "R1298" &SEC = "1" #&CDS_SEC = "1";
"A":   PN = "1"  !CDS_PN = "1";
"B":   PN = "2"  !CDS_PN = "2";
BODY = "Q_RES","I31": LOCATION = "R1311" #&CDS_LOCATION = "R1311" &SEC = "1" #&CDS_SEC = "1";
"A":   PN = "1"  !CDS_PN = "1";
"B":   PN = "2"  !CDS_PN = "2";
BODY = "Q_RES","I36": LOCATION = "R1457" #&CDS_LOCATION = "R1457" &SEC = "1" #&CDS_SEC = "1";
"A":   PN = "1"  !CDS_PN = "1";
"B":   PN = "2"  !CDS_PN = "2";
BODY = "Q_RES","I43": LOCATION = "R1476" #&CDS_LOCATION = "R1476" &SEC = "1" #&CDS_SEC = "1";
"A":   PN = "1"  !CDS_PN = "1";
"B":   PN = "2"  !CDS_PN = "2";
BODY = "Q_RES","I44": LOCATION = "R1475" #&CDS_LOCATION = "R1475" &SEC = "1" #&CDS_SEC = "1";
"A":   PN = "1"  !CDS_PN = "1";
"B":   PN = "2"  !CDS_PN = "2";
BODY = "Q_RES","I47": LOCATION = "R1477" #&CDS_LOCATION = "R1477" &SEC = "1" #&CDS_SEC = "1";
"A":   PN = "1"  !CDS_PN = "1";
"B":   PN = "2"  !CDS_PN = "2";
BODY = "Q_RES","I50": LOCATION = "R1478" #&CDS_LOCATION = "R1478" &SEC = "1" #&CDS_SEC = "1";
"A":   PN = "1"  !CDS_PN = "1";
"B":   PN = "2"  !CDS_PN = "2";
BODY = "Q_RES","I57": LOCATION = "R3038" #&CDS_LOCATION = "R3038" &SEC = "1" #&CDS_SEC = "1";
"A":   PN = "1"  !CDS_PN = "1";
"B":   PN = "2"  !CDS_PN = "2";
BODY = "Q_RES","I63": LOCATION = "R1220" #&CDS_LOCATION = "R1220" &SEC = "1" #&CDS_SEC = "1";
"A":   PN = "1"  !CDS_PN = "1";
"B":   PN = "2"  !CDS_PN = "2";
BODY = "Q_RES","I64": LOCATION = "R1221" #&CDS_LOCATION = "R1221" &SEC = "1" #&CDS_SEC = "1";
"A":   PN = "1"  !CDS_PN = "1";
"B":   PN = "2"  !CDS_PN = "2";
BODY = "Q_RES","I70": LOCATION = "R1497" #&CDS_LOCATION = "R1497" &SEC = "1" #&CDS_SEC = "1";
"A":   PN = "1"  !CDS_PN = "1";
"B":   PN = "2"  !CDS_PN = "2";
BODY = "Q_RES","I71": LOCATION = "R1496" #&CDS_LOCATION = "R1496" &SEC = "1" #&CDS_SEC = "1";
"A":   PN = "1"  !CDS_PN = "1";
"B":   PN = "2"  !CDS_PN = "2";
BODY = "Q_RES","I76": LOCATION = "R1498" #&CDS_LOCATION = "R1498" &SEC = "1" #&CDS_SEC = "1";
"A":   PN = "1"  !CDS_PN = "1";
"B":   PN = "2"  !CDS_PN = "2";
BODY = "Q_RES","I77": LOCATION = "R1499" #&CDS_LOCATION = "R1499" &SEC = "1" #&CDS_SEC = "1";
"A":   PN = "1"  !CDS_PN = "1";
"B":   PN = "2"  !CDS_PN = "2";
DRAWING = "@s9s_mb_2u_lib.s9s_mb_2u(sch_1):page190";
BODY = "Q_RES","I33": LOCATION = "R1214" #&CDS_LOCATION = "R1214" &SEC = "1" #&CDS_SEC = "1";
"A":   PN = "1"  !CDS_PN = "1";
"B":   PN = "2"  !CDS_PN = "2";
BODY = "NC7SB3157","I34": LOCATION = "U60" #&CDS_LOCATION = "U60" #SEC = "1" !CDS_SEC = "1";
"A":   PN = "4"  !CDS_PN = "4";
"B0":   PN = "3"  !CDS_PN = "3";
"B1":   PN = "1"  !CDS_PN = "1";
"GND":   PN = "2"  !CDS_PN = "2";
"S":   PN = "6"  !CDS_PN = "6";
"VCC":   PN = "5"  !CDS_PN = "5";
BODY = "Q_CAP","I36": LOCATION = "C607" #&CDS_LOCATION = "C607" &SEC = "1" #&CDS_SEC = "1";
"A":   PN = "1"  !CDS_PN = "1";
"B":   PN = "2"  !CDS_PN = "2";
BODY = "Q_CAP","I37": LOCATION = "C605" #&CDS_LOCATION = "C605" &SEC = "1" #&CDS_SEC = "1";
"A":   PN = "1"  !CDS_PN = "1";
"B":   PN = "2"  !CDS_PN = "2";
BODY = "Q_RES","I38": LOCATION = "R1215" #&CDS_LOCATION = "R1215" &SEC = "1" #&CDS_SEC = "1";
"A":   PN = "1"  !CDS_PN = "1";
"B":   PN = "2"  !CDS_PN = "2";
BODY = "NC7SB3157","I39": LOCATION = "U61" #&CDS_LOCATION = "U61" #SEC = "1" !CDS_SEC = "1";
"A":   PN = "4"  !CDS_PN = "4";
"B0":   PN = "3"  !CDS_PN = "3";
"B1":   PN = "1"  !CDS_PN = "1";
"GND":   PN = "2"  !CDS_PN = "2";
"S":   PN = "6"  !CDS_PN = "6";
"VCC":   PN = "5"  !CDS_PN = "5";
BODY = "Q_CAP","I43": LOCATION = "C608" #&CDS_LOCATION = "C608" &SEC = "1" #&CDS_SEC = "1";
"A":   PN = "1"  !CDS_PN = "1";
"B":   PN = "2"  !CDS_PN = "2";
BODY = "Q_CAP","I45": LOCATION = "C606" #&CDS_LOCATION = "C606" &SEC = "1" #&CDS_SEC = "1";
"A":   PN = "1"  !CDS_PN = "1";
"B":   PN = "2"  !CDS_PN = "2";
BODY = "Q_RES","I54": LOCATION = "R1748" #&CDS_LOCATION = "R1748" &SEC = "1" #&CDS_SEC = "1";
"A":   PN = "1"  !CDS_PN = "1";
"B":   PN = "2"  !CDS_PN = "2";
BODY = "Q_RES","I70": LOCATION = "R1961" #&CDS_LOCATION = "R1961" &SEC = "1" #&CDS_SEC = "1";
"A":   PN = "1"  !CDS_PN = "1";
"B":   PN = "2"  !CDS_PN = "2";
BODY = "Q_CAP","I84": LOCATION = "C1647" #&CDS_LOCATION = "C1647" &SEC = "1" #&CDS_SEC = "1";
"A":   PN = "1"  !CDS_PN = "1";
"B":   PN = "2"  !CDS_PN = "2";
BODY = "Q_RES","I87": LOCATION = "R1750" #&CDS_LOCATION = "R1750" &SEC = "1" #&CDS_SEC = "1";
"A":   PN = "1"  !CDS_PN = "1";
"B":   PN = "2"  !CDS_PN = "2";
BODY = "Q_RES","I89": LOCATION = "R1749" #&CDS_LOCATION = "R1749" &SEC = "1" #&CDS_SEC = "1";
"A":   PN = "1"  !CDS_PN = "1";
"B":   PN = "2"  !CDS_PN = "2";
BODY = "Q_RES","I91": LOCATION = "R2132" #&CDS_LOCATION = "R2132" &SEC = "1" #&CDS_SEC = "1";
"A":   PN = "1"  !CDS_PN = "1";
"B":   PN = "2"  !CDS_PN = "2";
BODY = "Q_RES","I94": LOCATION = "R2451" #&CDS_LOCATION = "R2451" &SEC = "1" #&CDS_SEC = "1";
"A":   PN = "1"  !CDS_PN = "1";
"B":   PN = "2"  !CDS_PN = "2";
BODY = "74LVC1G07SE7","I95": #LOCATION = "U154" !CDS_LOCATION = "U154" &SEC = "1" #&CDS_SEC = "1";
"A":   PN = "2"  !CDS_PN = "2";
"GND":   PN = "3"  !CDS_PN = "3";
"NC1":   PN = "1"  !CDS_PN = "1";
"VCC":   PN = "5"  !CDS_PN = "5";
"Y":   PN = "4"  !CDS_PN = "4";
BODY = "Q_RES","I96": #LOCATION = "R1868" !CDS_LOCATION = "R1868" &SEC = "1" #&CDS_SEC = "1";
"A":   PN = "1"  !CDS_PN = "1";
"B":   PN = "2"  !CDS_PN = "2";
BODY = "Q_RES","I97": #LOCATION = "R1869" !CDS_LOCATION = "R1869" &SEC = "1" #&CDS_SEC = "1";
"A":   PN = "1"  !CDS_PN = "1";
"B":   PN = "2"  !CDS_PN = "2";
BODY = "Q_RES","I98": #LOCATION = "R1870" !CDS_LOCATION = "R1870" &SEC = "1" #&CDS_SEC = "1";
"A":   PN = "1"  !CDS_PN = "1";
"B":   PN = "2"  !CDS_PN = "2";
BODY = "Q_RES","I99": #LOCATION = "R1871" !CDS_LOCATION = "R1871" &SEC = "1" #&CDS_SEC = "1";
"A":   PN = "1"  !CDS_PN = "1";
"B":   PN = "2"  !CDS_PN = "2";
BODY = "Q_RES","I100": #LOCATION = "R1872" !CDS_LOCATION = "R1872" &SEC = "1" #&CDS_SEC = "1";
"A":   PN = "1"  !CDS_PN = "1";
"B":   PN = "2"  !CDS_PN = "2";
BODY = "Q_RES","I101": #LOCATION = "R2363" !CDS_LOCATION = "R2363" &SEC = "1" #&CDS_SEC = "1";
"A":   PN = "1"  !CDS_PN = "1";
"B":   PN = "2"  !CDS_PN = "2";
BODY = "Q_RES","I102": #LOCATION = "R1479" !CDS_LOCATION = "R1479" &SEC = "1" #&CDS_SEC = "1";
"A":   PN = "1"  !CDS_PN = "1";
"B":   PN = "2"  !CDS_PN = "2";
BODY = "Q_RES","I105": #LOCATION = "R4118" !CDS_LOCATION = "R4118" &SEC = "1" #&CDS_SEC = "1";
"A":   PN = "1"  !CDS_PN = "1";
"B":   PN = "2"  !CDS_PN = "2";
DRAWING = "@s9s_mb_2u_lib.s9s_mb_2u(sch_1):page191";
BODY = "Q_RES","I2": LOCATION = "R1249" #&CDS_LOCATION = "R1249" &SEC = "1" #&CDS_SEC = "1";
"A":   PN = "1"  !CDS_PN = "1";
"B":   PN = "2"  !CDS_PN = "2";
BODY = "Q_RES","I14": LOCATION = "R1247" #&CDS_LOCATION = "R1247" &SEC = "1" #&CDS_SEC = "1";
"A":   PN = "1"  !CDS_PN = "1";
"B":   PN = "2"  !CDS_PN = "2";
BODY = "Q_RES","I29": LOCATION = "R1263" #&CDS_LOCATION = "R1263" &SEC = "1" #&CDS_SEC = "1";
"A":   PN = "1"  !CDS_PN = "1";
"B":   PN = "2"  !CDS_PN = "2";
BODY = "Q_RES","I35": LOCATION = "R1820" #&CDS_LOCATION = "R1820" &SEC = "1" #&CDS_SEC = "1";
"A":   PN = "1"  !CDS_PN = "1";
"B":   PN = "2"  !CDS_PN = "2";
BODY = "Q_RES","I38": #LOCATION = "R1266" !CDS_LOCATION = "R1266" &SEC = "1" #&CDS_SEC = "1";
"A":   PN = "1"  !CDS_PN = "1";
"B":   PN = "2"  !CDS_PN = "2";
DRAWING = "@s9s_mb_2u_lib.s9s_mb_2u(sch_1):page192";
BODY = "Q_RES","I1": LOCATION = "R3040" #&CDS_LOCATION = "R3040" &SEC = "1" #&CDS_SEC = "1";
"A":   PN = "1"  !CDS_PN = "1";
"B":   PN = "2"  !CDS_PN = "2";
BODY = "Q_RES","I4": LOCATION = "R1257" #&CDS_LOCATION = "R1257" &SEC = "1" #&CDS_SEC = "1";
"A":   PN = "1"  !CDS_PN = "1";
"B":   PN = "2"  !CDS_PN = "2";
BODY = "Q_RES","I6": LOCATION = "R3041" #&CDS_LOCATION = "R3041" &SEC = "1" #&CDS_SEC = "1";
"A":   PN = "1"  !CDS_PN = "1";
"B":   PN = "2"  !CDS_PN = "2";
BODY = "Q_RES","I8": LOCATION = "R1259" #&CDS_LOCATION = "R1259" &SEC = "1" #&CDS_SEC = "1";
"A":   PN = "1"  !CDS_PN = "1";
"B":   PN = "2"  !CDS_PN = "2";
BODY = "Q_RES","I11": LOCATION = "R1262" #&CDS_LOCATION = "R1262" &SEC = "1" #&CDS_SEC = "1";
"A":   PN = "1"  !CDS_PN = "1";
"B":   PN = "2"  !CDS_PN = "2";
BODY = "Q_RES","I17": LOCATION = "R1260" #&CDS_LOCATION = "R1260" &SEC = "1" #&CDS_SEC = "1";
"A":   PN = "1"  !CDS_PN = "1";
"B":   PN = "2"  !CDS_PN = "2";
BODY = "Q_RES","I18": LOCATION = "R3042" #&CDS_LOCATION = "R3042" &SEC = "1" #&CDS_SEC = "1";
"A":   PN = "1"  !CDS_PN = "1";
"B":   PN = "2"  !CDS_PN = "2";
BODY = "Q_RES","I23": LOCATION = "R1253" #&CDS_LOCATION = "R1253" &SEC = "1" #&CDS_SEC = "1";
"A":   PN = "1"  !CDS_PN = "1";
"B":   PN = "2"  !CDS_PN = "2";
BODY = "Q_RES","I24": LOCATION = "R1254" #&CDS_LOCATION = "R1254" &SEC = "1" #&CDS_SEC = "1";
"A":   PN = "1"  !CDS_PN = "1";
"B":   PN = "2"  !CDS_PN = "2";
BODY = "Q_RES","I26": LOCATION = "R1255" #&CDS_LOCATION = "R1255" &SEC = "1" #&CDS_SEC = "1";
"A":   PN = "1"  !CDS_PN = "1";
"B":   PN = "2"  !CDS_PN = "2";
BODY = "Q_RES","I41": LOCATION = "R1449" #&CDS_LOCATION = "R1449" &SEC = "1" #&CDS_SEC = "1";
"A":   PN = "1"  !CDS_PN = "1";
"B":   PN = "2"  !CDS_PN = "2";
BODY = "Q_RES","I42": LOCATION = "R1450" #&CDS_LOCATION = "R1450" &SEC = "1" #&CDS_SEC = "1";
"A":   PN = "1"  !CDS_PN = "1";
"B":   PN = "2"  !CDS_PN = "2";
BODY = "Q_RES","I50": LOCATION = "R1458" #&CDS_LOCATION = "R1458" &SEC = "1" #&CDS_SEC = "1";
"A":   PN = "1"  !CDS_PN = "1";
"B":   PN = "2"  !CDS_PN = "2";
BODY = "Q_RES","I51": LOCATION = "R1459" #&CDS_LOCATION = "R1459" &SEC = "1" #&CDS_SEC = "1";
"A":   PN = "1"  !CDS_PN = "1";
"B":   PN = "2"  !CDS_PN = "2";
BODY = "Q_RES","I59": LOCATION = "R8" #&CDS_LOCATION = "R8" &SEC = "1" #&CDS_SEC = "1";
"A":   PN = "1"  !CDS_PN = "1";
"B":   PN = "2"  !CDS_PN = "2";
BODY = "Q_RES","I60": LOCATION = "R71" #&CDS_LOCATION = "R71" &SEC = "1" #&CDS_SEC = "1";
"A":   PN = "1"  !CDS_PN = "1";
"B":   PN = "2"  !CDS_PN = "2";
BODY = "Q_RES","I62": LOCATION = "R1554" #&CDS_LOCATION = "R1554" &SEC = "1" #&CDS_SEC = "1";
"A":   PN = "1"  !CDS_PN = "1";
"B":   PN = "2"  !CDS_PN = "2";
BODY = "Q_RES","I66": LOCATION = "R456" #&CDS_LOCATION = "R456" &SEC = "1" #&CDS_SEC = "1";
"A":   PN = "1"  !CDS_PN = "1";
"B":   PN = "2"  !CDS_PN = "2";
BODY = "Q_RES","I69": LOCATION = "R401" #&CDS_LOCATION = "R401" &SEC = "1" #&CDS_SEC = "1";
"A":   PN = "1"  !CDS_PN = "1";
"B":   PN = "2"  !CDS_PN = "2";
BODY = "Q_RES","I72": LOCATION = "R1955" #&CDS_LOCATION = "R1955" &SEC = "1" #&CDS_SEC = "1";
"A":   PN = "1"  !CDS_PN = "1";
"B":   PN = "2"  !CDS_PN = "2";
BODY = "Q_RES","I75": LOCATION = "R2342" #&CDS_LOCATION = "R2342" &SEC = "1" #&CDS_SEC = "1";
"A":   PN = "1"  !CDS_PN = "1";
"B":   PN = "2"  !CDS_PN = "2";
DRAWING = "@s9s_mb_2u_lib.s9s_mb_2u(sch_1):page193";
BODY = "Q_RES","I3": LOCATION = "R1307" #&CDS_LOCATION = "R1307" &SEC = "1" #&CDS_SEC = "1";
"A":   PN = "1"  !CDS_PN = "1";
"B":   PN = "2"  !CDS_PN = "2";
BODY = "Q_RES","I5": LOCATION = "R1300" #&CDS_LOCATION = "R1300" &SEC = "1" #&CDS_SEC = "1";
"A":   PN = "1"  !CDS_PN = "1";
"B":   PN = "2"  !CDS_PN = "2";
BODY = "Q_RES","I10": LOCATION = "R1309" #&CDS_LOCATION = "R1309" &SEC = "1" #&CDS_SEC = "1";
"A":   PN = "1"  !CDS_PN = "1";
"B":   PN = "2"  !CDS_PN = "2";
BODY = "Q_RES","I13": LOCATION = "R1306" #&CDS_LOCATION = "R1306" &SEC = "1" #&CDS_SEC = "1";
"A":   PN = "1"  !CDS_PN = "1";
"B":   PN = "2"  !CDS_PN = "2";
BODY = "Q_RES","I20": LOCATION = "R1310" #&CDS_LOCATION = "R1310" &SEC = "1" #&CDS_SEC = "1";
"A":   PN = "1"  !CDS_PN = "1";
"B":   PN = "2"  !CDS_PN = "2";
BODY = "Q_RES","I21": LOCATION = "R1313" #&CDS_LOCATION = "R1313" &SEC = "1" #&CDS_SEC = "1";
"A":   PN = "1"  !CDS_PN = "1";
"B":   PN = "2"  !CDS_PN = "2";
BODY = "Q_RES","I27": LOCATION = "R1455" #&CDS_LOCATION = "R1455" &SEC = "1" #&CDS_SEC = "1";
"A":   PN = "1"  !CDS_PN = "1";
"B":   PN = "2"  !CDS_PN = "2";
BODY = "Q_RES","I28": LOCATION = "R1456" #&CDS_LOCATION = "R1456" &SEC = "1" #&CDS_SEC = "1";
"A":   PN = "1"  !CDS_PN = "1";
"B":   PN = "2"  !CDS_PN = "2";
BODY = "Q_RES","I32": LOCATION = "R698" #&CDS_LOCATION = "R698" &SEC = "1" #&CDS_SEC = "1";
"A":   PN = "1"  !CDS_PN = "1";
"B":   PN = "2"  !CDS_PN = "2";
BODY = "Q_RES","I40": LOCATION = "R3065" #&CDS_LOCATION = "R3065" &SEC = "1" #&CDS_SEC = "1";
"A":   PN = "1"  !CDS_PN = "1";
"B":   PN = "2"  !CDS_PN = "2";
DRAWING = "@s9s_mb_2u_lib.s9s_mb_2u(sch_1):page195";
BODY = "9QXL2001BNHGI8","I119": LOCATION = "U38" #&CDS_LOCATION = "U38" &SEC = "1" #&CDS_SEC = "1";
"^VSADR0_TRI":   PN = "B4"  !CDS_PN = "B4";
"^VSADR1_TRI":   PN = "B8"  !CDS_PN = "B8";
"DIF0":   PN = "J1"  !CDS_PN = "J1";
"DIF0#":   PN = "K1"  !CDS_PN = "K1";
"DIF1":   PN = "L1"  !CDS_PN = "L1";
"DIF1#":   PN = "M1"  !CDS_PN = "M1";
"DIF2":   PN = "M2"  !CDS_PN = "M2";
"DIF2#":   PN = "M3"  !CDS_PN = "M3";
"DIF3":   PN = "M4"  !CDS_PN = "M4";
"DIF3#":   PN = "M5"  !CDS_PN = "M5";
"DIF4":   PN = "M7"  !CDS_PN = "M7";
"DIF4#":   PN = "M8"  !CDS_PN = "M8";
"DIF5":   PN = "M9"  !CDS_PN = "M9";
"DIF5#":   PN = "M10"  !CDS_PN = "M10";
"DIF6":   PN = "M11"  !CDS_PN = "M11";
"DIF6#":   PN = "M12"  !CDS_PN = "M12";
"DIF7":   PN = "L12"  !CDS_PN = "L12";
"DIF7#":   PN = "K12"  !CDS_PN = "K12";
"DIF8":   PN = "J12"  !CDS_PN = "J12";
"DIF8#":   PN = "H12"  !CDS_PN = "H12";
"DIF9":   PN = "G12"  !CDS_PN = "G12";
"DIF9#":   PN = "F12"  !CDS_PN = "F12";
"DIF10":   PN = "D12"  !CDS_PN = "D12";
"DIF10#":   PN = "C12"  !CDS_PN = "C12";
"DIF11":   PN = "B12"  !CDS_PN = "B12";
"DIF11#":   PN = "A12"  !CDS_PN = "A12";
"DIF12":   PN = "A11"  !CDS_PN = "A11";
"DIF12#":   PN = "A10"  !CDS_PN = "A10";
"DIF13":   PN = "A9"  !CDS_PN = "A9";
"DIF13#":   PN = "A8"  !CDS_PN = "A8";
"DIF14":   PN = "A7"  !CDS_PN = "A7";
"DIF14#":   PN = "A6"  !CDS_PN = "A6";
"DIF15":   PN = "A5"  !CDS_PN = "A5";
"DIF15#":   PN = "A4"  !CDS_PN = "A4";
"DIF16":   PN = "A3"  !CDS_PN = "A3";
"DIF16#":   PN = "A2"  !CDS_PN = "A2";
"DIF17":   PN = "A1"  !CDS_PN = "A1";
"DIF17#":   PN = "B1"  !CDS_PN = "B1";
"DIF18":   PN = "C1"  !CDS_PN = "C1";
"DIF18#":   PN = "D1"  !CDS_PN = "D1";
"DIF19":   PN = "E1"  !CDS_PN = "E1";
"DIF19#":   PN = "F1"  !CDS_PN = "F1";
"DIF_IN":   PN = "G1"  !CDS_PN = "G1";
"DIF_IN#":   PN = "H1"  !CDS_PN = "H1";
"EPAD":   PN = "TH"  !CDS_PN = "TH";
"NC1":   PN = "B3"  !CDS_PN = "B3";
"NC2":   PN = "B5"  !CDS_PN = "B5";
"NC3":   PN = "B7"  !CDS_PN = "B7";
"NC4":   PN = "B9"  !CDS_PN = "B9";
"NC5":   PN = "C2"  !CDS_PN = "C2";
"NC6":   PN = "D2"  !CDS_PN = "D2";
"NC7":   PN = "D11"  !CDS_PN = "D11";
"NC8":   PN = "F2"  !CDS_PN = "F2";
"NC9":   PN = "F11"  !CDS_PN = "F11";
"NC10":   PN = "G2"  !CDS_PN = "G2";
"NC11":   PN = "G11"  !CDS_PN = "G11";
"NC12":   PN = "J2"  !CDS_PN = "J2";
"NC13":   PN = "J11"  !CDS_PN = "J11";
"NC14":   PN = "K2"  !CDS_PN = "K2";
"NC15":   PN = "L6"  !CDS_PN = "L6";
"NC16":   PN = "L7"  !CDS_PN = "L7";
"NC17":   PN = "L3"  !CDS_PN = "L3";
"NC18":   PN = "L9"  !CDS_PN = "L9";
"SMBCLK":   PN = "L5"  !CDS_PN = "L5";
"SMBDAT":   PN = "L4"  !CDS_PN = "L4";
"VCKPWRGD_PD#":   PN = "M6"  !CDS_PN = "M6";
"VDDA3.3":   PN = "B6"  !CDS_PN = "B6";
"VDDO3.3_B2":   PN = "B2"  !CDS_PN = "B2";
"VDDO3.3_B11":   PN = "B11"  !CDS_PN = "B11";
"VDDO3.3_L2":   PN = "L2"  !CDS_PN = "L2";
"VDDO3.3_L11":   PN = "L11"  !CDS_PN = "L11";
"VDDR3.3":   PN = "H2"  !CDS_PN = "H2";
"VOE5#||DATA":   PN = "L8"  !CDS_PN = "L8";
"VOE6#||CLK":   PN = "L10"  !CDS_PN = "L10";
"VOE7#":   PN = "K11"  !CDS_PN = "K11";
"VOE8#":   PN = "H11"  !CDS_PN = "H11";
"VOE9#":   PN = "E12"  !CDS_PN = "E12";
"VOE10#||SHFT_LD#":   PN = "E11"  !CDS_PN = "E11";
"VOE11#":   PN = "C11"  !CDS_PN = "C11";
"VOE12#":   PN = "B10"  !CDS_PN = "B10";
"VSBEN":   PN = "E2"  !CDS_PN = "E2";
BODY = "Q_RES","I156": LOCATION = "R576" #&CDS_LOCATION = "R576" &SEC = "1" #&CDS_SEC = "1";
"A":   PN = "1"  !CDS_PN = "1";
"B":   PN = "2"  !CDS_PN = "2";
BODY = "Q_RES","I162": LOCATION = "R572" #&CDS_LOCATION = "R572" &SEC = "1" #&CDS_SEC = "1";
"A":   PN = "1"  !CDS_PN = "1";
"B":   PN = "2"  !CDS_PN = "2";
BODY = "Q_RES","I163": LOCATION = "R571" #&CDS_LOCATION = "R571" &SEC = "1" #&CDS_SEC = "1";
"A":   PN = "1"  !CDS_PN = "1";
"B":   PN = "2"  !CDS_PN = "2";
BODY = "Q_CAP","I164": LOCATION = "C209" #&CDS_LOCATION = "C209" &SEC = "1" #&CDS_SEC = "1";
"A":   PN = "1"  !CDS_PN = "1";
"B":   PN = "2"  !CDS_PN = "2";
BODY = "Q_CAP","I165": LOCATION = "C211" #&CDS_LOCATION = "C211" &SEC = "1" #&CDS_SEC = "1";
"A":   PN = "1"  !CDS_PN = "1";
"B":   PN = "2"  !CDS_PN = "2";
BODY = "Q_CAP","I167": LOCATION = "C208" #&CDS_LOCATION = "C208" &SEC = "1" #&CDS_SEC = "1";
"A":   PN = "1"  !CDS_PN = "1";
"B":   PN = "2"  !CDS_PN = "2";
BODY = "Q_CAP","I168": LOCATION = "C210" #&CDS_LOCATION = "C210" &SEC = "1" #&CDS_SEC = "1";
"A":   PN = "1"  !CDS_PN = "1";
"B":   PN = "2"  !CDS_PN = "2";
BODY = "Q_INDUCTOR","I170": LOCATION = "L3" #&CDS_LOCATION = "L3" &SEC = "1" #&CDS_SEC = "1";
"1":   PN = "1"  !CDS_PN = "1";
"2":   PN = "2"  !CDS_PN = "2";
BODY = "Q_CAP","I171": LOCATION = "C204" #&CDS_LOCATION = "C204" &SEC = "1" #&CDS_SEC = "1";
"A":   PN = "1"  !CDS_PN = "1";
"B":   PN = "2"  !CDS_PN = "2";
BODY = "Q_CAP","I172": LOCATION = "C205" #&CDS_LOCATION = "C205" &SEC = "1" #&CDS_SEC = "1";
"A":   PN = "1"  !CDS_PN = "1";
"B":   PN = "2"  !CDS_PN = "2";
BODY = "Q_CAP","I173": LOCATION = "C206" #&CDS_LOCATION = "C206" &SEC = "1" #&CDS_SEC = "1";
"A":   PN = "1"  !CDS_PN = "1";
"B":   PN = "2"  !CDS_PN = "2";
BODY = "Q_CAP","I174": LOCATION = "C207" #&CDS_LOCATION = "C207" &SEC = "1" #&CDS_SEC = "1";
"A":   PN = "1"  !CDS_PN = "1";
"B":   PN = "2"  !CDS_PN = "2";
BODY = "Q_INDUCTOR","I177": LOCATION = "L4" #&CDS_LOCATION = "L4" &SEC = "1" #&CDS_SEC = "1";
"1":   PN = "1"  !CDS_PN = "1";
"2":   PN = "2"  !CDS_PN = "2";
BODY = "Q_RES","I178": LOCATION = "R568" #&CDS_LOCATION = "R568" &SEC = "1" #&CDS_SEC = "1";
"A":   PN = "1"  !CDS_PN = "1";
"B":   PN = "2"  !CDS_PN = "2";
BODY = "Q_RES","I179": LOCATION = "R567" #&CDS_LOCATION = "R567" &SEC = "1" #&CDS_SEC = "1";
"A":   PN = "1"  !CDS_PN = "1";
"B":   PN = "2"  !CDS_PN = "2";
BODY = "Q_RES","I185": LOCATION = "R569" #&CDS_LOCATION = "R569" &SEC = "1" #&CDS_SEC = "1";
"A":   PN = "1"  !CDS_PN = "1";
"B":   PN = "2"  !CDS_PN = "2";
BODY = "Q_RES","I187": LOCATION = "R570" #&CDS_LOCATION = "R570" &SEC = "1" #&CDS_SEC = "1";
"A":   PN = "1"  !CDS_PN = "1";
"B":   PN = "2"  !CDS_PN = "2";
BODY = "Q_RES","I194": LOCATION = "R573" #&CDS_LOCATION = "R573" &SEC = "1" #&CDS_SEC = "1";
"A":   PN = "1"  !CDS_PN = "1";
"B":   PN = "2"  !CDS_PN = "2";
BODY = "Q_RES","I197": LOCATION = "R574" #&CDS_LOCATION = "R574" &SEC = "1" #&CDS_SEC = "1";
"A":   PN = "1"  !CDS_PN = "1";
"B":   PN = "2"  !CDS_PN = "2";
BODY = "Q_RES","I199": LOCATION = "R575" #&CDS_LOCATION = "R575" &SEC = "1" #&CDS_SEC = "1";
"A":   PN = "1"  !CDS_PN = "1";
"B":   PN = "2"  !CDS_PN = "2";
BODY = "Q_RES","I304": LOCATION = "R106" #&CDS_LOCATION = "R106" &SEC = "1" #&CDS_SEC = "1";
"A":   PN = "1"  !CDS_PN = "1";
"B":   PN = "2"  !CDS_PN = "2";
BODY = "Q_CAP","I419": LOCATION = "C1409" #&CDS_LOCATION = "C1409" &SEC = "1" #&CDS_SEC = "1";
"A":   PN = "1"  !CDS_PN = "1";
"B":   PN = "2"  !CDS_PN = "2";
BODY = "Q_RES","I487": LOCATION = "R4534" #&CDS_LOCATION = "R4534" &SEC = "1" #&CDS_SEC = "1";
"A":   PN = "1"  !CDS_PN = "1";
"B":   PN = "2"  !CDS_PN = "2";
BODY = "Q_RES","I534": #LOCATION = "R1543" !CDS_LOCATION = "R1543" &SEC = "1" #&CDS_SEC = "1";
"A":   PN = "1"  !CDS_PN = "1";
"B":   PN = "2"  !CDS_PN = "2";
BODY = "Q_RES","I535": #LOCATION = "R2562" !CDS_LOCATION = "R2562" &SEC = "1" #&CDS_SEC = "1";
"A":   PN = "1"  !CDS_PN = "1";
"B":   PN = "2"  !CDS_PN = "2";
BODY = "Q_RES","I536": #LOCATION = "R3636" !CDS_LOCATION = "R3636" &SEC = "1" #&CDS_SEC = "1";
"A":   PN = "1"  !CDS_PN = "1";
"B":   PN = "2"  !CDS_PN = "2";
BODY = "Q_RES","I537": #LOCATION = "R3637" !CDS_LOCATION = "R3637" &SEC = "1" #&CDS_SEC = "1";
"A":   PN = "1"  !CDS_PN = "1";
"B":   PN = "2"  !CDS_PN = "2";
BODY = "Q_RES","I539": LOCATION = "R4516" #&CDS_LOCATION = "R4516" &SEC = "1" #&CDS_SEC = "1";
"A":   PN = "1"  !CDS_PN = "1";
"B":   PN = "2"  !CDS_PN = "2";
BODY = "Q_RES","I540": LOCATION = "R4517" #&CDS_LOCATION = "R4517" &SEC = "1" #&CDS_SEC = "1";
"A":   PN = "1"  !CDS_PN = "1";
"B":   PN = "2"  !CDS_PN = "2";
DRAWING = "@s9s_mb_2u_lib.s9s_mb_2u(sch_1):page197";
BODY = "9SQ440NQQI8","I180": LOCATION = "U13" #&CDS_LOCATION = "U13" &SEC = "1" #&CDS_SEC = "1";
"25M0":   PN = "A5"  !CDS_PN = "A5";
"25M0#":   PN = "A4"  !CDS_PN = "A4";
"25M1":   PN = "A3"  !CDS_PN = "A3";
"25M1#":   PN = "A2"  !CDS_PN = "A2";
"25M2":   PN = "A56"  !CDS_PN = "A56";
"25M2#":   PN = "A55"  !CDS_PN = "A55";
"25MPG":   PN = "A1"  !CDS_PN = "A1";
"100M0":   PN = "A34"  !CDS_PN = "A34";
"100M0#":   PN = "A33"  !CDS_PN = "A33";
"100M1":   PN = "A32"  !CDS_PN = "A32";
"100M1#":   PN = "A31"  !CDS_PN = "A31";
"100M2":   PN = "A28"  !CDS_PN = "A28";
"100M2#":   PN = "A27"  !CDS_PN = "A27";
"100M3":   PN = "A25"  !CDS_PN = "A25";
"100M3#":   PN = "A24"  !CDS_PN = "A24";
"100M4":   PN = "A23"  !CDS_PN = "A23";
"100M4#":   PN = "A22"  !CDS_PN = "A22";
"100M5":   PN = "A21"  !CDS_PN = "A21";
"100M5#":   PN = "A20"  !CDS_PN = "A20";
"100M6":   PN = "A19"  !CDS_PN = "A19";
"100M6#":   PN = "A18"  !CDS_PN = "A18";
"EPAD":   PN = "C1"  !CDS_PN = "C1";
"GNDS":   PN = "B10"  !CDS_PN = "B10";
"GNDXTAL":   PN = "A14"  !CDS_PN = "A14";
"MXCK0":   PN = "A52"  !CDS_PN = "A52";
"MXCK0#":   PN = "A51"  !CDS_PN = "A51";
"MXCK1":   PN = "A50"  !CDS_PN = "A50";
"MXCK1#":   PN = "A49"  !CDS_PN = "A49";
"MXCK2":   PN = "A48"  !CDS_PN = "A48";
"MXCK2#":   PN = "A47"  !CDS_PN = "A47";
"MXCK3":   PN = "A46"  !CDS_PN = "A46";
"MXCK3#":   PN = "A45"  !CDS_PN = "A45";
"MXCK4":   PN = "A44"  !CDS_PN = "A44";
"MXCK4#":   PN = "A43"  !CDS_PN = "A43";
"MXCK5":   PN = "A42"  !CDS_PN = "A42";
"MXCK5#":   PN = "A41"  !CDS_PN = "A41";
"MXCK6":   PN = "A40"  !CDS_PN = "A40";
"MXCK6#":   PN = "A39"  !CDS_PN = "A39";
"MXCK7":   PN = "A38"  !CDS_PN = "A38";
"MXCK7#":   PN = "A37"  !CDS_PN = "A37";
"MXCK8":   PN = "A36"  !CDS_PN = "A36";
"MXCK8#":   PN = "A35"  !CDS_PN = "A35";
"MXCK_SEL_100M#":   PN = "B38"  !CDS_PN = "B38";
"NVGND":   PN = "B12"  !CDS_PN = "B12";
"OE0#":   PN = "B27"  !CDS_PN = "B27";
"OE1#":   PN = "A30"  !CDS_PN = "A30";
"OE2#":   PN = "A29"  !CDS_PN = "A29";
"OE3#":   PN = "A26"  !CDS_PN = "A26";
"OE4#":   PN = "B19"  !CDS_PN = "B19";
"OE5#":   PN = "B15"  !CDS_PN = "B15";
"OE6#":   PN = "B14"  !CDS_PN = "B14";
"PFT_IN":   PN = "A8"  !CDS_PN = "A8";
"PFT_IN#":   PN = "A9"  !CDS_PN = "A9";
"PFT_LOST#":   PN = "B4"  !CDS_PN = "B4";
"PFT_OUT":   PN = "A6"  !CDS_PN = "A6";
"PFT_OUT#":   PN = "A7"  !CDS_PN = "A7";
"PWRGD||PWRDN#":   PN = "A17"  !CDS_PN = "A17";
"SBI_CLK":   PN = "A54"  !CDS_PN = "A54";
"SBI_IN":   PN = "B43"  !CDS_PN = "B43";
"SBI_OUT":   PN = "A53"  !CDS_PN = "A53";
"SCLK":   PN = "A10"  !CDS_PN = "A10";
"SHFT_LD#":   PN = "B42"  !CDS_PN = "B42";
"SMB_ADR0_TRI":   PN = "A11"  !CDS_PN = "A11";
"SMB_ADR1_TRI":   PN = "B9"  !CDS_PN = "B9";
"SMBDATTA":   PN = "B8"  !CDS_PN = "B8";
"SS_EN_TRI":   PN = "A16"  !CDS_PN = "A16";
"VDD100M_B21":   PN = "B21"  !CDS_PN = "B21";
"VDD100M_B23":   PN = "B23"  !CDS_PN = "B23";
"VDDA25M":   PN = "B1"  !CDS_PN = "B1";
"VDDA100M":   PN = "B17"  !CDS_PN = "B17";
"VDDMXCK_B29":   PN = "B29"  !CDS_PN = "B29";
"VDDMXCK_B32":   PN = "B32"  !CDS_PN = "B32";
"VDDMXCK_B35":   PN = "B35"  !CDS_PN = "B35";
"VDDMXCK_B40":   PN = "B40"  !CDS_PN = "B40";
"VDDPT":   PN = "B6"  !CDS_PN = "B6";
"VDDXTAL":   PN = "A12"  !CDS_PN = "A12";
"XIN_CLKIN":   PN = "A13"  !CDS_PN = "A13";
"XOUT":   PN = "B11"  !CDS_PN = "B11";
BODY = "Q_RES","I252": LOCATION = "R1680" #&CDS_LOCATION = "R1680" &SEC = "1" #&CDS_SEC = "1";
"A":   PN = "1"  !CDS_PN = "1";
"B":   PN = "2"  !CDS_PN = "2";
BODY = "Q_RES","I265": LOCATION = "R1483" #&CDS_LOCATION = "R1483" &SEC = "1" #&CDS_SEC = "1";
"A":   PN = "1"  !CDS_PN = "1";
"B":   PN = "2"  !CDS_PN = "2";
BODY = "Q_RES","I267": LOCATION = "R1471" #&CDS_LOCATION = "R1471" &SEC = "1" #&CDS_SEC = "1";
"A":   PN = "1"  !CDS_PN = "1";
"B":   PN = "2"  !CDS_PN = "2";
BODY = "Q_RES","I268": LOCATION = "R1484" #&CDS_LOCATION = "R1484" &SEC = "1" #&CDS_SEC = "1";
"A":   PN = "1"  !CDS_PN = "1";
"B":   PN = "2"  !CDS_PN = "2";
BODY = "Q_RES","I269": LOCATION = "R1527" #&CDS_LOCATION = "R1527" &SEC = "1" #&CDS_SEC = "1";
"A":   PN = "1"  !CDS_PN = "1";
"B":   PN = "2"  !CDS_PN = "2";
BODY = "Q_RES","I270": LOCATION = "R1502" #&CDS_LOCATION = "R1502" &SEC = "1" #&CDS_SEC = "1";
"A":   PN = "1"  !CDS_PN = "1";
"B":   PN = "2"  !CDS_PN = "2";
BODY = "Q_RES","I271": LOCATION = "R1500" #&CDS_LOCATION = "R1500" &SEC = "1" #&CDS_SEC = "1";
"A":   PN = "1"  !CDS_PN = "1";
"B":   PN = "2"  !CDS_PN = "2";
BODY = "Q_RES","I272": LOCATION = "R1305" #&CDS_LOCATION = "R1305" &SEC = "1" #&CDS_SEC = "1";
"A":   PN = "1"  !CDS_PN = "1";
"B":   PN = "2"  !CDS_PN = "2";
BODY = "Q_RES","I273": LOCATION = "R1204" #&CDS_LOCATION = "R1204" &SEC = "1" #&CDS_SEC = "1";
"A":   PN = "1"  !CDS_PN = "1";
"B":   PN = "2"  !CDS_PN = "2";
BODY = "Q_RES","I274": LOCATION = "R1462" #&CDS_LOCATION = "R1462" &SEC = "1" #&CDS_SEC = "1";
"A":   PN = "1"  !CDS_PN = "1";
"B":   PN = "2"  !CDS_PN = "2";
BODY = "Q_RES","I275": LOCATION = "R1390" #&CDS_LOCATION = "R1390" &SEC = "1" #&CDS_SEC = "1";
"A":   PN = "1"  !CDS_PN = "1";
"B":   PN = "2"  !CDS_PN = "2";
BODY = "Q_RES","I276": LOCATION = "R1267" #&CDS_LOCATION = "R1267" &SEC = "1" #&CDS_SEC = "1";
"A":   PN = "1"  !CDS_PN = "1";
"B":   PN = "2"  !CDS_PN = "2";
BODY = "Q_RES","I277": LOCATION = "R1194" #&CDS_LOCATION = "R1194" &SEC = "1" #&CDS_SEC = "1";
"A":   PN = "1"  !CDS_PN = "1";
"B":   PN = "2"  !CDS_PN = "2";
BODY = "Q_RES","I278": LOCATION = "R912" #&CDS_LOCATION = "R912" &SEC = "1" #&CDS_SEC = "1";
"A":   PN = "1"  !CDS_PN = "1";
"B":   PN = "2"  !CDS_PN = "2";
BODY = "Q_RES","I280": LOCATION = "R2481" #&CDS_LOCATION = "R2481" &SEC = "1" #&CDS_SEC = "1";
"A":   PN = "1"  !CDS_PN = "1";
"B":   PN = "2"  !CDS_PN = "2";
BODY = "Q_RES","I281": LOCATION = "R1196" #&CDS_LOCATION = "R1196" &SEC = "1" #&CDS_SEC = "1";
"A":   PN = "1"  !CDS_PN = "1";
"B":   PN = "2"  !CDS_PN = "2";
BODY = "Q_RES","I282": LOCATION = "R953" #&CDS_LOCATION = "R953" &SEC = "1" #&CDS_SEC = "1";
"A":   PN = "1"  !CDS_PN = "1";
"B":   PN = "2"  !CDS_PN = "2";
BODY = "Q_RES","I283": LOCATION = "R734" #&CDS_LOCATION = "R734" &SEC = "1" #&CDS_SEC = "1";
"A":   PN = "1"  !CDS_PN = "1";
"B":   PN = "2"  !CDS_PN = "2";
BODY = "Q_CAP","I286": LOCATION = "C1324" #&CDS_LOCATION = "C1324" &SEC = "1" #&CDS_SEC = "1";
"A":   PN = "1"  !CDS_PN = "1";
"B":   PN = "2"  !CDS_PN = "2";
BODY = "9SQ440NQQI8","I288": LOCATION = "U13" #&CDS_LOCATION = "U13" &SEC = "2" #&CDS_SEC = "2";
"NC_A15":   PN = "A15"  !CDS_PN = "A15";
"NC_B2":   PN = "B2"  !CDS_PN = "B2";
"NC_B3":   PN = "B3"  !CDS_PN = "B3";
"NC_B5":   PN = "B5"  !CDS_PN = "B5";
"NC_B7":   PN = "B7"  !CDS_PN = "B7";
"NC_B13":   PN = "B13"  !CDS_PN = "B13";
"NC_B16":   PN = "B16"  !CDS_PN = "B16";
"NC_B18":   PN = "B18"  !CDS_PN = "B18";
"NC_B20":   PN = "B20"  !CDS_PN = "B20";
"NC_B22":   PN = "B22"  !CDS_PN = "B22";
"NC_B24":   PN = "B24"  !CDS_PN = "B24";
"NC_B25":   PN = "B25"  !CDS_PN = "B25";
"NC_B26":   PN = "B26"  !CDS_PN = "B26";
"NC_B28":   PN = "B28"  !CDS_PN = "B28";
"NC_B30":   PN = "B30"  !CDS_PN = "B30";
"NC_B31":   PN = "B31"  !CDS_PN = "B31";
"NC_B33":   PN = "B33"  !CDS_PN = "B33";
"NC_B34":   PN = "B34"  !CDS_PN = "B34";
"NC_B36":   PN = "B36"  !CDS_PN = "B36";
"NC_B37":   PN = "B37"  !CDS_PN = "B37";
"NC_B39":   PN = "B39"  !CDS_PN = "B39";
"NC_B41":   PN = "B41"  !CDS_PN = "B41";
"NC_B44":   PN = "B44"  !CDS_PN = "B44";
BODY = "Q_RES","I303": LOCATION = "R1958" #&CDS_LOCATION = "R1958" &SEC = "1" #&CDS_SEC = "1";
"A":   PN = "1"  !CDS_PN = "1";
"B":   PN = "2"  !CDS_PN = "2";
BODY = "Q_RES","I378": LOCATION = "R3638" #&CDS_LOCATION = "R3638" &SEC = "1" #&CDS_SEC = "1";
"A":   PN = "1"  !CDS_PN = "1";
"B":   PN = "2"  !CDS_PN = "2";
BODY = "Q_RES","I379": LOCATION = "R3639" #&CDS_LOCATION = "R3639" &SEC = "1" #&CDS_SEC = "1";
"A":   PN = "1"  !CDS_PN = "1";
"B":   PN = "2"  !CDS_PN = "2";
BODY = "Q_RES","I380": LOCATION = "R3640" #&CDS_LOCATION = "R3640" &SEC = "1" #&CDS_SEC = "1";
"A":   PN = "1"  !CDS_PN = "1";
"B":   PN = "2"  !CDS_PN = "2";
BODY = "Q_RES","I381": LOCATION = "R3641" #&CDS_LOCATION = "R3641" &SEC = "1" #&CDS_SEC = "1";
"A":   PN = "1"  !CDS_PN = "1";
"B":   PN = "2"  !CDS_PN = "2";
BODY = "Q_RES","I382": LOCATION = "R3642" #&CDS_LOCATION = "R3642" &SEC = "1" #&CDS_SEC = "1";
"A":   PN = "1"  !CDS_PN = "1";
"B":   PN = "2"  !CDS_PN = "2";
BODY = "Q_RES","I383": LOCATION = "R3643" #&CDS_LOCATION = "R3643" &SEC = "1" #&CDS_SEC = "1";
"A":   PN = "1"  !CDS_PN = "1";
"B":   PN = "2"  !CDS_PN = "2";
BODY = "Q_XTAL_4P_13BI_24GND","I391": #LOCATION = "Y2" !CDS_LOCATION = "Y2" &SEC = "1" #&CDS_SEC = "1";
"G1":   PN = "2"  !CDS_PN = "2";
"G2":   PN = "4"  !CDS_PN = "4";
"X1":   PN = "1"  !CDS_PN = "1";
"X2":   PN = "3"  !CDS_PN = "3";
BODY = "Q_RES","I392": #LOCATION = "R1724" !CDS_LOCATION = "R1724" &SEC = "1" #&CDS_SEC = "1";
"A":   PN = "1"  !CDS_PN = "1";
"B":   PN = "2"  !CDS_PN = "2";
BODY = "Q_CAP","I393": #LOCATION = "C2036" !CDS_LOCATION = "C2036" &SEC = "1" #&CDS_SEC = "1";
"A":   PN = "1"  !CDS_PN = "1";
"B":   PN = "2"  !CDS_PN = "2";
BODY = "Q_CAP","I394": #LOCATION = "C2037" !CDS_LOCATION = "C2037" &SEC = "1" #&CDS_SEC = "1";
"A":   PN = "1"  !CDS_PN = "1";
"B":   PN = "2"  !CDS_PN = "2";
DRAWING = "@s9s_mb_2u_lib.s9s_mb_2u(sch_1):page199";
BODY = "Q_CAP","I6": LOCATION = "C172" #&CDS_LOCATION = "C172" &SEC = "1" #&CDS_SEC = "1";
"A":   PN = "1"  !CDS_PN = "1";
"B":   PN = "2"  !CDS_PN = "2";
BODY = "Q_RES","I7": LOCATION = "R519" #&CDS_LOCATION = "R519" &SEC = "1" #&CDS_SEC = "1";
"A":   PN = "1"  !CDS_PN = "1";
"B":   PN = "2"  !CDS_PN = "2";
BODY = "Q_CAP","I19": LOCATION = "C108" #&CDS_LOCATION = "C108" &SEC = "1" #&CDS_SEC = "1";
"A":   PN = "1"  !CDS_PN = "1";
"B":   PN = "2"  !CDS_PN = "2";
BODY = "Q_INDUCTOR","I20": LOCATION = "L1" #&CDS_LOCATION = "L1" &SEC = "1" #&CDS_SEC = "1";
"1":   PN = "1"  !CDS_PN = "1";
"2":   PN = "2"  !CDS_PN = "2";
BODY = "Q_RES","I36": LOCATION = "R442" #&CDS_LOCATION = "R442" &SEC = "1" #&CDS_SEC = "1";
"A":   PN = "1"  !CDS_PN = "1";
"B":   PN = "2"  !CDS_PN = "2";
BODY = "Q_INDUCTOR","I41": LOCATION = "L13" #&CDS_LOCATION = "L13" &SEC = "1" #&CDS_SEC = "1";
"1":   PN = "1"  !CDS_PN = "1";
"2":   PN = "2"  !CDS_PN = "2";
BODY = "Q_CAP","I43": LOCATION = "C1311" #&CDS_LOCATION = "C1311" &SEC = "1" #&CDS_SEC = "1";
"A":   PN = "1"  !CDS_PN = "1";
"B":   PN = "2"  !CDS_PN = "2";
BODY = "Q_CAP","I44": LOCATION = "C1309" #&CDS_LOCATION = "C1309" &SEC = "1" #&CDS_SEC = "1";
"A":   PN = "1"  !CDS_PN = "1";
"B":   PN = "2"  !CDS_PN = "2";
BODY = "Q_CAP","I48": LOCATION = "C1313" #&CDS_LOCATION = "C1313" &SEC = "1" #&CDS_SEC = "1";
"A":   PN = "1"  !CDS_PN = "1";
"B":   PN = "2"  !CDS_PN = "2";
BODY = "Q_CAP","I53": LOCATION = "C1314" #&CDS_LOCATION = "C1314" &SEC = "1" #&CDS_SEC = "1";
"A":   PN = "1"  !CDS_PN = "1";
"B":   PN = "2"  !CDS_PN = "2";
BODY = "Q_RES","I55": LOCATION = "R447" #&CDS_LOCATION = "R447" &SEC = "1" #&CDS_SEC = "1";
"A":   PN = "1"  !CDS_PN = "1";
"B":   PN = "2"  !CDS_PN = "2";
BODY = "Q_CAP","I58": LOCATION = "C1312" #&CDS_LOCATION = "C1312" &SEC = "1" #&CDS_SEC = "1";
"A":   PN = "1"  !CDS_PN = "1";
"B":   PN = "2"  !CDS_PN = "2";
BODY = "Q_CAP","I59": LOCATION = "C1310" #&CDS_LOCATION = "C1310" &SEC = "1" #&CDS_SEC = "1";
"A":   PN = "1"  !CDS_PN = "1";
"B":   PN = "2"  !CDS_PN = "2";
BODY = "Q_INDUCTOR","I60": LOCATION = "L14" #&CDS_LOCATION = "L14" &SEC = "1" #&CDS_SEC = "1";
"1":   PN = "1"  !CDS_PN = "1";
"2":   PN = "2"  !CDS_PN = "2";
BODY = "Q_CAP","I76": #LOCATION = "C110" !CDS_LOCATION = "C110" &SEC = "1" #&CDS_SEC = "1";
"A":   PN = "1"  !CDS_PN = "1";
"B":   PN = "2"  !CDS_PN = "2";
BODY = "Q_CAP","I77": #LOCATION = "C171" !CDS_LOCATION = "C171" &SEC = "1" #&CDS_SEC = "1";
"A":   PN = "1"  !CDS_PN = "1";
"B":   PN = "2"  !CDS_PN = "2";
BODY = "Q_CAP","I78": #LOCATION = "C173" !CDS_LOCATION = "C173" &SEC = "1" #&CDS_SEC = "1";
"A":   PN = "1"  !CDS_PN = "1";
"B":   PN = "2"  !CDS_PN = "2";
BODY = "Q_CAP","I79": #LOCATION = "C114" !CDS_LOCATION = "C114" &SEC = "1" #&CDS_SEC = "1";
"A":   PN = "1"  !CDS_PN = "1";
"B":   PN = "2"  !CDS_PN = "2";
BODY = "Q_CAP","I80": #LOCATION = "C112" !CDS_LOCATION = "C112" &SEC = "1" #&CDS_SEC = "1";
"A":   PN = "1"  !CDS_PN = "1";
"B":   PN = "2"  !CDS_PN = "2";
BODY = "Q_CAP","I81": #LOCATION = "C111" !CDS_LOCATION = "C111" &SEC = "1" #&CDS_SEC = "1";
"A":   PN = "1"  !CDS_PN = "1";
"B":   PN = "2"  !CDS_PN = "2";
BODY = "Q_CAP","I82": #LOCATION = "C107" !CDS_LOCATION = "C107" &SEC = "1" #&CDS_SEC = "1";
"A":   PN = "1"  !CDS_PN = "1";
"B":   PN = "2"  !CDS_PN = "2";
BODY = "Q_CAP","I85": #LOCATION = "C120" !CDS_LOCATION = "C120" &SEC = "1" #&CDS_SEC = "1";
"A":   PN = "1"  !CDS_PN = "1";
"B":   PN = "2"  !CDS_PN = "2";
BODY = "Q_CAP","I86": #LOCATION = "C119" !CDS_LOCATION = "C119" &SEC = "1" #&CDS_SEC = "1";
"A":   PN = "1"  !CDS_PN = "1";
"B":   PN = "2"  !CDS_PN = "2";
BODY = "Q_CAP","I87": #LOCATION = "C117" !CDS_LOCATION = "C117" &SEC = "1" #&CDS_SEC = "1";
"A":   PN = "1"  !CDS_PN = "1";
"B":   PN = "2"  !CDS_PN = "2";
BODY = "Q_CAP","I88": #LOCATION = "C116" !CDS_LOCATION = "C116" &SEC = "1" #&CDS_SEC = "1";
"A":   PN = "1"  !CDS_PN = "1";
"B":   PN = "2"  !CDS_PN = "2";
BODY = "Q_CAP","I89": #LOCATION = "C115" !CDS_LOCATION = "C115" &SEC = "1" #&CDS_SEC = "1";
"A":   PN = "1"  !CDS_PN = "1";
"B":   PN = "2"  !CDS_PN = "2";
DRAWING = "@s9s_mb_2u_lib.s9s_mb_2u(sch_1):page200";
BODY = "Q_CAP","I5": LOCATION = "C2331" #&CDS_LOCATION = "C2331" &SEC = "1" #&CDS_SEC = "1";
"A":   PN = "1"  !CDS_PN = "1";
"B":   PN = "2"  !CDS_PN = "2";
BODY = "Q_CAP","I10": LOCATION = "C2332" #&CDS_LOCATION = "C2332" &SEC = "1" #&CDS_SEC = "1";
"A":   PN = "1"  !CDS_PN = "1";
"B":   PN = "2"  !CDS_PN = "2";
BODY = "Q_RES","I11": LOCATION = "R4475" #&CDS_LOCATION = "R4475" &SEC = "1" #&CDS_SEC = "1";
"A":   PN = "1"  !CDS_PN = "1";
"B":   PN = "2"  !CDS_PN = "2";
BODY = "9ZXL0451EKILFT","I1": LOCATION = "U314" #&CDS_LOCATION = "U314" &SEC = "1" #&CDS_SEC = "1";
"^CKPWRGD_PD#":   PN = "1"  !CDS_PN = "1";
"^HIBW_BYPM_LOBW#":   PN = "32"  !CDS_PN = "32";
"DIF0":   PN = "13"  !CDS_PN = "13";
"DIF0#":   PN = "14"  !CDS_PN = "14";
"DIF1":   PN = "19"  !CDS_PN = "19";
"DIF1#":   PN = "20"  !CDS_PN = "20";
"DIF2":   PN = "22"  !CDS_PN = "22";
"DIF2#":   PN = "23"  !CDS_PN = "23";
"DIF3":   PN = "27"  !CDS_PN = "27";
"DIF3#":   PN = "28"  !CDS_PN = "28";
"DIF_IN":   PN = "3"  !CDS_PN = "3";
"DIF_IN#":   PN = "4"  !CDS_PN = "4";
"EPAD_GND":   PN = "33"  !CDS_PN = "33";
"FBOUT_NC":   PN = "9"  !CDS_PN = "9";
"FBOUT_NC#":   PN = "8"  !CDS_PN = "8";
"NC0":   PN = "10"  !CDS_PN = "10";
"NC1":   PN = "11"  !CDS_PN = "11";
"NC2":   PN = "17"  !CDS_PN = "17";
"NC3":   PN = "30"  !CDS_PN = "30";
"SMBCLK":   PN = "7"  !CDS_PN = "7";
"SMBDAT":   PN = "6"  !CDS_PN = "6";
"VDD0":   PN = "12"  !CDS_PN = "12";
"VDD1":   PN = "16"  !CDS_PN = "16";
"VDD2":   PN = "21"  !CDS_PN = "21";
"VDD3":   PN = "25"  !CDS_PN = "25";
"VDD4":   PN = "29"  !CDS_PN = "29";
"VDDA":   PN = "31"  !CDS_PN = "31";
"VDDR":   PN = "2"  !CDS_PN = "2";
"VOE0#":   PN = "15"  !CDS_PN = "15";
"VOE1#":   PN = "18"  !CDS_PN = "18";
"VOE2#":   PN = "24"  !CDS_PN = "24";
"VOE3#":   PN = "26"  !CDS_PN = "26";
"VSADR0_TRI":   PN = "5"  !CDS_PN = "5";
BODY = "Q_RES","I4": LOCATION = "R4493" #&CDS_LOCATION = "R4493" &SEC = "1" #&CDS_SEC = "1";
"A":   PN = "1"  !CDS_PN = "1";
"B":   PN = "2"  !CDS_PN = "2";
BODY = "Q_CAP","I17": LOCATION = "C2328" #&CDS_LOCATION = "C2328" &SEC = "1" #&CDS_SEC = "1";
"A":   PN = "1"  !CDS_PN = "1";
"B":   PN = "2"  !CDS_PN = "2";
BODY = "Q_RES","I30": LOCATION = "R4489" #&CDS_LOCATION = "R4489" &SEC = "1" #&CDS_SEC = "1";
"A":   PN = "1"  !CDS_PN = "1";
"B":   PN = "2"  !CDS_PN = "2";
BODY = "Q_RES","I31": LOCATION = "R4490" #&CDS_LOCATION = "R4490" &SEC = "1" #&CDS_SEC = "1";
"A":   PN = "1"  !CDS_PN = "1";
"B":   PN = "2"  !CDS_PN = "2";
BODY = "Q_RES","I39": LOCATION = "R4476" #&CDS_LOCATION = "R4476" &SEC = "1" #&CDS_SEC = "1";
"A":   PN = "1"  !CDS_PN = "1";
"B":   PN = "2"  !CDS_PN = "2";
BODY = "Q_RES","I48": LOCATION = "R4491" #&CDS_LOCATION = "R4491" &SEC = "1" #&CDS_SEC = "1";
"A":   PN = "1"  !CDS_PN = "1";
"B":   PN = "2"  !CDS_PN = "2";
BODY = "Q_RES","I49": LOCATION = "R4492" #&CDS_LOCATION = "R4492" &SEC = "1" #&CDS_SEC = "1";
"A":   PN = "1"  !CDS_PN = "1";
"B":   PN = "2"  !CDS_PN = "2";
BODY = "Q_CAP","I54": LOCATION = "C2329" #&CDS_LOCATION = "C2329" &SEC = "1" #&CDS_SEC = "1";
"A":   PN = "1"  !CDS_PN = "1";
"B":   PN = "2"  !CDS_PN = "2";
BODY = "Q_CAP","I55": LOCATION = "C2330" #&CDS_LOCATION = "C2330" &SEC = "1" #&CDS_SEC = "1";
"A":   PN = "1"  !CDS_PN = "1";
"B":   PN = "2"  !CDS_PN = "2";
BODY = "Q_CAP","I56": LOCATION = "C2333" #&CDS_LOCATION = "C2333" &SEC = "1" #&CDS_SEC = "1";
"A":   PN = "1"  !CDS_PN = "1";
"B":   PN = "2"  !CDS_PN = "2";
BODY = "Q_CAP","I57": LOCATION = "C2336" #&CDS_LOCATION = "C2336" &SEC = "1" #&CDS_SEC = "1";
"A":   PN = "1"  !CDS_PN = "1";
"B":   PN = "2"  !CDS_PN = "2";
BODY = "Q_CAP","I58": LOCATION = "C2334" #&CDS_LOCATION = "C2334" &SEC = "1" #&CDS_SEC = "1";
"A":   PN = "1"  !CDS_PN = "1";
"B":   PN = "2"  !CDS_PN = "2";
BODY = "Q_CAP","I59": LOCATION = "C2335" #&CDS_LOCATION = "C2335" &SEC = "1" #&CDS_SEC = "1";
"A":   PN = "1"  !CDS_PN = "1";
"B":   PN = "2"  !CDS_PN = "2";
BODY = "Q_RES","I69": LOCATION = "R4494" #&CDS_LOCATION = "R4494" &SEC = "1" #&CDS_SEC = "1";
"A":   PN = "1"  !CDS_PN = "1";
"B":   PN = "2"  !CDS_PN = "2";
BODY = "Q_CAP","I71": LOCATION = "C2339" #&CDS_LOCATION = "C2339" &SEC = "1" #&CDS_SEC = "1";
"A":   PN = "1"  !CDS_PN = "1";
"B":   PN = "2"  !CDS_PN = "2";
BODY = "Q_RES","I74": #LOCATION = "R4477" !CDS_LOCATION = "R4477" &SEC = "1" #&CDS_SEC = "1";
"A":   PN = "1"  !CDS_PN = "1";
"B":   PN = "2"  !CDS_PN = "2";
BODY = "Q_RES","I75": #LOCATION = "R4478" !CDS_LOCATION = "R4478" &SEC = "1" #&CDS_SEC = "1";
"A":   PN = "1"  !CDS_PN = "1";
"B":   PN = "2"  !CDS_PN = "2";
BODY = "Q_RES","I76": #LOCATION = "R4479" !CDS_LOCATION = "R4479" &SEC = "1" #&CDS_SEC = "1";
"A":   PN = "1"  !CDS_PN = "1";
"B":   PN = "2"  !CDS_PN = "2";
BODY = "Q_RES","I77": LOCATION = "R4518" #&CDS_LOCATION = "R4518" &SEC = "1" #&CDS_SEC = "1";
"A":   PN = "1"  !CDS_PN = "1";
"B":   PN = "2"  !CDS_PN = "2";
BODY = "Q_RES","I78": LOCATION = "R4519" #&CDS_LOCATION = "R4519" &SEC = "1" #&CDS_SEC = "1";
"A":   PN = "1"  !CDS_PN = "1";
"B":   PN = "2"  !CDS_PN = "2";
BODY = "Q_RES","I79": LOCATION = "R4520" #&CDS_LOCATION = "R4520" &SEC = "1" #&CDS_SEC = "1";
"A":   PN = "1"  !CDS_PN = "1";
"B":   PN = "2"  !CDS_PN = "2";
BODY = "Q_INDUCTOR","I81": #LOCATION = "L19" !CDS_LOCATION = "L19" &SEC = "1" #&CDS_SEC = "1";
"1":   PN = "1"  !CDS_PN = "1";
"2":   PN = "2"  !CDS_PN = "2";
BODY = "Q_INDUCTOR","I82": #LOCATION = "L20" !CDS_LOCATION = "L20" &SEC = "1" #&CDS_SEC = "1";
"1":   PN = "1"  !CDS_PN = "1";
"2":   PN = "2"  !CDS_PN = "2";
DRAWING = "@s9s_mb_2u_lib.s9s_mb_2u(sch_1):page207";
BODY = "MOSFET_N","I236": LOCATION = "U89" #&CDS_LOCATION = "U89" &SEC = "1" #&CDS_SEC = "1";
"DRAIN":   PN = "D"  !CDS_PN = "D";
"GATE":   PN = "G"  !CDS_PN = "G";
"SOURCE":   PN = "S"  !CDS_PN = "S";
BODY = "Q_RES","I268": LOCATION = "R2339" #&CDS_LOCATION = "R2339" &SEC = "1" #&CDS_SEC = "1";
"A":   PN = "1"  !CDS_PN = "1";
"B":   PN = "2"  !CDS_PN = "2";
BODY = "MOSFET_NCH_GDS_ESD_PROTECTED","I272": #LOCATION = "Q33" !CDS_LOCATION = "Q33" &SEC = "1" #&CDS_SEC = "1";
"D":   PN = "D"  !CDS_PN = "D";
"G":   PN = "G"  !CDS_PN = "G";
"S":   PN = "S"  !CDS_PN = "S";
BODY = "Q_RES","I273": LOCATION = "R365" #&CDS_LOCATION = "R365" &SEC = "1" #&CDS_SEC = "1";
"A":   PN = "1"  !CDS_PN = "1";
"B":   PN = "2"  !CDS_PN = "2";
BODY = "Q_RES","I275": LOCATION = "R1841" #&CDS_LOCATION = "R1841" &SEC = "1" #&CDS_SEC = "1";
"A":   PN = "1"  !CDS_PN = "1";
"B":   PN = "2"  !CDS_PN = "2";
BODY = "Q_LED","I277": #LOCATION = "D0" !CDS_LOCATION = "D0" &SEC = "1" #&CDS_SEC = "1";
"A":   PN = "A"  !CDS_PN = "A";
"C":   PN = "C"  !CDS_PN = "C";
BODY = "Q_RES","I278": #LOCATION = "R1195" !CDS_LOCATION = "R1195" &SEC = "1" #&CDS_SEC = "1";
"A":   PN = "1"  !CDS_PN = "1";
"B":   PN = "2"  !CDS_PN = "2";
BODY = "Q_LED","I279": #LOCATION = "D6" !CDS_LOCATION = "D6" &SEC = "1" #&CDS_SEC = "1";
"A":   PN = "A"  !CDS_PN = "A";
"C":   PN = "C"  !CDS_PN = "C";
BODY = "Q_RES","I280": #LOCATION = "R366" !CDS_LOCATION = "R366" &SEC = "1" #&CDS_SEC = "1";
"A":   PN = "1"  !CDS_PN = "1";
"B":   PN = "2"  !CDS_PN = "2";
DRAWING = "@s9s_mb_2u_lib.s9s_mb_2u(sch_1):page208";
BODY = "Q_RES","I4": LOCATION = "R1415" #&CDS_LOCATION = "R1415" &SEC = "1" #&CDS_SEC = "1";
"A":   PN = "1"  !CDS_PN = "1";
"B":   PN = "2"  !CDS_PN = "2";
BODY = "Q_RES","I5": LOCATION = "R1416" #&CDS_LOCATION = "R1416" &SEC = "1" #&CDS_SEC = "1";
"A":   PN = "1"  !CDS_PN = "1";
"B":   PN = "2"  !CDS_PN = "2";
BODY = "Q_RES","I6": LOCATION = "R1418" #&CDS_LOCATION = "R1418" &SEC = "1" #&CDS_SEC = "1";
"A":   PN = "1"  !CDS_PN = "1";
"B":   PN = "2"  !CDS_PN = "2";
BODY = "Q_RES","I7": LOCATION = "R1417" #&CDS_LOCATION = "R1417" &SEC = "1" #&CDS_SEC = "1";
"A":   PN = "1"  !CDS_PN = "1";
"B":   PN = "2"  !CDS_PN = "2";
BODY = "Q_RES","I8": LOCATION = "R1419" #&CDS_LOCATION = "R1419" &SEC = "1" #&CDS_SEC = "1";
"A":   PN = "1"  !CDS_PN = "1";
"B":   PN = "2"  !CDS_PN = "2";
BODY = "Q_RES","I9": LOCATION = "R1420" #&CDS_LOCATION = "R1420" &SEC = "1" #&CDS_SEC = "1";
"A":   PN = "1"  !CDS_PN = "1";
"B":   PN = "2"  !CDS_PN = "2";
BODY = "Q_RES","I10": LOCATION = "R1421" #&CDS_LOCATION = "R1421" &SEC = "1" #&CDS_SEC = "1";
"A":   PN = "1"  !CDS_PN = "1";
"B":   PN = "2"  !CDS_PN = "2";
BODY = "Q_RES","I11": LOCATION = "R1326" #&CDS_LOCATION = "R1326" &SEC = "1" #&CDS_SEC = "1";
"A":   PN = "1"  !CDS_PN = "1";
"B":   PN = "2"  !CDS_PN = "2";
BODY = "Q_RES","I12": LOCATION = "R1302" #&CDS_LOCATION = "R1302" &SEC = "1" #&CDS_SEC = "1";
"A":   PN = "1"  !CDS_PN = "1";
"B":   PN = "2"  !CDS_PN = "2";
BODY = "Q_RES","I13": LOCATION = "R1328" #&CDS_LOCATION = "R1328" &SEC = "1" #&CDS_SEC = "1";
"A":   PN = "1"  !CDS_PN = "1";
"B":   PN = "2"  !CDS_PN = "2";
BODY = "Q_RES","I14": LOCATION = "R1327" #&CDS_LOCATION = "R1327" &SEC = "1" #&CDS_SEC = "1";
"A":   PN = "1"  !CDS_PN = "1";
"B":   PN = "2"  !CDS_PN = "2";
BODY = "Q_RES","I15": LOCATION = "R1329" #&CDS_LOCATION = "R1329" &SEC = "1" #&CDS_SEC = "1";
"A":   PN = "1"  !CDS_PN = "1";
"B":   PN = "2"  !CDS_PN = "2";
BODY = "Q_RES","I16": LOCATION = "R1330" #&CDS_LOCATION = "R1330" &SEC = "1" #&CDS_SEC = "1";
"A":   PN = "1"  !CDS_PN = "1";
"B":   PN = "2"  !CDS_PN = "2";
BODY = "Q_RES","I17": LOCATION = "R1388" #&CDS_LOCATION = "R1388" &SEC = "1" #&CDS_SEC = "1";
"A":   PN = "1"  !CDS_PN = "1";
"B":   PN = "2"  !CDS_PN = "2";
BODY = "Q_RES","I18": LOCATION = "R990" #&CDS_LOCATION = "R990" &SEC = "1" #&CDS_SEC = "1";
"A":   PN = "1"  !CDS_PN = "1";
"B":   PN = "2"  !CDS_PN = "2";
BODY = "Q_RES","I19": LOCATION = "R4533" #&CDS_LOCATION = "R4533" &SEC = "1" #&CDS_SEC = "1";
"A":   PN = "1"  !CDS_PN = "1";
"B":   PN = "2"  !CDS_PN = "2";
BODY = "Q_RES","I20": LOCATION = "R991" #&CDS_LOCATION = "R991" &SEC = "1" #&CDS_SEC = "1";
"A":   PN = "1"  !CDS_PN = "1";
"B":   PN = "2"  !CDS_PN = "2";
BODY = "Q_RES","I21": LOCATION = "R992" #&CDS_LOCATION = "R992" &SEC = "1" #&CDS_SEC = "1";
"A":   PN = "1"  !CDS_PN = "1";
"B":   PN = "2"  !CDS_PN = "2";
BODY = "Q_RES","I22": LOCATION = "R1398" #&CDS_LOCATION = "R1398" &SEC = "1" #&CDS_SEC = "1";
"A":   PN = "1"  !CDS_PN = "1";
"B":   PN = "2"  !CDS_PN = "2";
BODY = "Q_RES","I23": LOCATION = "R1402" #&CDS_LOCATION = "R1402" &SEC = "1" #&CDS_SEC = "1";
"A":   PN = "1"  !CDS_PN = "1";
"B":   PN = "2"  !CDS_PN = "2";
BODY = "Q_RES","I24": LOCATION = "R1403" #&CDS_LOCATION = "R1403" &SEC = "1" #&CDS_SEC = "1";
"A":   PN = "1"  !CDS_PN = "1";
"B":   PN = "2"  !CDS_PN = "2";
BODY = "Q_RES","I25": LOCATION = "R1404" #&CDS_LOCATION = "R1404" &SEC = "1" #&CDS_SEC = "1";
"A":   PN = "1"  !CDS_PN = "1";
"B":   PN = "2"  !CDS_PN = "2";
BODY = "Q_RES","I26": LOCATION = "R1405" #&CDS_LOCATION = "R1405" &SEC = "1" #&CDS_SEC = "1";
"A":   PN = "1"  !CDS_PN = "1";
"B":   PN = "2"  !CDS_PN = "2";
BODY = "Q_RES","I51": LOCATION = "R1406" #&CDS_LOCATION = "R1406" &SEC = "1" #&CDS_SEC = "1";
"A":   PN = "1"  !CDS_PN = "1";
"B":   PN = "2"  !CDS_PN = "2";
BODY = "Q_RES","I52": LOCATION = "R1407" #&CDS_LOCATION = "R1407" &SEC = "1" #&CDS_SEC = "1";
"A":   PN = "1"  !CDS_PN = "1";
"B":   PN = "2"  !CDS_PN = "2";
BODY = "Q_RES","I53": LOCATION = "R1408" #&CDS_LOCATION = "R1408" &SEC = "1" #&CDS_SEC = "1";
"A":   PN = "1"  !CDS_PN = "1";
"B":   PN = "2"  !CDS_PN = "2";
BODY = "Q_RES","I54": LOCATION = "R1410" #&CDS_LOCATION = "R1410" &SEC = "1" #&CDS_SEC = "1";
"A":   PN = "1"  !CDS_PN = "1";
"B":   PN = "2"  !CDS_PN = "2";
BODY = "Q_RES","I55": LOCATION = "R1409" #&CDS_LOCATION = "R1409" &SEC = "1" #&CDS_SEC = "1";
"A":   PN = "1"  !CDS_PN = "1";
"B":   PN = "2"  !CDS_PN = "2";
BODY = "Q_RES","I56": LOCATION = "R1411" #&CDS_LOCATION = "R1411" &SEC = "1" #&CDS_SEC = "1";
"A":   PN = "1"  !CDS_PN = "1";
"B":   PN = "2"  !CDS_PN = "2";
BODY = "Q_RES","I57": LOCATION = "R1412" #&CDS_LOCATION = "R1412" &SEC = "1" #&CDS_SEC = "1";
"A":   PN = "1"  !CDS_PN = "1";
"B":   PN = "2"  !CDS_PN = "2";
BODY = "Q_RES","I58": LOCATION = "R1414" #&CDS_LOCATION = "R1414" &SEC = "1" #&CDS_SEC = "1";
"A":   PN = "1"  !CDS_PN = "1";
"B":   PN = "2"  !CDS_PN = "2";
BODY = "Q_RES","I59": LOCATION = "R1413" #&CDS_LOCATION = "R1413" &SEC = "1" #&CDS_SEC = "1";
"A":   PN = "1"  !CDS_PN = "1";
"B":   PN = "2"  !CDS_PN = "2";
BODY = "Q_RES","I66": LOCATION = "R4622" #&CDS_LOCATION = "R4622" &SEC = "1" #&CDS_SEC = "1";
"A":   PN = "1"  !CDS_PN = "1";
"B":   PN = "2"  !CDS_PN = "2";
DRAWING = "@s9s_mb_2u_lib.s9s_mb_2u(sch_1):page210";
BODY = "Q_RES","I19": LOCATION = "R803" #&CDS_LOCATION = "R803" &SEC = "1" #&CDS_SEC = "1";
"A":   PN = "1"  !CDS_PN = "1";
"B":   PN = "2"  !CDS_PN = "2";
BODY = "Q_RES","I20": LOCATION = "R804" #&CDS_LOCATION = "R804" &SEC = "1" #&CDS_SEC = "1";
"A":   PN = "1"  !CDS_PN = "1";
"B":   PN = "2"  !CDS_PN = "2";
BODY = "Q_RES","I25": LOCATION = "R805" #&CDS_LOCATION = "R805" &SEC = "1" #&CDS_SEC = "1";
"A":   PN = "1"  !CDS_PN = "1";
"B":   PN = "2"  !CDS_PN = "2";
BODY = "Q_RES","I54": LOCATION = "R806" #&CDS_LOCATION = "R806" &SEC = "1" #&CDS_SEC = "1";
"A":   PN = "1"  !CDS_PN = "1";
"B":   PN = "2"  !CDS_PN = "2";
BODY = "Q_RES","I59": LOCATION = "R929" #&CDS_LOCATION = "R929" &SEC = "1" #&CDS_SEC = "1";
"A":   PN = "1"  !CDS_PN = "1";
"B":   PN = "2"  !CDS_PN = "2";
BODY = "Q_RES","I60": LOCATION = "R928" #&CDS_LOCATION = "R928" &SEC = "1" #&CDS_SEC = "1";
"A":   PN = "1"  !CDS_PN = "1";
"B":   PN = "2"  !CDS_PN = "2";
BODY = "Q_RES","I61": LOCATION = "R927" #&CDS_LOCATION = "R927" &SEC = "1" #&CDS_SEC = "1";
"A":   PN = "1"  !CDS_PN = "1";
"B":   PN = "2"  !CDS_PN = "2";
BODY = "Q_RES","I63": LOCATION = "R930" #&CDS_LOCATION = "R930" &SEC = "1" #&CDS_SEC = "1";
"A":   PN = "1"  !CDS_PN = "1";
"B":   PN = "2"  !CDS_PN = "2";
BODY = "Q_RES","I75": LOCATION = "R919" #&CDS_LOCATION = "R919" &SEC = "1" #&CDS_SEC = "1";
"A":   PN = "1"  !CDS_PN = "1";
"B":   PN = "2"  !CDS_PN = "2";
BODY = "Q_RES","I76": LOCATION = "R920" #&CDS_LOCATION = "R920" &SEC = "1" #&CDS_SEC = "1";
"A":   PN = "1"  !CDS_PN = "1";
"B":   PN = "2"  !CDS_PN = "2";
BODY = "CONN8_210HP1080BR1","I79": #LOCATION = "J43" !CDS_LOCATION = "J43" &SEC = "1" #&CDS_SEC = "1";
"1":   PN = "1"  !CDS_PN = "1";
"2":   PN = "2"  !CDS_PN = "2";
"3":   PN = "3"  !CDS_PN = "3";
"4":   PN = "4"  !CDS_PN = "4";
"5":   PN = "5"  !CDS_PN = "5";
"6":   PN = "6"  !CDS_PN = "6";
"7":   PN = "7"  !CDS_PN = "7";
"8":   PN = "8"  !CDS_PN = "8";
BODY = "Q_CAP","I86": LOCATION = "C554" #&CDS_LOCATION = "C554" &SEC = "1" #&CDS_SEC = "1";
"A":   PN = "1"  !CDS_PN = "1";
"B":   PN = "2"  !CDS_PN = "2";
BODY = "Q_CAP","I88": LOCATION = "C563" #&CDS_LOCATION = "C563" &SEC = "1" #&CDS_SEC = "1";
"A":   PN = "1"  !CDS_PN = "1";
"B":   PN = "2"  !CDS_PN = "2";
BODY = "SCHOTTKY_12","I91": LOCATION = "D141" #&CDS_LOCATION = "D141" &SEC = "1" #&CDS_SEC = "1";
"A":   PN = "1"  !CDS_PN = "1";
"C":   PN = "2"  !CDS_PN = "2";
DRAWING = "@s9s_mb_2u_lib.s9s_mb_2u(sch_1):page211";
BODY = "Q_RES","I9": LOCATION = "R981" #&CDS_LOCATION = "R981" &SEC = "1" #&CDS_SEC = "1";
"A":   PN = "1"  !CDS_PN = "1";
"B":   PN = "2"  !CDS_PN = "2";
BODY = "Q_RES","I10": LOCATION = "R982" #&CDS_LOCATION = "R982" &SEC = "1" #&CDS_SEC = "1";
"A":   PN = "1"  !CDS_PN = "1";
"B":   PN = "2"  !CDS_PN = "2";
BODY = "Q_RES","I13": LOCATION = "R983" #&CDS_LOCATION = "R983" &SEC = "1" #&CDS_SEC = "1";
"A":   PN = "1"  !CDS_PN = "1";
"B":   PN = "2"  !CDS_PN = "2";
BODY = "Q_RES","I15": LOCATION = "R984" #&CDS_LOCATION = "R984" &SEC = "1" #&CDS_SEC = "1";
"A":   PN = "1"  !CDS_PN = "1";
"B":   PN = "2"  !CDS_PN = "2";
BODY = "Q_RES","I21": LOCATION = "R985" #&CDS_LOCATION = "R985" &SEC = "1" #&CDS_SEC = "1";
"A":   PN = "1"  !CDS_PN = "1";
"B":   PN = "2"  !CDS_PN = "2";
BODY = "Q_RES","I23": LOCATION = "R988" #&CDS_LOCATION = "R988" &SEC = "1" #&CDS_SEC = "1";
"A":   PN = "1"  !CDS_PN = "1";
"B":   PN = "2"  !CDS_PN = "2";
BODY = "Q_RES","I24": LOCATION = "R987" #&CDS_LOCATION = "R987" &SEC = "1" #&CDS_SEC = "1";
"A":   PN = "1"  !CDS_PN = "1";
"B":   PN = "2"  !CDS_PN = "2";
BODY = "Q_RES","I25": LOCATION = "R986" #&CDS_LOCATION = "R986" &SEC = "1" #&CDS_SEC = "1";
"A":   PN = "1"  !CDS_PN = "1";
"B":   PN = "2"  !CDS_PN = "2";
BODY = "Q_RES","I44": LOCATION = "R1423" #&CDS_LOCATION = "R1423" &SEC = "1" #&CDS_SEC = "1";
"A":   PN = "1"  !CDS_PN = "1";
"B":   PN = "2"  !CDS_PN = "2";
BODY = "Q_RES","I48": LOCATION = "R1442" #&CDS_LOCATION = "R1442" &SEC = "1" #&CDS_SEC = "1";
"A":   PN = "1"  !CDS_PN = "1";
"B":   PN = "2"  !CDS_PN = "2";
BODY = "Q_RES","I49": LOCATION = "R1443" #&CDS_LOCATION = "R1443" &SEC = "1" #&CDS_SEC = "1";
"A":   PN = "1"  !CDS_PN = "1";
"B":   PN = "2"  !CDS_PN = "2";
BODY = "Q_RES","I54": LOCATION = "R1444" #&CDS_LOCATION = "R1444" &SEC = "1" #&CDS_SEC = "1";
"A":   PN = "1"  !CDS_PN = "1";
"B":   PN = "2"  !CDS_PN = "2";
BODY = "Q_RES","I62": LOCATION = "R1448" #&CDS_LOCATION = "R1448" &SEC = "1" #&CDS_SEC = "1";
"A":   PN = "1"  !CDS_PN = "1";
"B":   PN = "2"  !CDS_PN = "2";
BODY = "Q_RES","I68": LOCATION = "R1447" #&CDS_LOCATION = "R1447" &SEC = "1" #&CDS_SEC = "1";
"A":   PN = "1"  !CDS_PN = "1";
"B":   PN = "2"  !CDS_PN = "2";
BODY = "Q_RES","I81": LOCATION = "R1751" #&CDS_LOCATION = "R1751" &SEC = "1" #&CDS_SEC = "1";
"A":   PN = "1"  !CDS_PN = "1";
"B":   PN = "2"  !CDS_PN = "2";
BODY = "Q_RES","I82": LOCATION = "R1752" #&CDS_LOCATION = "R1752" &SEC = "1" #&CDS_SEC = "1";
"A":   PN = "1"  !CDS_PN = "1";
"B":   PN = "2"  !CDS_PN = "2";
BODY = "Q_RES","I84": LOCATION = "R1753" #&CDS_LOCATION = "R1753" &SEC = "1" #&CDS_SEC = "1";
"A":   PN = "1"  !CDS_PN = "1";
"B":   PN = "2"  !CDS_PN = "2";
BODY = "Q_RES","I88": LOCATION = "R1754" #&CDS_LOCATION = "R1754" &SEC = "1" #&CDS_SEC = "1";
"A":   PN = "1"  !CDS_PN = "1";
"B":   PN = "2"  !CDS_PN = "2";
BODY = "Q_RES","I91": LOCATION = "R1758" #&CDS_LOCATION = "R1758" &SEC = "1" #&CDS_SEC = "1";
"A":   PN = "1"  !CDS_PN = "1";
"B":   PN = "2"  !CDS_PN = "2";
BODY = "Q_RES","I96": LOCATION = "R1755" #&CDS_LOCATION = "R1755" &SEC = "1" #&CDS_SEC = "1";
"A":   PN = "1"  !CDS_PN = "1";
"B":   PN = "2"  !CDS_PN = "2";
BODY = "Q_RES","I98": LOCATION = "R1756" #&CDS_LOCATION = "R1756" &SEC = "1" #&CDS_SEC = "1";
"A":   PN = "1"  !CDS_PN = "1";
"B":   PN = "2"  !CDS_PN = "2";
BODY = "Q_RES","I99": LOCATION = "R1757" #&CDS_LOCATION = "R1757" &SEC = "1" #&CDS_SEC = "1";
"A":   PN = "1"  !CDS_PN = "1";
"B":   PN = "2"  !CDS_PN = "2";
BODY = "Q_RES","I110": LOCATION = "R1811" #&CDS_LOCATION = "R1811" &SEC = "1" #&CDS_SEC = "1";
"A":   PN = "1"  !CDS_PN = "1";
"B":   PN = "2"  !CDS_PN = "2";
BODY = "Q_RES","I111": LOCATION = "R1812" #&CDS_LOCATION = "R1812" &SEC = "1" #&CDS_SEC = "1";
"A":   PN = "1"  !CDS_PN = "1";
"B":   PN = "2"  !CDS_PN = "2";
BODY = "Q_RES","I122": LOCATION = "R1843" #&CDS_LOCATION = "R1843" &SEC = "1" #&CDS_SEC = "1";
"A":   PN = "1"  !CDS_PN = "1";
"B":   PN = "2"  !CDS_PN = "2";
BODY = "Q_RES","I123": LOCATION = "R1844" #&CDS_LOCATION = "R1844" &SEC = "1" #&CDS_SEC = "1";
"A":   PN = "1"  !CDS_PN = "1";
"B":   PN = "2"  !CDS_PN = "2";
BODY = "Q_RES","I127": LOCATION = "R1919" #&CDS_LOCATION = "R1919" &SEC = "1" #&CDS_SEC = "1";
"A":   PN = "1"  !CDS_PN = "1";
"B":   PN = "2"  !CDS_PN = "2";
BODY = "Q_RES","I129": LOCATION = "R4267" #&CDS_LOCATION = "R4267" &SEC = "1" #&CDS_SEC = "1";
"A":   PN = "1"  !CDS_PN = "1";
"B":   PN = "2"  !CDS_PN = "2";
DRAWING = "@s9s_mb_2u_lib.s9s_mb_2u(sch_1):page212";
BODY = "Q_RES","I7": LOCATION = "R1205" #&CDS_LOCATION = "R1205" &SEC = "1" #&CDS_SEC = "1";
"A":   PN = "1"  !CDS_PN = "1";
"B":   PN = "2"  !CDS_PN = "2";
BODY = "Q_RES","I10": LOCATION = "R1206" #&CDS_LOCATION = "R1206" &SEC = "1" #&CDS_SEC = "1";
"A":   PN = "1"  !CDS_PN = "1";
"B":   PN = "2"  !CDS_PN = "2";
BODY = "Q_RES","I15": LOCATION = "R1207" #&CDS_LOCATION = "R1207" &SEC = "1" #&CDS_SEC = "1";
"A":   PN = "1"  !CDS_PN = "1";
"B":   PN = "2"  !CDS_PN = "2";
BODY = "Q_RES","I17": LOCATION = "R110" #&CDS_LOCATION = "R110" &SEC = "1" #&CDS_SEC = "1";
"A":   PN = "1"  !CDS_PN = "1";
"B":   PN = "2"  !CDS_PN = "2";
BODY = "MOSFET_N","I19": LOCATION = "U70" #&CDS_LOCATION = "U70" &SEC = "1" #&CDS_SEC = "1";
"DRAIN":   PN = "D"  !CDS_PN = "D";
"GATE":   PN = "G"  !CDS_PN = "G";
"SOURCE":   PN = "S"  !CDS_PN = "S";
BODY = "Q_RES","I24": LOCATION = "R111" #&CDS_LOCATION = "R111" &SEC = "1" #&CDS_SEC = "1";
"A":   PN = "1"  !CDS_PN = "1";
"B":   PN = "2"  !CDS_PN = "2";
BODY = "Q_RES","I27": LOCATION = "R113" #&CDS_LOCATION = "R113" &SEC = "1" #&CDS_SEC = "1";
"A":   PN = "1"  !CDS_PN = "1";
"B":   PN = "2"  !CDS_PN = "2";
BODY = "Q_RES","I44": LOCATION = "R109" #&CDS_LOCATION = "R109" &SEC = "1" #&CDS_SEC = "1";
"A":   PN = "1"  !CDS_PN = "1";
"B":   PN = "2"  !CDS_PN = "2";
BODY = "Q_RES","I55": LOCATION = "R1469" #&CDS_LOCATION = "R1469" &SEC = "1" #&CDS_SEC = "1";
"A":   PN = "1"  !CDS_PN = "1";
"B":   PN = "2"  !CDS_PN = "2";
BODY = "Q_RES","I56": LOCATION = "R1470" #&CDS_LOCATION = "R1470" &SEC = "1" #&CDS_SEC = "1";
"A":   PN = "1"  !CDS_PN = "1";
"B":   PN = "2"  !CDS_PN = "2";
BODY = "Q_RES","I86": LOCATION = "R1995" #&CDS_LOCATION = "R1995" &SEC = "1" #&CDS_SEC = "1";
"A":   PN = "1"  !CDS_PN = "1";
"B":   PN = "2"  !CDS_PN = "2";
BODY = "Q_RES","I87": LOCATION = "R1996" #&CDS_LOCATION = "R1996" &SEC = "1" #&CDS_SEC = "1";
"A":   PN = "1"  !CDS_PN = "1";
"B":   PN = "2"  !CDS_PN = "2";
BODY = "Q_RES","I91": LOCATION = "R269" #&CDS_LOCATION = "R269" &SEC = "1" #&CDS_SEC = "1";
"A":   PN = "1"  !CDS_PN = "1";
"B":   PN = "2"  !CDS_PN = "2";
BODY = "Q_RES","I92": LOCATION = "R1541" #&CDS_LOCATION = "R1541" &SEC = "1" #&CDS_SEC = "1";
"A":   PN = "1"  !CDS_PN = "1";
"B":   PN = "2"  !CDS_PN = "2";
BODY = "Q_RES","I94": LOCATION = "R1744" #&CDS_LOCATION = "R1744" &SEC = "1" #&CDS_SEC = "1";
"A":   PN = "1"  !CDS_PN = "1";
"B":   PN = "2"  !CDS_PN = "2";
BODY = "Q_RES","I105": LOCATION = "R1514" #&CDS_LOCATION = "R1514" &SEC = "1" #&CDS_SEC = "1";
"A":   PN = "1"  !CDS_PN = "1";
"B":   PN = "2"  !CDS_PN = "2";
BODY = "Q_RES","I113": LOCATION = "R1520" #&CDS_LOCATION = "R1520" &SEC = "1" #&CDS_SEC = "1";
"A":   PN = "1"  !CDS_PN = "1";
"B":   PN = "2"  !CDS_PN = "2";
BODY = "Q_RES","I127": LOCATION = "R2738" #&CDS_LOCATION = "R2738" &SEC = "1" #&CDS_SEC = "1";
"A":   PN = "1"  !CDS_PN = "1";
"B":   PN = "2"  !CDS_PN = "2";
BODY = "Q_RES","I129": LOCATION = "R3050" #&CDS_LOCATION = "R3050" &SEC = "1" #&CDS_SEC = "1";
"A":   PN = "1"  !CDS_PN = "1";
"B":   PN = "2"  !CDS_PN = "2";
BODY = "Q_RES","I130": #LOCATION = "R1318" !CDS_LOCATION = "R1318" &SEC = "1" #&CDS_SEC = "1";
"A":   PN = "1"  !CDS_PN = "1";
"B":   PN = "2"  !CDS_PN = "2";
DRAWING = "@s9s_mb_2u_lib.s9s_mb_2u(sch_1):page217";
BODY = "Q_RES","I29": LOCATION = "R679" #&CDS_LOCATION = "R679" &SEC = "1" #&CDS_SEC = "1";
"A":   PN = "1"  !CDS_PN = "1";
"B":   PN = "2"  !CDS_PN = "2";
BODY = "Q_RES","I13": LOCATION = "R678" #&CDS_LOCATION = "R678" &SEC = "1" #&CDS_SEC = "1";
"A":   PN = "1"  !CDS_PN = "1";
"B":   PN = "2"  !CDS_PN = "2";
BODY = "Q_RES","I16": LOCATION = "R685" #&CDS_LOCATION = "R685" &SEC = "1" #&CDS_SEC = "1";
"A":   PN = "1"  !CDS_PN = "1";
"B":   PN = "2"  !CDS_PN = "2";
BODY = "Q_RES","I17": LOCATION = "R684" #&CDS_LOCATION = "R684" &SEC = "1" #&CDS_SEC = "1";
"A":   PN = "1"  !CDS_PN = "1";
"B":   PN = "2"  !CDS_PN = "2";
BODY = "Q_RES","I18": LOCATION = "R683" #&CDS_LOCATION = "R683" &SEC = "1" #&CDS_SEC = "1";
"A":   PN = "1"  !CDS_PN = "1";
"B":   PN = "2"  !CDS_PN = "2";
BODY = "QS3VH257QG8","I19": #LOCATION = "U15" !CDS_LOCATION = "U15" &SEC = "1" #&CDS_SEC = "1";
"E*":   PN = "15"  !CDS_PN = "15";
"GND":   PN = "8"  !CDS_PN = "8";
"I0A":   PN = "2"  !CDS_PN = "2";
"I0B":   PN = "5"  !CDS_PN = "5";
"I0C":   PN = "11"  !CDS_PN = "11";
"I0D":   PN = "14"  !CDS_PN = "14";
"I1A":   PN = "3"  !CDS_PN = "3";
"I1B":   PN = "6"  !CDS_PN = "6";
"I1C":   PN = "10"  !CDS_PN = "10";
"I1D":   PN = "13"  !CDS_PN = "13";
"S":   PN = "1"  !CDS_PN = "1";
"VCC":   PN = "16"  !CDS_PN = "16";
"YA":   PN = "4"  !CDS_PN = "4";
"YB":   PN = "7"  !CDS_PN = "7";
"YC":   PN = "9"  !CDS_PN = "9";
"YD":   PN = "12"  !CDS_PN = "12";
BODY = "Q_RES","I20": LOCATION = "R682" #&CDS_LOCATION = "R682" &SEC = "1" #&CDS_SEC = "1";
"A":   PN = "1"  !CDS_PN = "1";
"B":   PN = "2"  !CDS_PN = "2";
BODY = "Q_CAP","I24": LOCATION = "C538" #&CDS_LOCATION = "C538" &SEC = "1" #&CDS_SEC = "1";
"A":   PN = "1"  !CDS_PN = "1";
"B":   PN = "2"  !CDS_PN = "2";
BODY = "Q_RES","I25": #LOCATION = "R689" !CDS_LOCATION = "R689" &SEC = "1" #&CDS_SEC = "1";
"A":   PN = "1"  !CDS_PN = "1";
"B":   PN = "2"  !CDS_PN = "2";
BODY = "Q_RES","I26": LOCATION = "R690" #&CDS_LOCATION = "R690" &SEC = "1" #&CDS_SEC = "1";
"A":   PN = "1"  !CDS_PN = "1";
"B":   PN = "2"  !CDS_PN = "2";
BODY = "Q_RES","I30": LOCATION = "R680" #&CDS_LOCATION = "R680" &SEC = "1" #&CDS_SEC = "1";
"A":   PN = "1"  !CDS_PN = "1";
"B":   PN = "2"  !CDS_PN = "2";
BODY = "Q_RES","I32": LOCATION = "R681" #&CDS_LOCATION = "R681" &SEC = "1" #&CDS_SEC = "1";
"A":   PN = "1"  !CDS_PN = "1";
"B":   PN = "2"  !CDS_PN = "2";
BODY = "Q_RES","I33": LOCATION = "R686" #&CDS_LOCATION = "R686" &SEC = "1" #&CDS_SEC = "1";
"A":   PN = "1"  !CDS_PN = "1";
"B":   PN = "2"  !CDS_PN = "2";
BODY = "Q_RES","I34": #LOCATION = "R687" !CDS_LOCATION = "R687" &SEC = "1" #&CDS_SEC = "1";
"A":   PN = "1"  !CDS_PN = "1";
"B":   PN = "2"  !CDS_PN = "2";
BODY = "Q_RES","I35": LOCATION = "R688" #&CDS_LOCATION = "R688" &SEC = "1" #&CDS_SEC = "1";
"A":   PN = "1"  !CDS_PN = "1";
"B":   PN = "2"  !CDS_PN = "2";
BODY = "Q_RES","I37": LOCATION = "R694" #&CDS_LOCATION = "R694" &SEC = "1" #&CDS_SEC = "1";
"A":   PN = "1"  !CDS_PN = "1";
"B":   PN = "2"  !CDS_PN = "2";
BODY = "Q_RES","I38": LOCATION = "R693" #&CDS_LOCATION = "R693" &SEC = "1" #&CDS_SEC = "1";
"A":   PN = "1"  !CDS_PN = "1";
"B":   PN = "2"  !CDS_PN = "2";
BODY = "Q_RES","I39": LOCATION = "R691" #&CDS_LOCATION = "R691" &SEC = "1" #&CDS_SEC = "1";
"A":   PN = "1"  !CDS_PN = "1";
"B":   PN = "2"  !CDS_PN = "2";
BODY = "Q_RES","I40": LOCATION = "R692" #&CDS_LOCATION = "R692" &SEC = "1" #&CDS_SEC = "1";
"A":   PN = "1"  !CDS_PN = "1";
"B":   PN = "2"  !CDS_PN = "2";
BODY = "Q_RES","I42": LOCATION = "R318" #&CDS_LOCATION = "R318" &SEC = "1" #&CDS_SEC = "1";
"A":   PN = "1"  !CDS_PN = "1";
"B":   PN = "2"  !CDS_PN = "2";
BODY = "Q_RES","I43": LOCATION = "R87" #&CDS_LOCATION = "R87" &SEC = "1" #&CDS_SEC = "1";
"A":   PN = "1"  !CDS_PN = "1";
"B":   PN = "2"  !CDS_PN = "2";
BODY = "Q_RES","I53": LOCATION = "R1821" #&CDS_LOCATION = "R1821" &SEC = "1" #&CDS_SEC = "1";
"A":   PN = "1"  !CDS_PN = "1";
"B":   PN = "2"  !CDS_PN = "2";
DRAWING = "@s9s_mb_2u_lib.s9s_mb_2u(sch_1):page218";
BODY = "Q_RES","I18": LOCATION = "R663" #&CDS_LOCATION = "R663" &SEC = "1" #&CDS_SEC = "1";
"A":   PN = "1"  !CDS_PN = "1";
"B":   PN = "2"  !CDS_PN = "2";
BODY = "Q_RES","I22": LOCATION = "R666" #&CDS_LOCATION = "R666" &SEC = "1" #&CDS_SEC = "1";
"A":   PN = "1"  !CDS_PN = "1";
"B":   PN = "2"  !CDS_PN = "2";
BODY = "Q_RES","I28": LOCATION = "R664" #&CDS_LOCATION = "R664" &SEC = "1" #&CDS_SEC = "1";
"A":   PN = "1"  !CDS_PN = "1";
"B":   PN = "2"  !CDS_PN = "2";
BODY = "Q_RES","I30": #LOCATION = "R672" !CDS_LOCATION = "R672" &SEC = "1" #&CDS_SEC = "1";
"A":   PN = "1"  !CDS_PN = "1";
"B":   PN = "2"  !CDS_PN = "2";
BODY = "Q_RES","I31": LOCATION = "R673" #&CDS_LOCATION = "R673" &SEC = "1" #&CDS_SEC = "1";
"A":   PN = "1"  !CDS_PN = "1";
"B":   PN = "2"  !CDS_PN = "2";
BODY = "Q_RES","I32": #LOCATION = "R670" !CDS_LOCATION = "R670" &SEC = "1" #&CDS_SEC = "1";
"A":   PN = "1"  !CDS_PN = "1";
"B":   PN = "2"  !CDS_PN = "2";
BODY = "Q_RES","I33": LOCATION = "R671" #&CDS_LOCATION = "R671" &SEC = "1" #&CDS_SEC = "1";
"A":   PN = "1"  !CDS_PN = "1";
"B":   PN = "2"  !CDS_PN = "2";
BODY = "Q_RES","I4": LOCATION = "R661" #&CDS_LOCATION = "R661" &SEC = "1" #&CDS_SEC = "1";
"A":   PN = "1"  !CDS_PN = "1";
"B":   PN = "2"  !CDS_PN = "2";
BODY = "QS3VH257QG8","I12": #LOCATION = "U14" !CDS_LOCATION = "U14" &SEC = "1" #&CDS_SEC = "1";
"E*":   PN = "15"  !CDS_PN = "15";
"GND":   PN = "8"  !CDS_PN = "8";
"I0A":   PN = "2"  !CDS_PN = "2";
"I0B":   PN = "5"  !CDS_PN = "5";
"I0C":   PN = "11"  !CDS_PN = "11";
"I0D":   PN = "14"  !CDS_PN = "14";
"I1A":   PN = "3"  !CDS_PN = "3";
"I1B":   PN = "6"  !CDS_PN = "6";
"I1C":   PN = "10"  !CDS_PN = "10";
"I1D":   PN = "13"  !CDS_PN = "13";
"S":   PN = "1"  !CDS_PN = "1";
"VCC":   PN = "16"  !CDS_PN = "16";
"YA":   PN = "4"  !CDS_PN = "4";
"YB":   PN = "7"  !CDS_PN = "7";
"YC":   PN = "9"  !CDS_PN = "9";
"YD":   PN = "12"  !CDS_PN = "12";
BODY = "Q_RES","I17": LOCATION = "R662" #&CDS_LOCATION = "R662" &SEC = "1" #&CDS_SEC = "1";
"A":   PN = "1"  !CDS_PN = "1";
"B":   PN = "2"  !CDS_PN = "2";
BODY = "Q_RES","I20": LOCATION = "R668" #&CDS_LOCATION = "R668" &SEC = "1" #&CDS_SEC = "1";
"A":   PN = "1"  !CDS_PN = "1";
"B":   PN = "2"  !CDS_PN = "2";
BODY = "Q_RES","I21": LOCATION = "R667" #&CDS_LOCATION = "R667" &SEC = "1" #&CDS_SEC = "1";
"A":   PN = "1"  !CDS_PN = "1";
"B":   PN = "2"  !CDS_PN = "2";
BODY = "Q_RES","I23": LOCATION = "R665" #&CDS_LOCATION = "R665" &SEC = "1" #&CDS_SEC = "1";
"A":   PN = "1"  !CDS_PN = "1";
"B":   PN = "2"  !CDS_PN = "2";
BODY = "Q_CAP","I25": LOCATION = "C537" #&CDS_LOCATION = "C537" &SEC = "1" #&CDS_SEC = "1";
"A":   PN = "1"  !CDS_PN = "1";
"B":   PN = "2"  !CDS_PN = "2";
BODY = "Q_RES","I29": LOCATION = "R669" #&CDS_LOCATION = "R669" &SEC = "1" #&CDS_SEC = "1";
"A":   PN = "1"  !CDS_PN = "1";
"B":   PN = "2"  !CDS_PN = "2";
BODY = "Q_RES","I34": LOCATION = "R677" #&CDS_LOCATION = "R677" &SEC = "1" #&CDS_SEC = "1";
"A":   PN = "1"  !CDS_PN = "1";
"B":   PN = "2"  !CDS_PN = "2";
BODY = "Q_RES","I35": LOCATION = "R676" #&CDS_LOCATION = "R676" &SEC = "1" #&CDS_SEC = "1";
"A":   PN = "1"  !CDS_PN = "1";
"B":   PN = "2"  !CDS_PN = "2";
BODY = "Q_RES","I36": LOCATION = "R675" #&CDS_LOCATION = "R675" &SEC = "1" #&CDS_SEC = "1";
"A":   PN = "1"  !CDS_PN = "1";
"B":   PN = "2"  !CDS_PN = "2";
BODY = "Q_RES","I37": LOCATION = "R674" #&CDS_LOCATION = "R674" &SEC = "1" #&CDS_SEC = "1";
"A":   PN = "1"  !CDS_PN = "1";
"B":   PN = "2"  !CDS_PN = "2";
DRAWING = "@s9s_mb_2u_lib.s9s_mb_2u(sch_1):page219";
BODY = "Q_RES","I2": LOCATION = "R537" #&CDS_LOCATION = "R537" &SEC = "1" #&CDS_SEC = "1";
"A":   PN = "1"  !CDS_PN = "1";
"B":   PN = "2"  !CDS_PN = "2";
BODY = "Q_RES","I6": LOCATION = "R539" #&CDS_LOCATION = "R539" &SEC = "1" #&CDS_SEC = "1";
"A":   PN = "1"  !CDS_PN = "1";
"B":   PN = "2"  !CDS_PN = "2";
BODY = "Q_RES","I9": LOCATION = "R538" #&CDS_LOCATION = "R538" &SEC = "1" #&CDS_SEC = "1";
"A":   PN = "1"  !CDS_PN = "1";
"B":   PN = "2"  !CDS_PN = "2";
BODY = "Q_RES","I10": LOCATION = "R540" #&CDS_LOCATION = "R540" &SEC = "1" #&CDS_SEC = "1";
"A":   PN = "1"  !CDS_PN = "1";
"B":   PN = "2"  !CDS_PN = "2";
BODY = "Q_RES","I3": LOCATION = "R536" #&CDS_LOCATION = "R536" &SEC = "1" #&CDS_SEC = "1";
"A":   PN = "1"  !CDS_PN = "1";
"B":   PN = "2"  !CDS_PN = "2";
BODY = "Q_RES","I8": LOCATION = "R587" #&CDS_LOCATION = "R587" &SEC = "1" #&CDS_SEC = "1";
"A":   PN = "1"  !CDS_PN = "1";
"B":   PN = "2"  !CDS_PN = "2";
BODY = "Q_RES","I18": LOCATION = "R1822" #&CDS_LOCATION = "R1822" &SEC = "1" #&CDS_SEC = "1";
"A":   PN = "1"  !CDS_PN = "1";
"B":   PN = "2"  !CDS_PN = "2";
BODY = "Q_RES","I20": LOCATION = "R1090" #&CDS_LOCATION = "R1090" &SEC = "1" #&CDS_SEC = "1";
"A":   PN = "1"  !CDS_PN = "1";
"B":   PN = "2"  !CDS_PN = "2";
BODY = "Q_RES","I21": LOCATION = "R1089" #&CDS_LOCATION = "R1089" &SEC = "1" #&CDS_SEC = "1";
"A":   PN = "1"  !CDS_PN = "1";
"B":   PN = "2"  !CDS_PN = "2";
BODY = "Q_RES","I22": LOCATION = "R651" #&CDS_LOCATION = "R651" &SEC = "1" #&CDS_SEC = "1";
"A":   PN = "1"  !CDS_PN = "1";
"B":   PN = "2"  !CDS_PN = "2";
BODY = "Q_RES","I23": LOCATION = "R652" #&CDS_LOCATION = "R652" &SEC = "1" #&CDS_SEC = "1";
"A":   PN = "1"  !CDS_PN = "1";
"B":   PN = "2"  !CDS_PN = "2";
BODY = "Q_RES","I24": LOCATION = "R2985" #&CDS_LOCATION = "R2985" &SEC = "1" #&CDS_SEC = "1";
"A":   PN = "1"  !CDS_PN = "1";
"B":   PN = "2"  !CDS_PN = "2";
BODY = "Q_RES","I25": LOCATION = "R2984" #&CDS_LOCATION = "R2984" &SEC = "1" #&CDS_SEC = "1";
"A":   PN = "1"  !CDS_PN = "1";
"B":   PN = "2"  !CDS_PN = "2";
BODY = "Q_RES","I35": LOCATION = "R3526" #&CDS_LOCATION = "R3526" &SEC = "1" #&CDS_SEC = "1";
"A":   PN = "1"  !CDS_PN = "1";
"B":   PN = "2"  !CDS_PN = "2";
BODY = "Q_RES","I36": LOCATION = "R2967" #&CDS_LOCATION = "R2967" &SEC = "1" #&CDS_SEC = "1";
"A":   PN = "1"  !CDS_PN = "1";
"B":   PN = "2"  !CDS_PN = "2";
BODY = "Q_RES","I37": LOCATION = "R3527" #&CDS_LOCATION = "R3527" &SEC = "1" #&CDS_SEC = "1";
"A":   PN = "1"  !CDS_PN = "1";
"B":   PN = "2"  !CDS_PN = "2";
BODY = "Q_RES","I38": LOCATION = "R3393" #&CDS_LOCATION = "R3393" #SEC = "1" !CDS_SEC = "1";
"A":   PN = "1"  !CDS_PN = "1";
"B":   PN = "2"  !CDS_PN = "2";
BODY = "Q_RES","I39": LOCATION = "R2968" #&CDS_LOCATION = "R2968" &SEC = "1" #&CDS_SEC = "1";
"A":   PN = "1"  !CDS_PN = "1";
"B":   PN = "2"  !CDS_PN = "2";
BODY = "Q_RES","I40": LOCATION = "R3394" #&CDS_LOCATION = "R3394" &SEC = "1" #&CDS_SEC = "1";
"A":   PN = "1"  !CDS_PN = "1";
"B":   PN = "2"  !CDS_PN = "2";
BODY = "Q_RES","I41": LOCATION = "R2268" #&CDS_LOCATION = "R2268" &SEC = "1" #&CDS_SEC = "1";
"A":   PN = "1"  !CDS_PN = "1";
"B":   PN = "2"  !CDS_PN = "2";
BODY = "TCA9548APWR","I45": #LOCATION = "U36" !CDS_LOCATION = "U36" #SEC = "1" !CDS_SEC = "1";
"A0":   PN = "1"  !CDS_PN = "1";
"A1":   PN = "2"  !CDS_PN = "2";
"A2":   PN = "21"  !CDS_PN = "21";
"GND":   PN = "12"  !CDS_PN = "12";
"RESET#":   PN = "3"  !CDS_PN = "3";
"SC0":   PN = "5"  !CDS_PN = "5";
"SC1":   PN = "7"  !CDS_PN = "7";
"SC2":   PN = "9"  !CDS_PN = "9";
"SC3":   PN = "11"  !CDS_PN = "11";
"SC4":   PN = "14"  !CDS_PN = "14";
"SC5":   PN = "16"  !CDS_PN = "16";
"SC6":   PN = "18"  !CDS_PN = "18";
"SC7":   PN = "20"  !CDS_PN = "20";
"SCL":   PN = "22"  !CDS_PN = "22";
"SD0":   PN = "4"  !CDS_PN = "4";
"SD1":   PN = "6"  !CDS_PN = "6";
"SD2":   PN = "8"  !CDS_PN = "8";
"SD3":   PN = "10"  !CDS_PN = "10";
"SD4":   PN = "13"  !CDS_PN = "13";
"SD5":   PN = "15"  !CDS_PN = "15";
"SD6":   PN = "17"  !CDS_PN = "17";
"SD7":   PN = "19"  !CDS_PN = "19";
"SDA":   PN = "23"  !CDS_PN = "23";
"VCC":   PN = "24"  !CDS_PN = "24";
BODY = "Q_CAP","I47": LOCATION = "C174" #&CDS_LOCATION = "C174" &SEC = "1" #&CDS_SEC = "1";
"A":   PN = "1"  !CDS_PN = "1";
"B":   PN = "2"  !CDS_PN = "2";
BODY = "Q_RES","I49": LOCATION = "R3535" #&CDS_LOCATION = "R3535" &SEC = "1" #&CDS_SEC = "1";
"A":   PN = "1"  !CDS_PN = "1";
"B":   PN = "2"  !CDS_PN = "2";
BODY = "Q_RES","I50": LOCATION = "R3536" #&CDS_LOCATION = "R3536" &SEC = "1" #&CDS_SEC = "1";
"A":   PN = "1"  !CDS_PN = "1";
"B":   PN = "2"  !CDS_PN = "2";
BODY = "Q_RES","I51": LOCATION = "R3583" #&CDS_LOCATION = "R3583" &SEC = "1" #&CDS_SEC = "1";
"A":   PN = "1"  !CDS_PN = "1";
"B":   PN = "2"  !CDS_PN = "2";
BODY = "Q_RES","I52": LOCATION = "R3582" #&CDS_LOCATION = "R3582" &SEC = "1" #&CDS_SEC = "1";
"A":   PN = "1"  !CDS_PN = "1";
"B":   PN = "2"  !CDS_PN = "2";
BODY = "Q_RES","I53": LOCATION = "R3396" #&CDS_LOCATION = "R3396" &SEC = "1" #&CDS_SEC = "1";
"A":   PN = "1"  !CDS_PN = "1";
"B":   PN = "2"  !CDS_PN = "2";
BODY = "Q_RES","I54": LOCATION = "R3395" #&CDS_LOCATION = "R3395" &SEC = "1" #&CDS_SEC = "1";
"A":   PN = "1"  !CDS_PN = "1";
"B":   PN = "2"  !CDS_PN = "2";
BODY = "Q_RES","I56": LOCATION = "R2205" #&CDS_LOCATION = "R2205" &SEC = "1" #&CDS_SEC = "1";
"A":   PN = "1"  !CDS_PN = "1";
"B":   PN = "2"  !CDS_PN = "2";
BODY = "Q_RES","I57": LOCATION = "R2204" #&CDS_LOCATION = "R2204" &SEC = "1" #&CDS_SEC = "1";
"A":   PN = "1"  !CDS_PN = "1";
"B":   PN = "2"  !CDS_PN = "2";
BODY = "Q_RES","I59": LOCATION = "R3580" #&CDS_LOCATION = "R3580" &SEC = "1" #&CDS_SEC = "1";
"A":   PN = "1"  !CDS_PN = "1";
"B":   PN = "2"  !CDS_PN = "2";
BODY = "Q_RES","I60": LOCATION = "R3581" #&CDS_LOCATION = "R3581" &SEC = "1" #&CDS_SEC = "1";
"A":   PN = "1"  !CDS_PN = "1";
"B":   PN = "2"  !CDS_PN = "2";
BODY = "Q_RES","I61": LOCATION = "R2565" #&CDS_LOCATION = "R2565" &SEC = "1" #&CDS_SEC = "1";
"A":   PN = "1"  !CDS_PN = "1";
"B":   PN = "2"  !CDS_PN = "2";
BODY = "Q_RES","I62": LOCATION = "R2566" #&CDS_LOCATION = "R2566" &SEC = "1" #&CDS_SEC = "1";
"A":   PN = "1"  !CDS_PN = "1";
"B":   PN = "2"  !CDS_PN = "2";
BODY = "Q_RES","I63": LOCATION = "R2703" #&CDS_LOCATION = "R2703" &SEC = "1" #&CDS_SEC = "1";
"A":   PN = "1"  !CDS_PN = "1";
"B":   PN = "2"  !CDS_PN = "2";
BODY = "Q_RES","I64": LOCATION = "R2704" #&CDS_LOCATION = "R2704" &SEC = "1" #&CDS_SEC = "1";
"A":   PN = "1"  !CDS_PN = "1";
"B":   PN = "2"  !CDS_PN = "2";
BODY = "Q_RES","I65": LOCATION = "R588" #&CDS_LOCATION = "R588" &SEC = "1" #&CDS_SEC = "1";
"A":   PN = "1"  !CDS_PN = "1";
"B":   PN = "2"  !CDS_PN = "2";
BODY = "Q_RES","I66": LOCATION = "R589" #&CDS_LOCATION = "R589" &SEC = "1" #&CDS_SEC = "1";
"A":   PN = "1"  !CDS_PN = "1";
"B":   PN = "2"  !CDS_PN = "2";
DRAWING = "@s9s_mb_2u_lib.s9s_mb_2u(sch_1):page223";
BODY = "Q_RES","I8": LOCATION = "R1006" #&CDS_LOCATION = "R1006" &SEC = "1" #&CDS_SEC = "1";
"A":   PN = "1"  !CDS_PN = "1";
"B":   PN = "2"  !CDS_PN = "2";
BODY = "Q_RES","I12": LOCATION = "R1007" #&CDS_LOCATION = "R1007" &SEC = "1" #&CDS_SEC = "1";
"A":   PN = "1"  !CDS_PN = "1";
"B":   PN = "2"  !CDS_PN = "2";
BODY = "Q_CAP","I18": LOCATION = "C561" #&CDS_LOCATION = "C561" &SEC = "1" #&CDS_SEC = "1";
"A":   PN = "1"  !CDS_PN = "1";
"B":   PN = "2"  !CDS_PN = "2";
BODY = "Q_CAP","I20": LOCATION = "C559" #&CDS_LOCATION = "C559" &SEC = "1" #&CDS_SEC = "1";
"A":   PN = "1"  !CDS_PN = "1";
"B":   PN = "2"  !CDS_PN = "2";
BODY = "Q_RES","I22": LOCATION = "R911" #&CDS_LOCATION = "R911" &SEC = "1" #&CDS_SEC = "1";
"A":   PN = "1"  !CDS_PN = "1";
"B":   PN = "2"  !CDS_PN = "2";
BODY = "Q_RES","I24": LOCATION = "R910" #&CDS_LOCATION = "R910" &SEC = "1" #&CDS_SEC = "1";
"A":   PN = "1"  !CDS_PN = "1";
"B":   PN = "2"  !CDS_PN = "2";
BODY = "Q_CAP","I31": LOCATION = "C562" #&CDS_LOCATION = "C562" &SEC = "1" #&CDS_SEC = "1";
"A":   PN = "1"  !CDS_PN = "1";
"B":   PN = "2"  !CDS_PN = "2";
BODY = "Q_RES","I34": LOCATION = "R1002" #&CDS_LOCATION = "R1002" &SEC = "1" #&CDS_SEC = "1";
"A":   PN = "1"  !CDS_PN = "1";
"B":   PN = "2"  !CDS_PN = "2";
BODY = "Q_RES","I38": LOCATION = "R1003" #&CDS_LOCATION = "R1003" &SEC = "1" #&CDS_SEC = "1";
"A":   PN = "1"  !CDS_PN = "1";
"B":   PN = "2"  !CDS_PN = "2";
BODY = "PCA9617ADP","I39": LOCATION = "U28" #&CDS_LOCATION = "U28" #SEC = "1" !CDS_SEC = "1";
"EN":   PN = "5"  !CDS_PN = "5";
"GND":   PN = "4"  !CDS_PN = "4";
"SCLA":   PN = "2"  !CDS_PN = "2";
"SCLB":   PN = "7"  !CDS_PN = "7";
"SDAA":   PN = "3"  !CDS_PN = "3";
"SDAB":   PN = "6"  !CDS_PN = "6";
"VCCA":   PN = "1"  !CDS_PN = "1";
"VCCB":   PN = "8"  !CDS_PN = "8";
BODY = "Q_CAP","I42": LOCATION = "C560" #&CDS_LOCATION = "C560" &SEC = "1" #&CDS_SEC = "1";
"A":   PN = "1"  !CDS_PN = "1";
"B":   PN = "2"  !CDS_PN = "2";
BODY = "PCA9617ADP","I43": LOCATION = "U29" #&CDS_LOCATION = "U29" #SEC = "1" !CDS_SEC = "1";
"EN":   PN = "5"  !CDS_PN = "5";
"GND":   PN = "4"  !CDS_PN = "4";
"SCLA":   PN = "2"  !CDS_PN = "2";
"SCLB":   PN = "7"  !CDS_PN = "7";
"SDAA":   PN = "3"  !CDS_PN = "3";
"SDAB":   PN = "6"  !CDS_PN = "6";
"VCCA":   PN = "1"  !CDS_PN = "1";
"VCCB":   PN = "8"  !CDS_PN = "8";
BODY = "Q_RES","I46": LOCATION = "R964" #&CDS_LOCATION = "R964" &SEC = "1" #&CDS_SEC = "1";
"A":   PN = "1"  !CDS_PN = "1";
"B":   PN = "2"  !CDS_PN = "2";
BODY = "Q_RES","I48": LOCATION = "R963" #&CDS_LOCATION = "R963" &SEC = "1" #&CDS_SEC = "1";
"A":   PN = "1"  !CDS_PN = "1";
"B":   PN = "2"  !CDS_PN = "2";
BODY = "Q_RES","I52": LOCATION = "R1000" #&CDS_LOCATION = "R1000" &SEC = "1" #&CDS_SEC = "1";
"A":   PN = "1"  !CDS_PN = "1";
"B":   PN = "2"  !CDS_PN = "2";
BODY = "Q_RES","I53": LOCATION = "R998" #&CDS_LOCATION = "R998" &SEC = "1" #&CDS_SEC = "1";
"A":   PN = "1"  !CDS_PN = "1";
"B":   PN = "2"  !CDS_PN = "2";
BODY = "Q_RES","I55": LOCATION = "R1001" #&CDS_LOCATION = "R1001" &SEC = "1" #&CDS_SEC = "1";
"A":   PN = "1"  !CDS_PN = "1";
"B":   PN = "2"  !CDS_PN = "2";
BODY = "CONN3_210HP1030BR1","I64": LOCATION = "JP7" #&CDS_LOCATION = "JP7" &SEC = "1" #&CDS_SEC = "1";
"1":   PN = "1"  !CDS_PN = "1";
"2":   PN = "2"  !CDS_PN = "2";
"3":   PN = "3"  !CDS_PN = "3";
BODY = "Q_RES","I69": LOCATION = "R999" #&CDS_LOCATION = "R999" &SEC = "1" #&CDS_SEC = "1";
"A":   PN = "1"  !CDS_PN = "1";
"B":   PN = "2"  !CDS_PN = "2";
BODY = "Q_RES","I76": LOCATION = "R2479" #&CDS_LOCATION = "R2479" &SEC = "1" #&CDS_SEC = "1";
"A":   PN = "1"  !CDS_PN = "1";
"B":   PN = "2"  !CDS_PN = "2";
BODY = "Q_RES","I77": LOCATION = "R2480" #&CDS_LOCATION = "R2480" &SEC = "1" #&CDS_SEC = "1";
"A":   PN = "1"  !CDS_PN = "1";
"B":   PN = "2"  !CDS_PN = "2";
BODY = "Q_RES","I81": LOCATION = "R968" #&CDS_LOCATION = "R968" &SEC = "1" #&CDS_SEC = "1";
"A":   PN = "1"  !CDS_PN = "1";
"B":   PN = "2"  !CDS_PN = "2";
BODY = "Q_RES","I82": LOCATION = "R966" #&CDS_LOCATION = "R966" &SEC = "1" #&CDS_SEC = "1";
"A":   PN = "1"  !CDS_PN = "1";
"B":   PN = "2"  !CDS_PN = "2";
BODY = "Q_RES","I88": LOCATION = "R2477" #&CDS_LOCATION = "R2477" &SEC = "1" #&CDS_SEC = "1";
"A":   PN = "1"  !CDS_PN = "1";
"B":   PN = "2"  !CDS_PN = "2";
BODY = "Q_RES","I89": LOCATION = "R2478" #&CDS_LOCATION = "R2478" &SEC = "1" #&CDS_SEC = "1";
"A":   PN = "1"  !CDS_PN = "1";
"B":   PN = "2"  !CDS_PN = "2";
BODY = "Q_RES","I93": LOCATION = "R965" #&CDS_LOCATION = "R965" &SEC = "1" #&CDS_SEC = "1";
"A":   PN = "1"  !CDS_PN = "1";
"B":   PN = "2"  !CDS_PN = "2";
BODY = "Q_RES","I94": LOCATION = "R967" #&CDS_LOCATION = "R967" &SEC = "1" #&CDS_SEC = "1";
"A":   PN = "1"  !CDS_PN = "1";
"B":   PN = "2"  !CDS_PN = "2";
BODY = "Q_RES","I99": #LOCATION = "R961" !CDS_LOCATION = "R961" &SEC = "1" #&CDS_SEC = "1";
"A":   PN = "1"  !CDS_PN = "1";
"B":   PN = "2"  !CDS_PN = "2";
BODY = "Q_RES","I100": #LOCATION = "R962" !CDS_LOCATION = "R962" &SEC = "1" #&CDS_SEC = "1";
"A":   PN = "1"  !CDS_PN = "1";
"B":   PN = "2"  !CDS_PN = "2";
BODY = "Q_RES","I101": #LOCATION = "R960" !CDS_LOCATION = "R960" &SEC = "1" #&CDS_SEC = "1";
"A":   PN = "1"  !CDS_PN = "1";
"B":   PN = "2"  !CDS_PN = "2";
BODY = "Q_RES","I102": #LOCATION = "R909" !CDS_LOCATION = "R909" &SEC = "1" #&CDS_SEC = "1";
"A":   PN = "1"  !CDS_PN = "1";
"B":   PN = "2"  !CDS_PN = "2";
BODY = "MOSFET_NCH_DUAL","I104": #LOCATION = "Q15" !CDS_LOCATION = "Q15" #SEC = "1" !CDS_SEC = "1";
"D1":   PN = "6"  !CDS_PN = "6";
"G1":   PN = "2"  !CDS_PN = "2";
"S1":   PN = "1"  !CDS_PN = "1";
BODY = "MOSFET_NCH_DUAL","I106": #LOCATION = "Q16" !CDS_LOCATION = "Q16" &SEC = "1" #&CDS_SEC = "1";
"D1":   PN = "6"  !CDS_PN = "6";
"G1":   PN = "2"  !CDS_PN = "2";
"S1":   PN = "1"  !CDS_PN = "1";
BODY = "MOSFET_NCH_DUAL","I108": #LOCATION = "Q15" !CDS_LOCATION = "Q15" &SEC = "2" #&CDS_SEC = "2";
"D2":   PN = "3"  !CDS_PN = "3";
"G2":   PN = "5"  !CDS_PN = "5";
"S2":   PN = "4"  !CDS_PN = "4";
BODY = "MOSFET_NCH_DUAL","I109": #LOCATION = "Q16" !CDS_LOCATION = "Q16" &SEC = "2" #&CDS_SEC = "2";
"D2":   PN = "3"  !CDS_PN = "3";
"G2":   PN = "5"  !CDS_PN = "5";
"S2":   PN = "4"  !CDS_PN = "4";
DRAWING = "@s9s_mb_2u_lib.s9s_mb_2u(sch_1):page224";
BODY = "Q_RES","I3": LOCATION = "R1648" #&CDS_LOCATION = "R1648" &SEC = "1" #&CDS_SEC = "1";
"A":   PN = "1"  !CDS_PN = "1";
"B":   PN = "2"  !CDS_PN = "2";
BODY = "Q_RES","I6": LOCATION = "R979" #&CDS_LOCATION = "R979" &SEC = "1" #&CDS_SEC = "1";
"A":   PN = "1"  !CDS_PN = "1";
"B":   PN = "2"  !CDS_PN = "2";
BODY = "Q_RES","I8": LOCATION = "R977" #&CDS_LOCATION = "R977" &SEC = "1" #&CDS_SEC = "1";
"A":   PN = "1"  !CDS_PN = "1";
"B":   PN = "2"  !CDS_PN = "2";
BODY = "Q_RES","I13": LOCATION = "R448" #&CDS_LOCATION = "R448" &SEC = "1" #&CDS_SEC = "1";
"A":   PN = "1"  !CDS_PN = "1";
"B":   PN = "2"  !CDS_PN = "2";
BODY = "Q_RES","I14": LOCATION = "R980" #&CDS_LOCATION = "R980" &SEC = "1" #&CDS_SEC = "1";
"A":   PN = "1"  !CDS_PN = "1";
"B":   PN = "2"  !CDS_PN = "2";
BODY = "Q_RES","I16": LOCATION = "R978" #&CDS_LOCATION = "R978" &SEC = "1" #&CDS_SEC = "1";
"A":   PN = "1"  !CDS_PN = "1";
"B":   PN = "2"  !CDS_PN = "2";
BODY = "Q_CAP","I22": LOCATION = "C569" #&CDS_LOCATION = "C569" &SEC = "1" #&CDS_SEC = "1";
"A":   PN = "1"  !CDS_PN = "1";
"B":   PN = "2"  !CDS_PN = "2";
BODY = "Q_CAP","I25": LOCATION = "C567" #&CDS_LOCATION = "C567" &SEC = "1" #&CDS_SEC = "1";
"A":   PN = "1"  !CDS_PN = "1";
"B":   PN = "2"  !CDS_PN = "2";
BODY = "PCA9517AD","I28": LOCATION = "U30" #&CDS_LOCATION = "U30" &SEC = "1" #&CDS_SEC = "1";
"ENABLE":   PN = "5"  !CDS_PN = "5";
"GND":   PN = "4"  !CDS_PN = "4";
"SCLA":   PN = "2"  !CDS_PN = "2";
"SCLB":   PN = "7"  !CDS_PN = "7";
"SDAA":   PN = "3"  !CDS_PN = "3";
"SDAB":   PN = "6"  !CDS_PN = "6";
"VCCA":   PN = "1"  !CDS_PN = "1";
"VCCB":   PN = "8"  !CDS_PN = "8";
BODY = "Q_CAP","I33": LOCATION = "C570" #&CDS_LOCATION = "C570" &SEC = "1" #&CDS_SEC = "1";
"A":   PN = "1"  !CDS_PN = "1";
"B":   PN = "2"  !CDS_PN = "2";
BODY = "Q_CAP","I35": LOCATION = "C568" #&CDS_LOCATION = "C568" &SEC = "1" #&CDS_SEC = "1";
"A":   PN = "1"  !CDS_PN = "1";
"B":   PN = "2"  !CDS_PN = "2";
BODY = "PCA9517AD","I37": LOCATION = "U31" #&CDS_LOCATION = "U31" &SEC = "1" #&CDS_SEC = "1";
"ENABLE":   PN = "5"  !CDS_PN = "5";
"GND":   PN = "4"  !CDS_PN = "4";
"SCLA":   PN = "2"  !CDS_PN = "2";
"SCLB":   PN = "7"  !CDS_PN = "7";
"SDAA":   PN = "3"  !CDS_PN = "3";
"SDAB":   PN = "6"  !CDS_PN = "6";
"VCCA":   PN = "1"  !CDS_PN = "1";
"VCCB":   PN = "8"  !CDS_PN = "8";
BODY = "Q_RES","I42": LOCATION = "R971" #&CDS_LOCATION = "R971" &SEC = "1" #&CDS_SEC = "1";
"A":   PN = "1"  !CDS_PN = "1";
"B":   PN = "2"  !CDS_PN = "2";
BODY = "Q_RES","I43": LOCATION = "R969" #&CDS_LOCATION = "R969" &SEC = "1" #&CDS_SEC = "1";
"A":   PN = "1"  !CDS_PN = "1";
"B":   PN = "2"  !CDS_PN = "2";
BODY = "Q_RES","I44": LOCATION = "R993" #&CDS_LOCATION = "R993" &SEC = "1" #&CDS_SEC = "1";
"A":   PN = "1"  !CDS_PN = "1";
"B":   PN = "2"  !CDS_PN = "2";
BODY = "Q_RES","I49": LOCATION = "R972" #&CDS_LOCATION = "R972" &SEC = "1" #&CDS_SEC = "1";
"A":   PN = "1"  !CDS_PN = "1";
"B":   PN = "2"  !CDS_PN = "2";
BODY = "Q_RES","I50": LOCATION = "R970" #&CDS_LOCATION = "R970" &SEC = "1" #&CDS_SEC = "1";
"A":   PN = "1"  !CDS_PN = "1";
"B":   PN = "2"  !CDS_PN = "2";
BODY = "Q_RES","I51": LOCATION = "R995" #&CDS_LOCATION = "R995" &SEC = "1" #&CDS_SEC = "1";
"A":   PN = "1"  !CDS_PN = "1";
"B":   PN = "2"  !CDS_PN = "2";
BODY = "Q_RES","I62": LOCATION = "R2208" #&CDS_LOCATION = "R2208" &SEC = "1" #&CDS_SEC = "1";
"A":   PN = "1"  !CDS_PN = "1";
"B":   PN = "2"  !CDS_PN = "2";
BODY = "Q_RES","I63": LOCATION = "R2209" #&CDS_LOCATION = "R2209" &SEC = "1" #&CDS_SEC = "1";
"A":   PN = "1"  !CDS_PN = "1";
"B":   PN = "2"  !CDS_PN = "2";
BODY = "Q_RES","I64": LOCATION = "R2210" #&CDS_LOCATION = "R2210" &SEC = "1" #&CDS_SEC = "1";
"A":   PN = "1"  !CDS_PN = "1";
"B":   PN = "2"  !CDS_PN = "2";
BODY = "Q_RES","I65": LOCATION = "R2211" #&CDS_LOCATION = "R2211" &SEC = "1" #&CDS_SEC = "1";
"A":   PN = "1"  !CDS_PN = "1";
"B":   PN = "2"  !CDS_PN = "2";
BODY = "Q_CAP","I68": LOCATION = "C1613" #&CDS_LOCATION = "C1613" &SEC = "1" #&CDS_SEC = "1";
"A":   PN = "1"  !CDS_PN = "1";
"B":   PN = "2"  !CDS_PN = "2";
BODY = "Q_RES","I83": LOCATION = "R2310" #&CDS_LOCATION = "R2310" &SEC = "1" #&CDS_SEC = "1";
"A":   PN = "1"  !CDS_PN = "1";
"B":   PN = "2"  !CDS_PN = "2";
BODY = "Q_RES","I84": LOCATION = "R2308" #&CDS_LOCATION = "R2308" &SEC = "1" #&CDS_SEC = "1";
"A":   PN = "1"  !CDS_PN = "1";
"B":   PN = "2"  !CDS_PN = "2";
BODY = "Q_RES","I85": LOCATION = "R2309" #&CDS_LOCATION = "R2309" &SEC = "1" #&CDS_SEC = "1";
"A":   PN = "1"  !CDS_PN = "1";
"B":   PN = "2"  !CDS_PN = "2";
BODY = "Q_RES","I86": LOCATION = "R2311" #&CDS_LOCATION = "R2311" &SEC = "1" #&CDS_SEC = "1";
"A":   PN = "1"  !CDS_PN = "1";
"B":   PN = "2"  !CDS_PN = "2";
BODY = "Q_RES","I97": LOCATION = "R2313" #&CDS_LOCATION = "R2313" &SEC = "1" #&CDS_SEC = "1";
"A":   PN = "1"  !CDS_PN = "1";
"B":   PN = "2"  !CDS_PN = "2";
BODY = "Q_RES","I101": LOCATION = "R2312" #&CDS_LOCATION = "R2312" &SEC = "1" #&CDS_SEC = "1";
"A":   PN = "1"  !CDS_PN = "1";
"B":   PN = "2"  !CDS_PN = "2";
BODY = "Q_RES","I103": LOCATION = "R2315" #&CDS_LOCATION = "R2315" &SEC = "1" #&CDS_SEC = "1";
"A":   PN = "1"  !CDS_PN = "1";
"B":   PN = "2"  !CDS_PN = "2";
BODY = "PCA9545APW","I106": #LOCATION = "U143" !CDS_LOCATION = "U143" #SEC = "1" !CDS_SEC = "1";
"A0":   PN = "1"  !CDS_PN = "1";
"A1":   PN = "2"  !CDS_PN = "2";
"INT#":   PN = "17"  !CDS_PN = "17";
"INT0#":   PN = "4"  !CDS_PN = "4";
"INT1#":   PN = "7"  !CDS_PN = "7";
"INT2#":   PN = "11"  !CDS_PN = "11";
"INT3#":   PN = "14"  !CDS_PN = "14";
"RESET#":   PN = "3"  !CDS_PN = "3";
"SC0":   PN = "6"  !CDS_PN = "6";
"SC1":   PN = "9"  !CDS_PN = "9";
"SC2":   PN = "13"  !CDS_PN = "13";
"SC3":   PN = "16"  !CDS_PN = "16";
"SCL":   PN = "18"  !CDS_PN = "18";
"SD0":   PN = "5"  !CDS_PN = "5";
"SD1":   PN = "8"  !CDS_PN = "8";
"SD2":   PN = "12"  !CDS_PN = "12";
"SD3":   PN = "15"  !CDS_PN = "15";
"SDA":   PN = "19"  !CDS_PN = "19";
"VDD":   PN = "20"  !CDS_PN = "20";
"VSS":   PN = "10"  !CDS_PN = "10";
BODY = "Q_RES","I109": LOCATION = "R3127" #&CDS_LOCATION = "R3127" &SEC = "1" #&CDS_SEC = "1";
"A":   PN = "1"  !CDS_PN = "1";
"B":   PN = "2"  !CDS_PN = "2";
BODY = "Q_RES","I110": LOCATION = "R3130" #&CDS_LOCATION = "R3130" &SEC = "1" #&CDS_SEC = "1";
"A":   PN = "1"  !CDS_PN = "1";
"B":   PN = "2"  !CDS_PN = "2";
BODY = "Q_RES","I111": LOCATION = "R3131" #&CDS_LOCATION = "R3131" &SEC = "1" #&CDS_SEC = "1";
"A":   PN = "1"  !CDS_PN = "1";
"B":   PN = "2"  !CDS_PN = "2";
BODY = "Q_RES","I114": LOCATION = "R3124" #&CDS_LOCATION = "R3124" &SEC = "1" #&CDS_SEC = "1";
"A":   PN = "1"  !CDS_PN = "1";
"B":   PN = "2"  !CDS_PN = "2";
BODY = "Q_RES","I115": LOCATION = "R3123" #&CDS_LOCATION = "R3123" &SEC = "1" #&CDS_SEC = "1";
"A":   PN = "1"  !CDS_PN = "1";
"B":   PN = "2"  !CDS_PN = "2";
BODY = "Q_RES","I116": LOCATION = "R3125" #&CDS_LOCATION = "R3125" &SEC = "1" #&CDS_SEC = "1";
"A":   PN = "1"  !CDS_PN = "1";
"B":   PN = "2"  !CDS_PN = "2";
BODY = "Q_RES","I117": LOCATION = "R3126" #&CDS_LOCATION = "R3126" &SEC = "1" #&CDS_SEC = "1";
"A":   PN = "1"  !CDS_PN = "1";
"B":   PN = "2"  !CDS_PN = "2";
BODY = "Q_RES","I130": LOCATION = "R3225" #&CDS_LOCATION = "R3225" &SEC = "1" #&CDS_SEC = "1";
"A":   PN = "1"  !CDS_PN = "1";
"B":   PN = "2"  !CDS_PN = "2";
BODY = "Q_RES","I131": LOCATION = "R3224" #&CDS_LOCATION = "R3224" &SEC = "1" #&CDS_SEC = "1";
"A":   PN = "1"  !CDS_PN = "1";
"B":   PN = "2"  !CDS_PN = "2";
BODY = "Q_RES","I132": LOCATION = "R3222" #&CDS_LOCATION = "R3222" &SEC = "1" #&CDS_SEC = "1";
"A":   PN = "1"  !CDS_PN = "1";
"B":   PN = "2"  !CDS_PN = "2";
BODY = "Q_RES","I133": LOCATION = "R3223" #&CDS_LOCATION = "R3223" &SEC = "1" #&CDS_SEC = "1";
"A":   PN = "1"  !CDS_PN = "1";
"B":   PN = "2"  !CDS_PN = "2";
BODY = "Q_RES","I142": #LOCATION = "R994" !CDS_LOCATION = "R994" &SEC = "1" #&CDS_SEC = "1";
"A":   PN = "1"  !CDS_PN = "1";
"B":   PN = "2"  !CDS_PN = "2";
BODY = "Q_RES","I143": #LOCATION = "R996" !CDS_LOCATION = "R996" &SEC = "1" #&CDS_SEC = "1";
"A":   PN = "1"  !CDS_PN = "1";
"B":   PN = "2"  !CDS_PN = "2";
DRAWING = "@s9s_mb_2u_lib.s9s_mb_2u(sch_1):page226";
BODY = "Q_RES","I1": LOCATION = "R1383" #&CDS_LOCATION = "R1383" &SEC = "1" #&CDS_SEC = "1";
"A":   PN = "1"  !CDS_PN = "1";
"B":   PN = "2"  !CDS_PN = "2";
BODY = "Q_RES","I7": LOCATION = "R1381" #&CDS_LOCATION = "R1381" &SEC = "1" #&CDS_SEC = "1";
"A":   PN = "1"  !CDS_PN = "1";
"B":   PN = "2"  !CDS_PN = "2";
BODY = "Q_RES","I10": LOCATION = "R1347" #&CDS_LOCATION = "R1347" &SEC = "1" #&CDS_SEC = "1";
"A":   PN = "1"  !CDS_PN = "1";
"B":   PN = "2"  !CDS_PN = "2";
BODY = "Q_RES","I11": LOCATION = "R3055" #&CDS_LOCATION = "R3055" &SEC = "1" #&CDS_SEC = "1";
"A":   PN = "1"  !CDS_PN = "1";
"B":   PN = "2"  !CDS_PN = "2";
BODY = "Q_RES","I12": LOCATION = "R3057" #&CDS_LOCATION = "R3057" &SEC = "1" #&CDS_SEC = "1";
"A":   PN = "1"  !CDS_PN = "1";
"B":   PN = "2"  !CDS_PN = "2";
BODY = "Q_RES","I13": LOCATION = "R1345" #&CDS_LOCATION = "R1345" &SEC = "1" #&CDS_SEC = "1";
"A":   PN = "1"  !CDS_PN = "1";
"B":   PN = "2"  !CDS_PN = "2";
BODY = "Q_RES","I14": LOCATION = "R1184" #&CDS_LOCATION = "R1184" &SEC = "1" #&CDS_SEC = "1";
"A":   PN = "1"  !CDS_PN = "1";
"B":   PN = "2"  !CDS_PN = "2";
BODY = "Q_CAP","I16": LOCATION = "C1291" #&CDS_LOCATION = "C1291" &SEC = "1" #&CDS_SEC = "1";
"A":   PN = "1"  !CDS_PN = "1";
"B":   PN = "2"  !CDS_PN = "2";
BODY = "GTL2014PW","I18": LOCATION = "U84" #&CDS_LOCATION = "U84" #SEC = "1" !CDS_SEC = "1";
"A0":   PN = "13"  !CDS_PN = "13";
"A1":   PN = "12"  !CDS_PN = "12";
"A2":   PN = "10"  !CDS_PN = "10";
"A3":   PN = "9"  !CDS_PN = "9";
"B0":   PN = "2"  !CDS_PN = "2";
"B1":   PN = "3"  !CDS_PN = "3";
"B2":   PN = "5"  !CDS_PN = "5";
"B3":   PN = "6"  !CDS_PN = "6";
"DIR":   PN = "1"  !CDS_PN = "1";
"GND_0":   PN = "7"  !CDS_PN = "7";
"GND_1":   PN = "8"  !CDS_PN = "8";
"GND_2":   PN = "11"  !CDS_PN = "11";
"VCC":   PN = "14"  !CDS_PN = "14";
"VREF":   PN = "4"  !CDS_PN = "4";
BODY = "Q_RES","I20": LOCATION = "R1382" #&CDS_LOCATION = "R1382" &SEC = "1" #&CDS_SEC = "1";
"A":   PN = "1"  !CDS_PN = "1";
"B":   PN = "2"  !CDS_PN = "2";
BODY = "Q_CAP","I27": LOCATION = "C1322" #&CDS_LOCATION = "C1322" &SEC = "1" #&CDS_SEC = "1";
"A":   PN = "1"  !CDS_PN = "1";
"B":   PN = "2"  !CDS_PN = "2";
BODY = "Q_RES","I31": LOCATION = "R1380" #&CDS_LOCATION = "R1380" &SEC = "1" #&CDS_SEC = "1";
"A":   PN = "1"  !CDS_PN = "1";
"B":   PN = "2"  !CDS_PN = "2";
BODY = "Q_RES","I34": LOCATION = "R1346" #&CDS_LOCATION = "R1346" &SEC = "1" #&CDS_SEC = "1";
"A":   PN = "1"  !CDS_PN = "1";
"B":   PN = "2"  !CDS_PN = "2";
BODY = "Q_RES","I36": LOCATION = "R3056" #&CDS_LOCATION = "R3056" &SEC = "1" #&CDS_SEC = "1";
"A":   PN = "1"  !CDS_PN = "1";
"B":   PN = "2"  !CDS_PN = "2";
BODY = "Q_RES","I37": LOCATION = "R483" #&CDS_LOCATION = "R483" &SEC = "1" #&CDS_SEC = "1";
"A":   PN = "1"  !CDS_PN = "1";
"B":   PN = "2"  !CDS_PN = "2";
BODY = "NX3L2267GM","I38": LOCATION = "U97" #&CDS_LOCATION = "U97" #SEC = "1" !CDS_SEC = "1";
"1S":   PN = "8"  !CDS_PN = "8";
"1Y0":   PN = "1"  !CDS_PN = "1";
"1Y1":   PN = "2"  !CDS_PN = "2";
"1Z":   PN = "9"  !CDS_PN = "9";
"2S":   PN = "7"  !CDS_PN = "7";
"2Y0":   PN = "3"  !CDS_PN = "3";
"2Y1":   PN = "4"  !CDS_PN = "4";
"2Z":   PN = "6"  !CDS_PN = "6";
"GND":   PN = "5"  !CDS_PN = "5";
"VCC":   PN = "10"  !CDS_PN = "10";
BODY = "Q_CAP","I43": LOCATION = "C1290" #&CDS_LOCATION = "C1290" &SEC = "1" #&CDS_SEC = "1";
"A":   PN = "1"  !CDS_PN = "1";
"B":   PN = "2"  !CDS_PN = "2";
BODY = "GTL2014PW","I45": LOCATION = "U83" #&CDS_LOCATION = "U83" #SEC = "1" !CDS_SEC = "1";
"A0":   PN = "13"  !CDS_PN = "13";
"A1":   PN = "12"  !CDS_PN = "12";
"A2":   PN = "10"  !CDS_PN = "10";
"A3":   PN = "9"  !CDS_PN = "9";
"B0":   PN = "2"  !CDS_PN = "2";
"B1":   PN = "3"  !CDS_PN = "3";
"B2":   PN = "5"  !CDS_PN = "5";
"B3":   PN = "6"  !CDS_PN = "6";
"DIR":   PN = "1"  !CDS_PN = "1";
"GND_0":   PN = "7"  !CDS_PN = "7";
"GND_1":   PN = "8"  !CDS_PN = "8";
"GND_2":   PN = "11"  !CDS_PN = "11";
"VCC":   PN = "14"  !CDS_PN = "14";
"VREF":   PN = "4"  !CDS_PN = "4";
BODY = "Q_RES","I47": LOCATION = "R1369" #&CDS_LOCATION = "R1369" &SEC = "1" #&CDS_SEC = "1";
"A":   PN = "1"  !CDS_PN = "1";
"B":   PN = "2"  !CDS_PN = "2";
BODY = "Q_RES","I48": LOCATION = "R1368" #&CDS_LOCATION = "R1368" &SEC = "1" #&CDS_SEC = "1";
"A":   PN = "1"  !CDS_PN = "1";
"B":   PN = "2"  !CDS_PN = "2";
BODY = "Q_CAP","I55": LOCATION = "C1321" #&CDS_LOCATION = "C1321" &SEC = "1" #&CDS_SEC = "1";
"A":   PN = "1"  !CDS_PN = "1";
"B":   PN = "2"  !CDS_PN = "2";
BODY = "Q_RES","I57": LOCATION = "R482" #&CDS_LOCATION = "R482" &SEC = "1" #&CDS_SEC = "1";
"A":   PN = "1"  !CDS_PN = "1";
"B":   PN = "2"  !CDS_PN = "2";
BODY = "Q_RES","I58": LOCATION = "R481" #&CDS_LOCATION = "R481" &SEC = "1" #&CDS_SEC = "1";
"A":   PN = "1"  !CDS_PN = "1";
"B":   PN = "2"  !CDS_PN = "2";
BODY = "Q_RES","I59": LOCATION = "R480" #&CDS_LOCATION = "R480" &SEC = "1" #&CDS_SEC = "1";
"A":   PN = "1"  !CDS_PN = "1";
"B":   PN = "2"  !CDS_PN = "2";
BODY = "Q_RES","I64": LOCATION = "R1366" #&CDS_LOCATION = "R1366" &SEC = "1" #&CDS_SEC = "1";
"A":   PN = "1"  !CDS_PN = "1";
"B":   PN = "2"  !CDS_PN = "2";
BODY = "Q_RES","I65": LOCATION = "R1367" #&CDS_LOCATION = "R1367" &SEC = "1" #&CDS_SEC = "1";
"A":   PN = "1"  !CDS_PN = "1";
"B":   PN = "2"  !CDS_PN = "2";
BODY = "NX3L2267GM","I68": LOCATION = "U96" #&CDS_LOCATION = "U96" #SEC = "1" !CDS_SEC = "1";
"1S":   PN = "8"  !CDS_PN = "8";
"1Y0":   PN = "1"  !CDS_PN = "1";
"1Y1":   PN = "2"  !CDS_PN = "2";
"1Z":   PN = "9"  !CDS_PN = "9";
"2S":   PN = "7"  !CDS_PN = "7";
"2Y0":   PN = "3"  !CDS_PN = "3";
"2Y1":   PN = "4"  !CDS_PN = "4";
"2Z":   PN = "6"  !CDS_PN = "6";
"GND":   PN = "5"  !CDS_PN = "5";
"VCC":   PN = "10"  !CDS_PN = "10";
BODY = "Q_RES","I77": LOCATION = "R1814" #&CDS_LOCATION = "R1814" &SEC = "1" #&CDS_SEC = "1";
"A":   PN = "1"  !CDS_PN = "1";
"B":   PN = "2"  !CDS_PN = "2";
BODY = "Q_RES","I79": LOCATION = "R1813" #&CDS_LOCATION = "R1813" &SEC = "1" #&CDS_SEC = "1";
"A":   PN = "1"  !CDS_PN = "1";
"B":   PN = "2"  !CDS_PN = "2";
BODY = "Q_RES","I80": LOCATION = "R1832" #&CDS_LOCATION = "R1832" &SEC = "1" #&CDS_SEC = "1";
"A":   PN = "1"  !CDS_PN = "1";
"B":   PN = "2"  !CDS_PN = "2";
BODY = "Q_RES","I82": LOCATION = "R1831" #&CDS_LOCATION = "R1831" &SEC = "1" #&CDS_SEC = "1";
"A":   PN = "1"  !CDS_PN = "1";
"B":   PN = "2"  !CDS_PN = "2";
BODY = "Q_RES","I87": LOCATION = "R2506" #&CDS_LOCATION = "R2506" &SEC = "1" #&CDS_SEC = "1";
"A":   PN = "1"  !CDS_PN = "1";
"B":   PN = "2"  !CDS_PN = "2";
BODY = "Q_RES","I88": LOCATION = "R2507" #&CDS_LOCATION = "R2507" &SEC = "1" #&CDS_SEC = "1";
"A":   PN = "1"  !CDS_PN = "1";
"B":   PN = "2"  !CDS_PN = "2";
BODY = "Q_RES","I89": LOCATION = "R2514" #&CDS_LOCATION = "R2514" &SEC = "1" #&CDS_SEC = "1";
"A":   PN = "1"  !CDS_PN = "1";
"B":   PN = "2"  !CDS_PN = "2";
BODY = "Q_RES","I90": LOCATION = "R2513" #&CDS_LOCATION = "R2513" &SEC = "1" #&CDS_SEC = "1";
"A":   PN = "1"  !CDS_PN = "1";
"B":   PN = "2"  !CDS_PN = "2";
BODY = "Q_RES","I91": LOCATION = "R2512" #&CDS_LOCATION = "R2512" &SEC = "1" #&CDS_SEC = "1";
"A":   PN = "1"  !CDS_PN = "1";
"B":   PN = "2"  !CDS_PN = "2";
BODY = "Q_CAP","I93": LOCATION = "C1664" #&CDS_LOCATION = "C1664" &SEC = "1" #&CDS_SEC = "1";
"A":   PN = "1"  !CDS_PN = "1";
"B":   PN = "2"  !CDS_PN = "2";
DRAWING = "@s9s_mb_2u_lib.s9s_mb_2u(sch_1):page227";
BODY = "Q_RES","I99": LOCATION = "R2421" #&CDS_LOCATION = "R2421" &SEC = "1" #&CDS_SEC = "1";
"A":   PN = "1"  !CDS_PN = "1";
"B":   PN = "2"  !CDS_PN = "2";
BODY = "Q_RES","I18": LOCATION = "R506" #&CDS_LOCATION = "R506" &SEC = "1" #&CDS_SEC = "1";
"A":   PN = "1"  !CDS_PN = "1";
"B":   PN = "2"  !CDS_PN = "2";
BODY = "Q_RES","I19": LOCATION = "R3777" #&CDS_LOCATION = "R3777" &SEC = "1" #&CDS_SEC = "1";
"A":   PN = "1"  !CDS_PN = "1";
"B":   PN = "2"  !CDS_PN = "2";
BODY = "Q_RES","I20": LOCATION = "R1798" #&CDS_LOCATION = "R1798" &SEC = "1" #&CDS_SEC = "1";
"A":   PN = "1"  !CDS_PN = "1";
"B":   PN = "2"  !CDS_PN = "2";
BODY = "Q_RES","I21": LOCATION = "R3776" #&CDS_LOCATION = "R3776" &SEC = "1" #&CDS_SEC = "1";
"A":   PN = "1"  !CDS_PN = "1";
"B":   PN = "2"  !CDS_PN = "2";
BODY = "Q_RES","I22": LOCATION = "R2417" #&CDS_LOCATION = "R2417" &SEC = "1" #&CDS_SEC = "1";
"A":   PN = "1"  !CDS_PN = "1";
"B":   PN = "2"  !CDS_PN = "2";
BODY = "Q_RES","I23": LOCATION = "R2418" #&CDS_LOCATION = "R2418" &SEC = "1" #&CDS_SEC = "1";
"A":   PN = "1"  !CDS_PN = "1";
"B":   PN = "2"  !CDS_PN = "2";
BODY = "Q_RES","I24": LOCATION = "R2416" #&CDS_LOCATION = "R2416" &SEC = "1" #&CDS_SEC = "1";
"A":   PN = "1"  !CDS_PN = "1";
"B":   PN = "2"  !CDS_PN = "2";
BODY = "Q_CAP","I82": #LOCATION = "C1302" !CDS_LOCATION = "C1302" &SEC = "1" #&CDS_SEC = "1";
"A":   PN = "1"  !CDS_PN = "1";
"B":   PN = "2"  !CDS_PN = "2";
BODY = "Q_RES","I84": LOCATION = "R142" #&CDS_LOCATION = "R142" &SEC = "1" #&CDS_SEC = "1";
"A":   PN = "1"  !CDS_PN = "1";
"B":   PN = "2"  !CDS_PN = "2";
BODY = "Q_RES","I85": LOCATION = "R2414" #&CDS_LOCATION = "R2414" &SEC = "1" #&CDS_SEC = "1";
"A":   PN = "1"  !CDS_PN = "1";
"B":   PN = "2"  !CDS_PN = "2";
BODY = "Q_RES","I86": LOCATION = "R2413" #&CDS_LOCATION = "R2413" &SEC = "1" #&CDS_SEC = "1";
"A":   PN = "1"  !CDS_PN = "1";
"B":   PN = "2"  !CDS_PN = "2";
BODY = "Q_RES","I87": LOCATION = "R4508" #&CDS_LOCATION = "R4508" &SEC = "1" #&CDS_SEC = "1";
"A":   PN = "1"  !CDS_PN = "1";
"B":   PN = "2"  !CDS_PN = "2";
BODY = "Q_RES","I88": LOCATION = "R4509" #&CDS_LOCATION = "R4509" &SEC = "1" #&CDS_SEC = "1";
"A":   PN = "1"  !CDS_PN = "1";
"B":   PN = "2"  !CDS_PN = "2";
BODY = "Q_RES","I89": LOCATION = "R4507" #&CDS_LOCATION = "R4507" &SEC = "1" #&CDS_SEC = "1";
"A":   PN = "1"  !CDS_PN = "1";
"B":   PN = "2"  !CDS_PN = "2";
BODY = "Q_RES","I90": LOCATION = "R4506" #&CDS_LOCATION = "R4506" &SEC = "1" #&CDS_SEC = "1";
"A":   PN = "1"  !CDS_PN = "1";
"B":   PN = "2"  !CDS_PN = "2";
BODY = "Q_RES","I91": LOCATION = "R4535" #&CDS_LOCATION = "R4535" &SEC = "1" #&CDS_SEC = "1";
"A":   PN = "1"  !CDS_PN = "1";
"B":   PN = "2"  !CDS_PN = "2";
BODY = "Q_RES","I92": LOCATION = "R4536" #&CDS_LOCATION = "R4536" &SEC = "1" #&CDS_SEC = "1";
"A":   PN = "1"  !CDS_PN = "1";
"B":   PN = "2"  !CDS_PN = "2";
BODY = "Q_RES","I93": LOCATION = "R2425" #&CDS_LOCATION = "R2425" &SEC = "1" #&CDS_SEC = "1";
"A":   PN = "1"  !CDS_PN = "1";
"B":   PN = "2"  !CDS_PN = "2";
BODY = "Q_RES","I94": LOCATION = "R3858" #&CDS_LOCATION = "R3858" &SEC = "1" #&CDS_SEC = "1";
"A":   PN = "1"  !CDS_PN = "1";
"B":   PN = "2"  !CDS_PN = "2";
BODY = "Q_RES","I95": LOCATION = "R2422" #&CDS_LOCATION = "R2422" &SEC = "1" #&CDS_SEC = "1";
"A":   PN = "1"  !CDS_PN = "1";
"B":   PN = "2"  !CDS_PN = "2";
BODY = "Q_RES","I96": LOCATION = "R2424" #&CDS_LOCATION = "R2424" &SEC = "1" #&CDS_SEC = "1";
"A":   PN = "1"  !CDS_PN = "1";
"B":   PN = "2"  !CDS_PN = "2";
BODY = "Q_RES","I97": LOCATION = "R2423" #&CDS_LOCATION = "R2423" &SEC = "1" #&CDS_SEC = "1";
"A":   PN = "1"  !CDS_PN = "1";
"B":   PN = "2"  !CDS_PN = "2";
BODY = "Q_RES","I98": LOCATION = "R2420" #&CDS_LOCATION = "R2420" &SEC = "1" #&CDS_SEC = "1";
"A":   PN = "1"  !CDS_PN = "1";
"B":   PN = "2"  !CDS_PN = "2";
BODY = "Q_RES","I164": LOCATION = "R2257" #&CDS_LOCATION = "R2257" &SEC = "1" #&CDS_SEC = "1";
"A":   PN = "1"  !CDS_PN = "1";
"B":   PN = "2"  !CDS_PN = "2";
BODY = "Q_RES","I2": LOCATION = "R4809" #&CDS_LOCATION = "R4809" &SEC = "1" #&CDS_SEC = "1";
"A":   PN = "1"  !CDS_PN = "1";
"B":   PN = "2"  !CDS_PN = "2";
BODY = "Q_RES","I25": LOCATION = "R2415" #&CDS_LOCATION = "R2415" &SEC = "1" #&CDS_SEC = "1";
"A":   PN = "1"  !CDS_PN = "1";
"B":   PN = "2"  !CDS_PN = "2";
BODY = "Q_RES","I26": LOCATION = "R1815" #&CDS_LOCATION = "R1815" &SEC = "1" #&CDS_SEC = "1";
"A":   PN = "1"  !CDS_PN = "1";
"B":   PN = "2"  !CDS_PN = "2";
BODY = "Q_RES","I27": LOCATION = "R1816" #&CDS_LOCATION = "R1816" &SEC = "1" #&CDS_SEC = "1";
"A":   PN = "1"  !CDS_PN = "1";
"B":   PN = "2"  !CDS_PN = "2";
BODY = "Q_RES","I28": #LOCATION = "R4087" !CDS_LOCATION = "R4087" &SEC = "1" #&CDS_SEC = "1";
"A":   PN = "1"  !CDS_PN = "1";
"B":   PN = "2"  !CDS_PN = "2";
BODY = "Q_RES","I48": LOCATION = "R3302" #&CDS_LOCATION = "R3302" &SEC = "1" #&CDS_SEC = "1";
"A":   PN = "1"  !CDS_PN = "1";
"B":   PN = "2"  !CDS_PN = "2";
BODY = "Q_RES","I49": LOCATION = "R3254" #&CDS_LOCATION = "R3254" &SEC = "1" #&CDS_SEC = "1";
"A":   PN = "1"  !CDS_PN = "1";
"B":   PN = "2"  !CDS_PN = "2";
BODY = "Q_RES","I57": LOCATION = "R4720" #&CDS_LOCATION = "R4720" &SEC = "1" #&CDS_SEC = "1";
"A":   PN = "1"  !CDS_PN = "1";
"B":   PN = "2"  !CDS_PN = "2";
BODY = "Q_RES","I58": LOCATION = "R2994" #&CDS_LOCATION = "R2994" &SEC = "1" #&CDS_SEC = "1";
"A":   PN = "1"  !CDS_PN = "1";
"B":   PN = "2"  !CDS_PN = "2";
BODY = "Q_RES","I100": LOCATION = "R2419" #&CDS_LOCATION = "R2419" &SEC = "1" #&CDS_SEC = "1";
"A":   PN = "1"  !CDS_PN = "1";
"B":   PN = "2"  !CDS_PN = "2";
BODY = "Q_RES","I101": LOCATION = "R3238" #&CDS_LOCATION = "R3238" &SEC = "1" #&CDS_SEC = "1";
"A":   PN = "1"  !CDS_PN = "1";
"B":   PN = "2"  !CDS_PN = "2";
BODY = "Q_RES","I102": LOCATION = "R3239" #&CDS_LOCATION = "R3239" &SEC = "1" #&CDS_SEC = "1";
"A":   PN = "1"  !CDS_PN = "1";
"B":   PN = "2"  !CDS_PN = "2";
BODY = "Q_RES","I159": LOCATION = "R3778" #&CDS_LOCATION = "R3778" &SEC = "1" #&CDS_SEC = "1";
"A":   PN = "1"  !CDS_PN = "1";
"B":   PN = "2"  !CDS_PN = "2";
BODY = "Q_RES","I167": LOCATION = "R2256" #&CDS_LOCATION = "R2256" &SEC = "1" #&CDS_SEC = "1";
"A":   PN = "1"  !CDS_PN = "1";
"B":   PN = "2"  !CDS_PN = "2";
BODY = "Q_RES","I172": LOCATION = "R1801" #&CDS_LOCATION = "R1801" &SEC = "1" #&CDS_SEC = "1";
"A":   PN = "1"  !CDS_PN = "1";
"B":   PN = "2"  !CDS_PN = "2";
BODY = "SCONN168_ME1016810202011","I173": #LOCATION = "J41" !CDS_LOCATION = "J41" #SEC = "1" !CDS_SEC = "1";
"+3.3V_EDGE":   PN = "B11"  !CDS_PN = "B11";
"+12V_EDGE_B1":   PN = "B1"  !CDS_PN = "B1";
"+12V_EDGE_B2":   PN = "B2"  !CDS_PN = "B2";
"+12V_EDGE_B3":   PN = "B3"  !CDS_PN = "B3";
"+12V_EDGE_B4":   PN = "B4"  !CDS_PN = "B4";
"+12V_EDGE_B5":   PN = "B5"  !CDS_PN = "B5";
"+12V_EDGE_B6":   PN = "B6"  !CDS_PN = "B6";
"AUX_PWR_EN":   PN = "B12"  !CDS_PN = "B12";
"BIF0#":   PN = "B7"  !CDS_PN = "B7";
"BIF1#":   PN = "B8"  !CDS_PN = "B8";
"BIF2#":   PN = "B9"  !CDS_PN = "B9";
"CLK":   PN = "OB6"  !CDS_PN = "OB6";
"DATA_IN":   PN = "OB4"  !CDS_PN = "OB4";
"DATA_OUT":   PN = "OB5"  !CDS_PN = "OB5";
"G1":   PN = "G1"  !CDS_PN = "G1";
"G2":   PN = "G2"  !CDS_PN = "G2";
"G3":   PN = "G3"  !CDS_PN = "G3";
"G4":   PN = "G4"  !CDS_PN = "G4";
"G5":   PN = "G5"  !CDS_PN = "G5";
"GND_A1":   PN = "A1"  !CDS_PN = "A1";
"GND_A2":   PN = "A2"  !CDS_PN = "A2";
"GND_A3":   PN = "A3"  !CDS_PN = "A3";
"GND_A4":   PN = "A4"  !CDS_PN = "A4";
"GND_A5":   PN = "A5"  !CDS_PN = "A5";
"GND_A6":   PN = "A6"  !CDS_PN = "A6";
"GND_A13":   PN = "A13"  !CDS_PN = "A13";
"GND_A16":   PN = "A16"  !CDS_PN = "A16";
"GND_A19":   PN = "A19"  !CDS_PN = "A19";
"GND_A22":   PN = "A22"  !CDS_PN = "A22";
"GND_A25":   PN = "A25"  !CDS_PN = "A25";
"GND_A28":   PN = "A28"  !CDS_PN = "A28";
"GND_A29":   PN = "A29"  !CDS_PN = "A29";
"GND_A32":   PN = "A32"  !CDS_PN = "A32";
"GND_A35":   PN = "A35"  !CDS_PN = "A35";
"GND_A38":   PN = "A38"  !CDS_PN = "A38";
"GND_A41":   PN = "A41"  !CDS_PN = "A41";
"GND_A43":   PN = "A43"  !CDS_PN = "A43";
"GND_A46":   PN = "A46"  !CDS_PN = "A46";
"GND_A49":   PN = "A49"  !CDS_PN = "A49";
"GND_A52":   PN = "A52"  !CDS_PN = "A52";
"GND_A55":   PN = "A55"  !CDS_PN = "A55";
"GND_A58":   PN = "A58"  !CDS_PN = "A58";
"GND_A61":   PN = "A61"  !CDS_PN = "A61";
"GND_A64":   PN = "A64"  !CDS_PN = "A64";
"GND_A67":   PN = "A67"  !CDS_PN = "A67";
"GND_B13":   PN = "B13"  !CDS_PN = "B13";
"GND_B16":   PN = "B16"  !CDS_PN = "B16";
"GND_B19":   PN = "B19"  !CDS_PN = "B19";
"GND_B22":   PN = "B22"  !CDS_PN = "B22";
"GND_B25":   PN = "B25"  !CDS_PN = "B25";
"GND_B28":   PN = "B28"  !CDS_PN = "B28";
"GND_B29":   PN = "B29"  !CDS_PN = "B29";
"GND_B32":   PN = "B32"  !CDS_PN = "B32";
"GND_B35":   PN = "B35"  !CDS_PN = "B35";
"GND_B38":   PN = "B38"  !CDS_PN = "B38";
"GND_B41":   PN = "B41"  !CDS_PN = "B41";
"GND_B43":   PN = "B43"  !CDS_PN = "B43";
"GND_B46":   PN = "B46"  !CDS_PN = "B46";
"GND_B49":   PN = "B49"  !CDS_PN = "B49";
"GND_B52":   PN = "B52"  !CDS_PN = "B52";
"GND_B55":   PN = "B55"  !CDS_PN = "B55";
"GND_B58":   PN = "B58"  !CDS_PN = "B58";
"GND_B61":   PN = "B61"  !CDS_PN = "B61";
"GND_B64":   PN = "B64"  !CDS_PN = "B64";
"GND_B67":   PN = "B67"  !CDS_PN = "B67";
"GND_OA10":   PN = "OA10"  !CDS_PN = "OA10";
"GND_OA13":   PN = "OA13"  !CDS_PN = "OA13";
"GND_OB10":   PN = "OB10"  !CDS_PN = "OB10";
"GND_OB13":   PN = "OB13"  !CDS_PN = "OB13";
"LD#":   PN = "OB3"  !CDS_PN = "OB3";
"MAIN_PWR_EN":   PN = "OB2"  !CDS_PN = "OB2";
"NIC_PWR_GOOD":   PN = "OB1"  !CDS_PN = "OB1";
"PERN0":   PN = "A17"  !CDS_PN = "A17";
"PERN1":   PN = "A20"  !CDS_PN = "A20";
"PERN2":   PN = "A23"  !CDS_PN = "A23";
"PERN3":   PN = "A26"  !CDS_PN = "A26";
"PERN4":   PN = "A30"  !CDS_PN = "A30";
"PERN5":   PN = "A33"  !CDS_PN = "A33";
"PERN6":   PN = "A36"  !CDS_PN = "A36";
"PERN7":   PN = "A39"  !CDS_PN = "A39";
"PERN8":   PN = "A44"  !CDS_PN = "A44";
"PERN9":   PN = "A47"  !CDS_PN = "A47";
"PERN10":   PN = "A50"  !CDS_PN = "A50";
"PERN11":   PN = "A53"  !CDS_PN = "A53";
"PERN12":   PN = "A56"  !CDS_PN = "A56";
"PERN13":   PN = "A59"  !CDS_PN = "A59";
"PERN14":   PN = "A62"  !CDS_PN = "A62";
"PERN15":   PN = "A65"  !CDS_PN = "A65";
"PERP0":   PN = "A18"  !CDS_PN = "A18";
"PERP1":   PN = "A21"  !CDS_PN = "A21";
"PERP2":   PN = "A24"  !CDS_PN = "A24";
"PERP3":   PN = "A27"  !CDS_PN = "A27";
"PERP4":   PN = "A31"  !CDS_PN = "A31";
"PERP5":   PN = "A34"  !CDS_PN = "A34";
"PERP6":   PN = "A37"  !CDS_PN = "A37";
"PERP7":   PN = "A40"  !CDS_PN = "A40";
"PERP8":   PN = "A45"  !CDS_PN = "A45";
"PERP9":   PN = "A48"  !CDS_PN = "A48";
"PERP10":   PN = "A51"  !CDS_PN = "A51";
"PERP11":   PN = "A54"  !CDS_PN = "A54";
"PERP12":   PN = "A57"  !CDS_PN = "A57";
"PERP13":   PN = "A60"  !CDS_PN = "A60";
"PERP14":   PN = "A63"  !CDS_PN = "A63";
"PERP15":   PN = "A66"  !CDS_PN = "A66";
"PERST0#":   PN = "B10"  !CDS_PN = "B10";
"PERST1#":   PN = "A11"  !CDS_PN = "A11";
"PERST2#":   PN = "OA1"  !CDS_PN = "OA1";
"PERST3#":   PN = "OA2"  !CDS_PN = "OA2";
"PETN0":   PN = "B17"  !CDS_PN = "B17";
"PETN1":   PN = "B20"  !CDS_PN = "B20";
"PETN2":   PN = "B23"  !CDS_PN = "B23";
"PETN3":   PN = "B26"  !CDS_PN = "B26";
"PETN4":   PN = "B30"  !CDS_PN = "B30";
"PETN5":   PN = "B33"  !CDS_PN = "B33";
"PETN6":   PN = "B36"  !CDS_PN = "B36";
"PETN7":   PN = "B39"  !CDS_PN = "B39";
"PETN8":   PN = "B44"  !CDS_PN = "B44";
"PETN9":   PN = "B47"  !CDS_PN = "B47";
"PETN10":   PN = "B50"  !CDS_PN = "B50";
"PETN11":   PN = "B53"  !CDS_PN = "B53";
"PETN12":   PN = "B56"  !CDS_PN = "B56";
"PETN13":   PN = "B59"  !CDS_PN = "B59";
"PETN14":   PN = "B62"  !CDS_PN = "B62";
"PETN15":   PN = "B65"  !CDS_PN = "B65";
"PETP0":   PN = "B18"  !CDS_PN = "B18";
"PETP1":   PN = "B21"  !CDS_PN = "B21";
"PETP2":   PN = "B24"  !CDS_PN = "B24";
"PETP3":   PN = "B27"  !CDS_PN = "B27";
"PETP4":   PN = "B31"  !CDS_PN = "B31";
"PETP5":   PN = "B34"  !CDS_PN = "B34";
"PETP6":   PN = "B37"  !CDS_PN = "B37";
"PETP7":   PN = "B40"  !CDS_PN = "B40";
"PETP8":   PN = "B45"  !CDS_PN = "B45";
"PETP9":   PN = "B48"  !CDS_PN = "B48";
"PETP10":   PN = "B51"  !CDS_PN = "B51";
"PETP11":   PN = "B54"  !CDS_PN = "B54";
"PETP12":   PN = "B57"  !CDS_PN = "B57";
"PETP13":   PN = "B60"  !CDS_PN = "B60";
"PETP14":   PN = "B63"  !CDS_PN = "B63";
"PETP15":   PN = "B66"  !CDS_PN = "B66";
"PRSNTA#":   PN = "A10"  !CDS_PN = "A10";
"PRSNTB0#":   PN = "B42"  !CDS_PN = "B42";
"PRSNTB1#":   PN = "A42"  !CDS_PN = "A42";
"PRSNTB2#":   PN = "A12"  !CDS_PN = "A12";
"PRSNTB3#":   PN = "B70"  !CDS_PN = "B70";
"PWRBRK0#":   PN = "A70"  !CDS_PN = "A70";
"RBT_ARB_IN":   PN = "OA4"  !CDS_PN = "OA4";
"RBT_ARB_OUT":   PN = "OA5"  !CDS_PN = "OA5";
"RBT_CLK_IN":   PN = "OA14"  !CDS_PN = "OA14";
"RBT_CRS_DV":   PN = "OB14"  !CDS_PN = "OB14";
"RBT_RXD0":   PN = "OB9"  !CDS_PN = "OB9";
"RBT_RXD1":   PN = "OB8"  !CDS_PN = "OB8";
"RBT_TX_EN":   PN = "OA7"  !CDS_PN = "OA7";
"RBT_TXD0":   PN = "OA9"  !CDS_PN = "OA9";
"RBT_TXD1":   PN = "OA8"  !CDS_PN = "OA8";
"REFCLKN0":   PN = "B14"  !CDS_PN = "B14";
"REFCLKN1":   PN = "A14"  !CDS_PN = "A14";
"REFCLKN2":   PN = "OB11"  !CDS_PN = "OB11";
"REFCLKN3":   PN = "OA11"  !CDS_PN = "OA11";
"REFCLKP0":   PN = "B15"  !CDS_PN = "B15";
"REFCLKP1":   PN = "A15"  !CDS_PN = "A15";
"REFCLKP2":   PN = "OB12"  !CDS_PN = "OB12";
"REFCLKP3":   PN = "OA12"  !CDS_PN = "OA12";
"RFU1_NC_B68":   PN = "B68"  !CDS_PN = "B68";
"RFU1_NC_B69":   PN = "B69"  !CDS_PN = "B69";
"SLOT_ID0":   PN = "OB7"  !CDS_PN = "OB7";
"SLOT_ID1":   PN = "OA6"  !CDS_PN = "OA6";
"SMCLK":   PN = "A7"  !CDS_PN = "A7";
"SMDAT":   PN = "A8"  !CDS_PN = "A8";
"SMRST#":   PN = "A9"  !CDS_PN = "A9";
"USB_DATN":   PN = "A68"  !CDS_PN = "A68";
"USB_DATP":   PN = "A69"  !CDS_PN = "A69";
"WAKE#":   PN = "OA3"  !CDS_PN = "OA3";
DRAWING = "@s9s_mb_2u_lib.s9s_mb_2u(sch_1):page228";
BODY = "Q_RES","I2": LOCATION = "R1319" #&CDS_LOCATION = "R1319" &SEC = "1" #&CDS_SEC = "1";
"A":   PN = "1"  !CDS_PN = "1";
"B":   PN = "2"  !CDS_PN = "2";
BODY = "Q_RES","I3": LOCATION = "R3062" #&CDS_LOCATION = "R3062" &SEC = "1" #&CDS_SEC = "1";
"A":   PN = "1"  !CDS_PN = "1";
"B":   PN = "2"  !CDS_PN = "2";
BODY = "Q_RES","I4": LOCATION = "R1384" #&CDS_LOCATION = "R1384" &SEC = "1" #&CDS_SEC = "1";
"A":   PN = "1"  !CDS_PN = "1";
"B":   PN = "2"  !CDS_PN = "2";
BODY = "Q_RES","I5": LOCATION = "R1385" #&CDS_LOCATION = "R1385" &SEC = "1" #&CDS_SEC = "1";
"A":   PN = "1"  !CDS_PN = "1";
"B":   PN = "2"  !CDS_PN = "2";
BODY = "Q_RES","I6": LOCATION = "R1386" #&CDS_LOCATION = "R1386" &SEC = "1" #&CDS_SEC = "1";
"A":   PN = "1"  !CDS_PN = "1";
"B":   PN = "2"  !CDS_PN = "2";
BODY = "Q_RES","I7": LOCATION = "R1387" #&CDS_LOCATION = "R1387" &SEC = "1" #&CDS_SEC = "1";
"A":   PN = "1"  !CDS_PN = "1";
"B":   PN = "2"  !CDS_PN = "2";
BODY = "Q_RES","I38": LOCATION = "R579" #&CDS_LOCATION = "R579" &SEC = "1" #&CDS_SEC = "1";
"A":   PN = "1"  !CDS_PN = "1";
"B":   PN = "2"  !CDS_PN = "2";
BODY = "Q_RES","I39": LOCATION = "R580" #&CDS_LOCATION = "R580" &SEC = "1" #&CDS_SEC = "1";
"A":   PN = "1"  !CDS_PN = "1";
"B":   PN = "2"  !CDS_PN = "2";
BODY = "Q_RES","I40": LOCATION = "R1525" #&CDS_LOCATION = "R1525" &SEC = "1" #&CDS_SEC = "1";
"A":   PN = "1"  !CDS_PN = "1";
"B":   PN = "2"  !CDS_PN = "2";
BODY = "Q_RES","I41": LOCATION = "R1526" #&CDS_LOCATION = "R1526" &SEC = "1" #&CDS_SEC = "1";
"A":   PN = "1"  !CDS_PN = "1";
"B":   PN = "2"  !CDS_PN = "2";
BODY = "Q_RES","I42": LOCATION = "R108" #&CDS_LOCATION = "R108" &SEC = "1" #&CDS_SEC = "1";
"A":   PN = "1"  !CDS_PN = "1";
"B":   PN = "2"  !CDS_PN = "2";
BODY = "Q_RES","I43": LOCATION = "R107" #&CDS_LOCATION = "R107" &SEC = "1" #&CDS_SEC = "1";
"A":   PN = "1"  !CDS_PN = "1";
"B":   PN = "2"  !CDS_PN = "2";
BODY = "Q_RES","I44": LOCATION = "R581" #&CDS_LOCATION = "R581" &SEC = "1" #&CDS_SEC = "1";
"A":   PN = "1"  !CDS_PN = "1";
"B":   PN = "2"  !CDS_PN = "2";
BODY = "Q_RES","I45": LOCATION = "R582" #&CDS_LOCATION = "R582" &SEC = "1" #&CDS_SEC = "1";
"A":   PN = "1"  !CDS_PN = "1";
"B":   PN = "2"  !CDS_PN = "2";
BODY = "Q_RES","I89": LOCATION = "R1661" #&CDS_LOCATION = "R1661" &SEC = "1" #&CDS_SEC = "1";
"A":   PN = "1"  !CDS_PN = "1";
"B":   PN = "2"  !CDS_PN = "2";
BODY = "Q_RES","I90": LOCATION = "R1662" #&CDS_LOCATION = "R1662" &SEC = "1" #&CDS_SEC = "1";
"A":   PN = "1"  !CDS_PN = "1";
"B":   PN = "2"  !CDS_PN = "2";
BODY = "Q_RES","I172": LOCATION = "R601" #&CDS_LOCATION = "R601" &SEC = "1" #&CDS_SEC = "1";
"A":   PN = "1"  !CDS_PN = "1";
"B":   PN = "2"  !CDS_PN = "2";
BODY = "Q_RES","I173": LOCATION = "R592" #&CDS_LOCATION = "R592" &SEC = "1" #&CDS_SEC = "1";
"A":   PN = "1"  !CDS_PN = "1";
"B":   PN = "2"  !CDS_PN = "2";
BODY = "Q_RES","I176": LOCATION = "R1460" #&CDS_LOCATION = "R1460" &SEC = "1" #&CDS_SEC = "1";
"A":   PN = "1"  !CDS_PN = "1";
"B":   PN = "2"  !CDS_PN = "2";
BODY = "Q_RES","I177": LOCATION = "R1336" #&CDS_LOCATION = "R1336" &SEC = "1" #&CDS_SEC = "1";
"A":   PN = "1"  !CDS_PN = "1";
"B":   PN = "2"  !CDS_PN = "2";
BODY = "Q_RES","I202": LOCATION = "R2212" #&CDS_LOCATION = "R2212" &SEC = "1" #&CDS_SEC = "1";
"A":   PN = "1"  !CDS_PN = "1";
"B":   PN = "2"  !CDS_PN = "2";
BODY = "Q_RES","I203": LOCATION = "R2213" #&CDS_LOCATION = "R2213" &SEC = "1" #&CDS_SEC = "1";
"A":   PN = "1"  !CDS_PN = "1";
"B":   PN = "2"  !CDS_PN = "2";
BODY = "Q_RES","I206": LOCATION = "R2449" #&CDS_LOCATION = "R2449" &SEC = "1" #&CDS_SEC = "1";
"A":   PN = "1"  !CDS_PN = "1";
"B":   PN = "2"  !CDS_PN = "2";
BODY = "Q_RES","I207": LOCATION = "R2450" #&CDS_LOCATION = "R2450" &SEC = "1" #&CDS_SEC = "1";
"A":   PN = "1"  !CDS_PN = "1";
"B":   PN = "2"  !CDS_PN = "2";
BODY = "Q_RES","I216": LOCATION = "R2456" #&CDS_LOCATION = "R2456" &SEC = "1" #&CDS_SEC = "1";
"A":   PN = "1"  !CDS_PN = "1";
"B":   PN = "2"  !CDS_PN = "2";
BODY = "Q_RES","I217": LOCATION = "R2455" #&CDS_LOCATION = "R2455" &SEC = "1" #&CDS_SEC = "1";
"A":   PN = "1"  !CDS_PN = "1";
"B":   PN = "2"  !CDS_PN = "2";
BODY = "Q_RES","I218": LOCATION = "R2454" #&CDS_LOCATION = "R2454" &SEC = "1" #&CDS_SEC = "1";
"A":   PN = "1"  !CDS_PN = "1";
"B":   PN = "2"  !CDS_PN = "2";
BODY = "Q_RES","I219": LOCATION = "R2453" #&CDS_LOCATION = "R2453" &SEC = "1" #&CDS_SEC = "1";
"A":   PN = "1"  !CDS_PN = "1";
"B":   PN = "2"  !CDS_PN = "2";
BODY = "Q_RES","I228": LOCATION = "R2995" #&CDS_LOCATION = "R2995" &SEC = "1" #&CDS_SEC = "1";
"A":   PN = "1"  !CDS_PN = "1";
"B":   PN = "2"  !CDS_PN = "2";
BODY = "Q_RES","I229": LOCATION = "R2996" #&CDS_LOCATION = "R2996" &SEC = "1" #&CDS_SEC = "1";
"A":   PN = "1"  !CDS_PN = "1";
"B":   PN = "2"  !CDS_PN = "2";
BODY = "Q_RES","I230": LOCATION = "R3004" #&CDS_LOCATION = "R3004" &SEC = "1" #&CDS_SEC = "1";
"A":   PN = "1"  !CDS_PN = "1";
"B":   PN = "2"  !CDS_PN = "2";
BODY = "Q_RES","I231": LOCATION = "R2999" #&CDS_LOCATION = "R2999" &SEC = "1" #&CDS_SEC = "1";
"A":   PN = "1"  !CDS_PN = "1";
"B":   PN = "2"  !CDS_PN = "2";
BODY = "Q_RES","I234": LOCATION = "R3061" #&CDS_LOCATION = "R3061" &SEC = "1" #&CDS_SEC = "1";
"A":   PN = "1"  !CDS_PN = "1";
"B":   PN = "2"  !CDS_PN = "2";
BODY = "Q_RES","I237": LOCATION = "R3060" #&CDS_LOCATION = "R3060" &SEC = "1" #&CDS_SEC = "1";
"A":   PN = "1"  !CDS_PN = "1";
"B":   PN = "2"  !CDS_PN = "2";
BODY = "Q_RES","I242": LOCATION = "R3058" #&CDS_LOCATION = "R3058" &SEC = "1" #&CDS_SEC = "1";
"A":   PN = "1"  !CDS_PN = "1";
"B":   PN = "2"  !CDS_PN = "2";
BODY = "Q_RES","I243": LOCATION = "R3059" #&CDS_LOCATION = "R3059" &SEC = "1" #&CDS_SEC = "1";
"A":   PN = "1"  !CDS_PN = "1";
"B":   PN = "2"  !CDS_PN = "2";
BODY = "Q_RES","I250": LOCATION = "R3227" #&CDS_LOCATION = "R3227" &SEC = "1" #&CDS_SEC = "1";
"A":   PN = "1"  !CDS_PN = "1";
"B":   PN = "2"  !CDS_PN = "2";
BODY = "Q_RES","I251": LOCATION = "R3226" #&CDS_LOCATION = "R3226" &SEC = "1" #&CDS_SEC = "1";
"A":   PN = "1"  !CDS_PN = "1";
"B":   PN = "2"  !CDS_PN = "2";
BODY = "Q_RES","I258": LOCATION = "R3241" #&CDS_LOCATION = "R3241" &SEC = "1" #&CDS_SEC = "1";
"A":   PN = "1"  !CDS_PN = "1";
"B":   PN = "2"  !CDS_PN = "2";
BODY = "Q_RES","I259": LOCATION = "R3240" #&CDS_LOCATION = "R3240" &SEC = "1" #&CDS_SEC = "1";
"A":   PN = "1"  !CDS_PN = "1";
"B":   PN = "2"  !CDS_PN = "2";
BODY = "Q_RES","I260": LOCATION = "R3242" #&CDS_LOCATION = "R3242" &SEC = "1" #&CDS_SEC = "1";
"A":   PN = "1"  !CDS_PN = "1";
"B":   PN = "2"  !CDS_PN = "2";
BODY = "Q_RES","I261": LOCATION = "R3243" #&CDS_LOCATION = "R3243" &SEC = "1" #&CDS_SEC = "1";
"A":   PN = "1"  !CDS_PN = "1";
"B":   PN = "2"  !CDS_PN = "2";
BODY = "Q_RES","I264": LOCATION = "R3341" #&CDS_LOCATION = "R3341" &SEC = "1" #&CDS_SEC = "1";
"A":   PN = "1"  !CDS_PN = "1";
"B":   PN = "2"  !CDS_PN = "2";
BODY = "Q_RES","I268": LOCATION = "R3340" #&CDS_LOCATION = "R3340" &SEC = "1" #&CDS_SEC = "1";
"A":   PN = "1"  !CDS_PN = "1";
"B":   PN = "2"  !CDS_PN = "2";
BODY = "Q_RES","I271": LOCATION = "R4150" #&CDS_LOCATION = "R4150" &SEC = "1" #&CDS_SEC = "1";
"A":   PN = "1"  !CDS_PN = "1";
"B":   PN = "2"  !CDS_PN = "2";
BODY = "Q_RES","I272": LOCATION = "R4149" #&CDS_LOCATION = "R4149" &SEC = "1" #&CDS_SEC = "1";
"A":   PN = "1"  !CDS_PN = "1";
"B":   PN = "2"  !CDS_PN = "2";
BODY = "Q_RES","I273": LOCATION = "R4152" #&CDS_LOCATION = "R4152" &SEC = "1" #&CDS_SEC = "1";
"A":   PN = "1"  !CDS_PN = "1";
"B":   PN = "2"  !CDS_PN = "2";
BODY = "Q_RES","I274": LOCATION = "R4151" #&CDS_LOCATION = "R4151" &SEC = "1" #&CDS_SEC = "1";
"A":   PN = "1"  !CDS_PN = "1";
"B":   PN = "2"  !CDS_PN = "2";
BODY = "Q_RES","I284": LOCATION = "R4511" #&CDS_LOCATION = "R4511" &SEC = "1" #&CDS_SEC = "1";
"A":   PN = "1"  !CDS_PN = "1";
"B":   PN = "2"  !CDS_PN = "2";
BODY = "Q_RES","I285": LOCATION = "R4510" #&CDS_LOCATION = "R4510" &SEC = "1" #&CDS_SEC = "1";
"A":   PN = "1"  !CDS_PN = "1";
"B":   PN = "2"  !CDS_PN = "2";
BODY = "Q_RES","I293": #LOCATION = "R4530" !CDS_LOCATION = "R4530" &SEC = "1" #&CDS_SEC = "1";
"A":   PN = "1"  !CDS_PN = "1";
"B":   PN = "2"  !CDS_PN = "2";
BODY = "Q_RES","I296": #LOCATION = "R4531" !CDS_LOCATION = "R4531" &SEC = "1" #&CDS_SEC = "1";
"A":   PN = "1"  !CDS_PN = "1";
"B":   PN = "2"  !CDS_PN = "2";
BODY = "Q_RES","I303": LOCATION = "R577" #&CDS_LOCATION = "R577" &SEC = "1" #&CDS_SEC = "1";
"A":   PN = "1"  !CDS_PN = "1";
"B":   PN = "2"  !CDS_PN = "2";
BODY = "Q_RES","I304": LOCATION = "R578" #&CDS_LOCATION = "R578" &SEC = "1" #&CDS_SEC = "1";
"A":   PN = "1"  !CDS_PN = "1";
"B":   PN = "2"  !CDS_PN = "2";
BODY = "Q_RES","I305": LOCATION = "R4512" #&CDS_LOCATION = "R4512" &SEC = "1" #&CDS_SEC = "1";
"A":   PN = "1"  !CDS_PN = "1";
"B":   PN = "2"  !CDS_PN = "2";
BODY = "Q_RES","I306": LOCATION = "R4513" #&CDS_LOCATION = "R4513" &SEC = "1" #&CDS_SEC = "1";
"A":   PN = "1"  !CDS_PN = "1";
"B":   PN = "2"  !CDS_PN = "2";
BODY = "Q_RES","I311": #LOCATION = "R593" !CDS_LOCATION = "R593" &SEC = "1" #&CDS_SEC = "1";
"A":   PN = "1"  !CDS_PN = "1";
"B":   PN = "2"  !CDS_PN = "2";
BODY = "Q_RES","I312": #LOCATION = "R594" !CDS_LOCATION = "R594" &SEC = "1" #&CDS_SEC = "1";
"A":   PN = "1"  !CDS_PN = "1";
"B":   PN = "2"  !CDS_PN = "2";
BODY = "Q_RES","I313": #LOCATION = "R596" !CDS_LOCATION = "R596" &SEC = "1" #&CDS_SEC = "1";
"A":   PN = "1"  !CDS_PN = "1";
"B":   PN = "2"  !CDS_PN = "2";
BODY = "Q_RES","I314": #LOCATION = "R595" !CDS_LOCATION = "R595" &SEC = "1" #&CDS_SEC = "1";
"A":   PN = "1"  !CDS_PN = "1";
"B":   PN = "2"  !CDS_PN = "2";
BODY = "Q_RES","I315": #LOCATION = "R598" !CDS_LOCATION = "R598" &SEC = "1" #&CDS_SEC = "1";
"A":   PN = "1"  !CDS_PN = "1";
"B":   PN = "2"  !CDS_PN = "2";
BODY = "Q_RES","I316": #LOCATION = "R597" !CDS_LOCATION = "R597" &SEC = "1" #&CDS_SEC = "1";
"A":   PN = "1"  !CDS_PN = "1";
"B":   PN = "2"  !CDS_PN = "2";
BODY = "Q_RES","I317": #LOCATION = "R599" !CDS_LOCATION = "R599" &SEC = "1" #&CDS_SEC = "1";
"A":   PN = "1"  !CDS_PN = "1";
"B":   PN = "2"  !CDS_PN = "2";
BODY = "Q_RES","I318": #LOCATION = "R600" !CDS_LOCATION = "R600" &SEC = "1" #&CDS_SEC = "1";
"A":   PN = "1"  !CDS_PN = "1";
"B":   PN = "2"  !CDS_PN = "2";
DRAWING = "@s9s_mb_2u_lib.s9s_mb_2u(sch_1):page231";
BODY = "M24128BWMN6TP","I35": LOCATION = "U64" #&CDS_LOCATION = "U64" &SEC = "1" #&CDS_SEC = "1";
"E0":   PN = "1"  !CDS_PN = "1";
"E1":   PN = "2"  !CDS_PN = "2";
"E2":   PN = "3"  !CDS_PN = "3";
"SCL":   PN = "6"  !CDS_PN = "6";
"SDA":   PN = "5"  !CDS_PN = "5";
"VCC":   PN = "8"  !CDS_PN = "8";
"VSS":   PN = "4"  !CDS_PN = "4";
"WC#":   PN = "7"  !CDS_PN = "7";
BODY = "Q_RES","I45": LOCATION = "R717" #&CDS_LOCATION = "R717" &SEC = "1" #&CDS_SEC = "1";
"A":   PN = "1"  !CDS_PN = "1";
"B":   PN = "2"  !CDS_PN = "2";
BODY = "Q_RES","I47": LOCATION = "R713" #&CDS_LOCATION = "R713" &SEC = "1" #&CDS_SEC = "1";
"A":   PN = "1"  !CDS_PN = "1";
"B":   PN = "2"  !CDS_PN = "2";
BODY = "Q_RES","I50": LOCATION = "R718" #&CDS_LOCATION = "R718" &SEC = "1" #&CDS_SEC = "1";
"A":   PN = "1"  !CDS_PN = "1";
"B":   PN = "2"  !CDS_PN = "2";
BODY = "Q_RES","I52": LOCATION = "R714" #&CDS_LOCATION = "R714" &SEC = "1" #&CDS_SEC = "1";
"A":   PN = "1"  !CDS_PN = "1";
"B":   PN = "2"  !CDS_PN = "2";
BODY = "Q_CAP","I55": LOCATION = "C629" #&CDS_LOCATION = "C629" &SEC = "1" #&CDS_SEC = "1";
"A":   PN = "1"  !CDS_PN = "1";
"B":   PN = "2"  !CDS_PN = "2";
BODY = "Q_RES","I57": LOCATION = "R710" #&CDS_LOCATION = "R710" &SEC = "1" #&CDS_SEC = "1";
"A":   PN = "1"  !CDS_PN = "1";
"B":   PN = "2"  !CDS_PN = "2";
BODY = "Q_RES","I61": LOCATION = "R722" #&CDS_LOCATION = "R722" &SEC = "1" #&CDS_SEC = "1";
"A":   PN = "1"  !CDS_PN = "1";
"B":   PN = "2"  !CDS_PN = "2";
BODY = "Q_RES","I62": LOCATION = "R721" #&CDS_LOCATION = "R721" &SEC = "1" #&CDS_SEC = "1";
"A":   PN = "1"  !CDS_PN = "1";
"B":   PN = "2"  !CDS_PN = "2";
BODY = "Q_RES","I93": LOCATION = "R1332" #&CDS_LOCATION = "R1332" &SEC = "1" #&CDS_SEC = "1";
"A":   PN = "1"  !CDS_PN = "1";
"B":   PN = "2"  !CDS_PN = "2";
BODY = "Q_RES","I95": LOCATION = "R1331" #&CDS_LOCATION = "R1331" &SEC = "1" #&CDS_SEC = "1";
"A":   PN = "1"  !CDS_PN = "1";
"B":   PN = "2"  !CDS_PN = "2";
DRAWING = "@s9s_mb_2u_lib.s9s_mb_2u(sch_1):page232";
BODY = "Q_RES","I4": LOCATION = "R1691" #&CDS_LOCATION = "R1691" &SEC = "1" #&CDS_SEC = "1";
"A":   PN = "1"  !CDS_PN = "1";
"B":   PN = "2"  !CDS_PN = "2";
BODY = "Q_RES","I33": LOCATION = "R1694" #&CDS_LOCATION = "R1694" &SEC = "1" #&CDS_SEC = "1";
"A":   PN = "1"  !CDS_PN = "1";
"B":   PN = "2"  !CDS_PN = "2";
BODY = "Q_CAP","I35": LOCATION = "C1319" #&CDS_LOCATION = "C1319" &SEC = "1" #&CDS_SEC = "1";
"A":   PN = "1"  !CDS_PN = "1";
"B":   PN = "2"  !CDS_PN = "2";
BODY = "Q_CAP","I47": LOCATION = "C1316" #&CDS_LOCATION = "C1316" &SEC = "1" #&CDS_SEC = "1";
"A":   PN = "1"  !CDS_PN = "1";
"B":   PN = "2"  !CDS_PN = "2";
BODY = "Q_RES","I3": LOCATION = "R1692" #&CDS_LOCATION = "R1692" &SEC = "1" #&CDS_SEC = "1";
"A":   PN = "1"  !CDS_PN = "1";
"B":   PN = "2"  !CDS_PN = "2";
BODY = "Q_CAP","I7": LOCATION = "C1318" #&CDS_LOCATION = "C1318" &SEC = "1" #&CDS_SEC = "1";
"A":   PN = "1"  !CDS_PN = "1";
"B":   PN = "2"  !CDS_PN = "2";
BODY = "Q_CAP","I9": LOCATION = "C1317" #&CDS_LOCATION = "C1317" &SEC = "1" #&CDS_SEC = "1";
"A":   PN = "1"  !CDS_PN = "1";
"B":   PN = "2"  !CDS_PN = "2";
BODY = "74LVC1G07SE7","I11": LOCATION = "U95" #&CDS_LOCATION = "U95" #SEC = "1" !CDS_SEC = "1";
"A":   PN = "2"  !CDS_PN = "2";
"GND":   PN = "3"  !CDS_PN = "3";
"NC1":   PN = "1"  !CDS_PN = "1";
"VCC":   PN = "5"  !CDS_PN = "5";
"Y":   PN = "4"  !CDS_PN = "4";
BODY = "Q_RES","I13": LOCATION = "R4807" #&CDS_LOCATION = "R4807" &SEC = "1" #&CDS_SEC = "1";
"A":   PN = "1"  !CDS_PN = "1";
"B":   PN = "2"  !CDS_PN = "2";
BODY = "MOSFET_NCH_GDS_ESD_PROTECTED","I14": #LOCATION = "Q52" !CDS_LOCATION = "Q52" &SEC = "1" #&CDS_SEC = "1";
"D":   PN = "D"  !CDS_PN = "D";
"G":   PN = "G"  !CDS_PN = "G";
"S":   PN = "S"  !CDS_PN = "S";
BODY = "Q_RES","I16": LOCATION = "R1689" #&CDS_LOCATION = "R1689" &SEC = "1" #&CDS_SEC = "1";
"A":   PN = "1"  !CDS_PN = "1";
"B":   PN = "2"  !CDS_PN = "2";
BODY = "Q_RES","I18": LOCATION = "R1688" #&CDS_LOCATION = "R1688" &SEC = "1" #&CDS_SEC = "1";
"A":   PN = "1"  !CDS_PN = "1";
"B":   PN = "2"  !CDS_PN = "2";
BODY = "Q_RES","I20": LOCATION = "R1950" #&CDS_LOCATION = "R1950" &SEC = "1" #&CDS_SEC = "1";
"A":   PN = "1"  !CDS_PN = "1";
"B":   PN = "2"  !CDS_PN = "2";
BODY = "Q_RES","I21": LOCATION = "R1745" #&CDS_LOCATION = "R1745" &SEC = "1" #&CDS_SEC = "1";
"A":   PN = "1"  !CDS_PN = "1";
"B":   PN = "2"  !CDS_PN = "2";
BODY = "Q_RES","I22": LOCATION = "R1690" #&CDS_LOCATION = "R1690" &SEC = "1" #&CDS_SEC = "1";
"A":   PN = "1"  !CDS_PN = "1";
"B":   PN = "2"  !CDS_PN = "2";
BODY = "Q_CAP","I24": LOCATION = "C1315" #&CDS_LOCATION = "C1315" &SEC = "1" #&CDS_SEC = "1";
"A":   PN = "1"  !CDS_PN = "1";
"B":   PN = "2"  !CDS_PN = "2";
BODY = "TPS3895ADRYR","I26": #LOCATION = "U117" !CDS_LOCATION = "U117" &SEC = "1" #&CDS_SEC = "1";
"CT":   PN = "5"  !CDS_PN = "5";
"ENABLE":   PN = "1"  !CDS_PN = "1";
"GND":   PN = "2"  !CDS_PN = "2";
"SENSE":   PN = "3"  !CDS_PN = "3";
"SENSE_OUT":   PN = "4"  !CDS_PN = "4";
"VCC":   PN = "6"  !CDS_PN = "6";
BODY = "ADM1086AKSZREEL7","I27": LOCATION = "U94" #&CDS_LOCATION = "U94" &SEC = "1" #&CDS_SEC = "1";
"CEXT":   PN = "5"  !CDS_PN = "5";
"ENIN":   PN = "1"  !CDS_PN = "1";
"ENOUT":   PN = "4"  !CDS_PN = "4";
"GND":   PN = "2"  !CDS_PN = "2";
"VCC":   PN = "6"  !CDS_PN = "6";
"VIN":   PN = "3"  !CDS_PN = "3";
BODY = "Q_RES","I31": LOCATION = "R4808" #&CDS_LOCATION = "R4808" &SEC = "1" #&CDS_SEC = "1";
"A":   PN = "1"  !CDS_PN = "1";
"B":   PN = "2"  !CDS_PN = "2";
BODY = "Q_RES","I32": LOCATION = "R1693" #&CDS_LOCATION = "R1693" &SEC = "1" #&CDS_SEC = "1";
"A":   PN = "1"  !CDS_PN = "1";
"B":   PN = "2"  !CDS_PN = "2";
BODY = "Q_RES","I36": LOCATION = "R1695" #&CDS_LOCATION = "R1695" &SEC = "1" #&CDS_SEC = "1";
"A":   PN = "1"  !CDS_PN = "1";
"B":   PN = "2"  !CDS_PN = "2";
BODY = "MOSFET_NCH_GDS_ESD_PROTECTED","I39": #LOCATION = "Q53" !CDS_LOCATION = "Q53" &SEC = "1" #&CDS_SEC = "1";
"D":   PN = "D"  !CDS_PN = "D";
"G":   PN = "G"  !CDS_PN = "G";
"S":   PN = "S"  !CDS_PN = "S";
BODY = "Q_RES","I40": LOCATION = "R2486" #&CDS_LOCATION = "R2486" &SEC = "1" #&CDS_SEC = "1";
"A":   PN = "1"  !CDS_PN = "1";
"B":   PN = "2"  !CDS_PN = "2";
DRAWING = "@s9s_mb_2u_lib.s9s_mb_2u(sch_1):page239";
BODY = "Q_RES","I19": LOCATION = "R1793" #&CDS_LOCATION = "R1793" &SEC = "1" #&CDS_SEC = "1";
"A":   PN = "1"  !CDS_PN = "1";
"B":   PN = "2"  !CDS_PN = "2";
BODY = "Q_RES","I20": LOCATION = "R1792" #&CDS_LOCATION = "R1792" &SEC = "1" #&CDS_SEC = "1";
"A":   PN = "1"  !CDS_PN = "1";
"B":   PN = "2"  !CDS_PN = "2";
BODY = "MAX11617EEET","I57": LOCATION = "U193" #&CDS_LOCATION = "U193" #SEC = "1" !CDS_SEC = "1";
"AIN0":   PN = "5"  !CDS_PN = "5";
"AIN1":   PN = "6"  !CDS_PN = "6";
"AIN2":   PN = "7"  !CDS_PN = "7";
"AIN3":   PN = "8"  !CDS_PN = "8";
"AIN4":   PN = "9"  !CDS_PN = "9";
"AIN5":   PN = "10"  !CDS_PN = "10";
"AIN6":   PN = "11"  !CDS_PN = "11";
"AIN7":   PN = "12"  !CDS_PN = "12";
"AIN8":   PN = "4"  !CDS_PN = "4";
"AIN9":   PN = "3"  !CDS_PN = "3";
"AIN10":   PN = "2"  !CDS_PN = "2";
"AIN11||REF":   PN = "1"  !CDS_PN = "1";
"GND":   PN = "15"  !CDS_PN = "15";
"SCL":   PN = "13"  !CDS_PN = "13";
"SDA":   PN = "14"  !CDS_PN = "14";
"VDD":   PN = "16"  !CDS_PN = "16";
BODY = "Q_CAP","I58": LOCATION = "C1757" #&CDS_LOCATION = "C1757" &SEC = "1" #&CDS_SEC = "1";
"A":   PN = "1"  !CDS_PN = "1";
"B":   PN = "2"  !CDS_PN = "2";
BODY = "Q_CAP","I61": LOCATION = "C1768" #&CDS_LOCATION = "C1768" &SEC = "1" #&CDS_SEC = "1";
"A":   PN = "1"  !CDS_PN = "1";
"B":   PN = "2"  !CDS_PN = "2";
BODY = "Q_INDUCTOR","I62": LOCATION = "L15" #&CDS_LOCATION = "L15" &SEC = "1" #&CDS_SEC = "1";
"1":   PN = "1"  !CDS_PN = "1";
"2":   PN = "2"  !CDS_PN = "2";
BODY = "Q_CAP","I68": LOCATION = "C1767" #&CDS_LOCATION = "C1767" &SEC = "1" #&CDS_SEC = "1";
"A":   PN = "1"  !CDS_PN = "1";
"B":   PN = "2"  !CDS_PN = "2";
BODY = "Q_CAP","I70": LOCATION = "C1347" #&CDS_LOCATION = "C1347" &SEC = "1" #&CDS_SEC = "1";
"A":   PN = "1"  !CDS_PN = "1";
"B":   PN = "2"  !CDS_PN = "2";
BODY = "Q_RES","I72": LOCATION = "R2900" #&CDS_LOCATION = "R2900" &SEC = "1" #&CDS_SEC = "1";
"A":   PN = "1"  !CDS_PN = "1";
"B":   PN = "2"  !CDS_PN = "2";
BODY = "ADC128D818CIMTXNOPB","I103": LOCATION = "U269" #&CDS_LOCATION = "U269" &SEC = "1" #&CDS_SEC = "1";
"A0":   PN = "7"  !CDS_PN = "7";
"A1":   PN = "8"  !CDS_PN = "8";
"GND":   PN = "4"  !CDS_PN = "4";
"IN0":   PN = "16"  !CDS_PN = "16";
"IN1":   PN = "15"  !CDS_PN = "15";
"IN2":   PN = "14"  !CDS_PN = "14";
"IN3":   PN = "13"  !CDS_PN = "13";
"IN4":   PN = "12"  !CDS_PN = "12";
"IN5":   PN = "11"  !CDS_PN = "11";
"IN6":   PN = "10"  !CDS_PN = "10";
"IN7":   PN = "9"  !CDS_PN = "9";
"INT#":   PN = "6"  !CDS_PN = "6";
"SCL":   PN = "3"  !CDS_PN = "3";
"SDA":   PN = "2"  !CDS_PN = "2";
"V+":   PN = "5"  !CDS_PN = "5";
"VREF":   PN = "1"  !CDS_PN = "1";
BODY = "Q_RES","I110": LOCATION = "R3671" #&CDS_LOCATION = "R3671" &SEC = "1" #&CDS_SEC = "1";
"A":   PN = "1"  !CDS_PN = "1";
"B":   PN = "2"  !CDS_PN = "2";
BODY = "Q_RES","I111": LOCATION = "R3672" #&CDS_LOCATION = "R3672" &SEC = "1" #&CDS_SEC = "1";
"A":   PN = "1"  !CDS_PN = "1";
"B":   PN = "2"  !CDS_PN = "2";
BODY = "Q_INDUCTOR","I118": LOCATION = "L16" #&CDS_LOCATION = "L16" &SEC = "1" #&CDS_SEC = "1";
"1":   PN = "1"  !CDS_PN = "1";
"2":   PN = "2"  !CDS_PN = "2";
BODY = "Q_CAP","I127": LOCATION = "C2051" #&CDS_LOCATION = "C2051" &SEC = "1" #&CDS_SEC = "1";
"A":   PN = "1"  !CDS_PN = "1";
"B":   PN = "2"  !CDS_PN = "2";
BODY = "Q_CAP","I128": LOCATION = "C2052" #&CDS_LOCATION = "C2052" &SEC = "1" #&CDS_SEC = "1";
"A":   PN = "1"  !CDS_PN = "1";
"B":   PN = "2"  !CDS_PN = "2";
BODY = "Q_RES","I129": LOCATION = "R3689" #&CDS_LOCATION = "R3689" &SEC = "1" #&CDS_SEC = "1";
"A":   PN = "1"  !CDS_PN = "1";
"B":   PN = "2"  !CDS_PN = "2";
BODY = "Q_RES","I131": LOCATION = "R3690" #&CDS_LOCATION = "R3690" &SEC = "1" #&CDS_SEC = "1";
"A":   PN = "1"  !CDS_PN = "1";
"B":   PN = "2"  !CDS_PN = "2";
BODY = "Q_RES","I141": LOCATION = "R2907" #&CDS_LOCATION = "R2907" &SEC = "1" #&CDS_SEC = "1";
"A":   PN = "1"  !CDS_PN = "1";
"B":   PN = "2"  !CDS_PN = "2";
BODY = "Q_RES","I149": LOCATION = "R1785" #&CDS_LOCATION = "R1785" &SEC = "1" #&CDS_SEC = "1";
"A":   PN = "1"  !CDS_PN = "1";
"B":   PN = "2"  !CDS_PN = "2";
BODY = "Q_RES","I161": LOCATION = "R2908" #&CDS_LOCATION = "R2908" &SEC = "1" #&CDS_SEC = "1";
"A":   PN = "1"  !CDS_PN = "1";
"B":   PN = "2"  !CDS_PN = "2";
BODY = "Q_RES","I162": LOCATION = "R2843" #&CDS_LOCATION = "R2843" &SEC = "1" #&CDS_SEC = "1";
"A":   PN = "1"  !CDS_PN = "1";
"B":   PN = "2"  !CDS_PN = "2";
BODY = "Q_RES","I163": LOCATION = "R1791" #&CDS_LOCATION = "R1791" &SEC = "1" #&CDS_SEC = "1";
"A":   PN = "1"  !CDS_PN = "1";
"B":   PN = "2"  !CDS_PN = "2";
BODY = "Q_RES","I168": LOCATION = "R3005" #&CDS_LOCATION = "R3005" &SEC = "1" #&CDS_SEC = "1";
"A":   PN = "1"  !CDS_PN = "1";
"B":   PN = "2"  !CDS_PN = "2";
BODY = "Q_RES","I173": LOCATION = "R1799" #&CDS_LOCATION = "R1799" &SEC = "1" #&CDS_SEC = "1";
"A":   PN = "1"  !CDS_PN = "1";
"B":   PN = "2"  !CDS_PN = "2";
BODY = "Q_RES","I174": LOCATION = "R1800" #&CDS_LOCATION = "R1800" &SEC = "1" #&CDS_SEC = "1";
"A":   PN = "1"  !CDS_PN = "1";
"B":   PN = "2"  !CDS_PN = "2";
BODY = "Q_RES","I176": LOCATION = "R3681" #&CDS_LOCATION = "R3681" &SEC = "1" #&CDS_SEC = "1";
"A":   PN = "1"  !CDS_PN = "1";
"B":   PN = "2"  !CDS_PN = "2";
BODY = "Q_RES","I179": LOCATION = "R3682" #&CDS_LOCATION = "R3682" &SEC = "1" #&CDS_SEC = "1";
"A":   PN = "1"  !CDS_PN = "1";
"B":   PN = "2"  !CDS_PN = "2";
BODY = "Q_CAP","I180": LOCATION = "C2042" #&CDS_LOCATION = "C2042" &SEC = "1" #&CDS_SEC = "1";
"A":   PN = "1"  !CDS_PN = "1";
"B":   PN = "2"  !CDS_PN = "2";
BODY = "Q_CAP","I181": LOCATION = "C2047" #&CDS_LOCATION = "C2047" &SEC = "1" #&CDS_SEC = "1";
"A":   PN = "1"  !CDS_PN = "1";
"B":   PN = "2"  !CDS_PN = "2";
BODY = "Q_CAP","I187": LOCATION = "C2044" #&CDS_LOCATION = "C2044" &SEC = "1" #&CDS_SEC = "1";
"A":   PN = "1"  !CDS_PN = "1";
"B":   PN = "2"  !CDS_PN = "2";
BODY = "Q_CAP","I188": LOCATION = "C2049" #&CDS_LOCATION = "C2049" &SEC = "1" #&CDS_SEC = "1";
"A":   PN = "1"  !CDS_PN = "1";
"B":   PN = "2"  !CDS_PN = "2";
BODY = "Q_RES","I190": LOCATION = "R3685" #&CDS_LOCATION = "R3685" &SEC = "1" #&CDS_SEC = "1";
"A":   PN = "1"  !CDS_PN = "1";
"B":   PN = "2"  !CDS_PN = "2";
BODY = "Q_RES","I191": LOCATION = "R3686" #&CDS_LOCATION = "R3686" &SEC = "1" #&CDS_SEC = "1";
"A":   PN = "1"  !CDS_PN = "1";
"B":   PN = "2"  !CDS_PN = "2";
BODY = "Q_CAP","I196": LOCATION = "C2043" #&CDS_LOCATION = "C2043" &SEC = "1" #&CDS_SEC = "1";
"A":   PN = "1"  !CDS_PN = "1";
"B":   PN = "2"  !CDS_PN = "2";
BODY = "Q_CAP","I197": LOCATION = "C2048" #&CDS_LOCATION = "C2048" &SEC = "1" #&CDS_SEC = "1";
"A":   PN = "1"  !CDS_PN = "1";
"B":   PN = "2"  !CDS_PN = "2";
BODY = "Q_RES","I199": LOCATION = "R3683" #&CDS_LOCATION = "R3683" &SEC = "1" #&CDS_SEC = "1";
"A":   PN = "1"  !CDS_PN = "1";
"B":   PN = "2"  !CDS_PN = "2";
BODY = "Q_RES","I200": LOCATION = "R3684" #&CDS_LOCATION = "R3684" &SEC = "1" #&CDS_SEC = "1";
"A":   PN = "1"  !CDS_PN = "1";
"B":   PN = "2"  !CDS_PN = "2";
BODY = "Q_CAP","I205": LOCATION = "C1344" #&CDS_LOCATION = "C1344" &SEC = "1" #&CDS_SEC = "1";
"A":   PN = "1"  !CDS_PN = "1";
"B":   PN = "2"  !CDS_PN = "2";
BODY = "Q_CAP","I207": LOCATION = "C2046" #&CDS_LOCATION = "C2046" &SEC = "1" #&CDS_SEC = "1";
"A":   PN = "1"  !CDS_PN = "1";
"B":   PN = "2"  !CDS_PN = "2";
BODY = "Q_RES","I209": LOCATION = "R3679" #&CDS_LOCATION = "R3679" &SEC = "1" #&CDS_SEC = "1";
"A":   PN = "1"  !CDS_PN = "1";
"B":   PN = "2"  !CDS_PN = "2";
BODY = "Q_RES","I210": LOCATION = "R3680" #&CDS_LOCATION = "R3680" &SEC = "1" #&CDS_SEC = "1";
"A":   PN = "1"  !CDS_PN = "1";
"B":   PN = "2"  !CDS_PN = "2";
BODY = "Q_RES","I223": LOCATION = "R3668" #&CDS_LOCATION = "R3668" &SEC = "1" #&CDS_SEC = "1";
"A":   PN = "1"  !CDS_PN = "1";
"B":   PN = "2"  !CDS_PN = "2";
BODY = "Q_RES","I224": LOCATION = "R3667" #&CDS_LOCATION = "R3667" &SEC = "1" #&CDS_SEC = "1";
"A":   PN = "1"  !CDS_PN = "1";
"B":   PN = "2"  !CDS_PN = "2";
BODY = "Q_RES","I227": LOCATION = "R3670" #&CDS_LOCATION = "R3670" &SEC = "1" #&CDS_SEC = "1";
"A":   PN = "1"  !CDS_PN = "1";
"B":   PN = "2"  !CDS_PN = "2";
BODY = "Q_RES","I228": LOCATION = "R3669" #&CDS_LOCATION = "R3669" &SEC = "1" #&CDS_SEC = "1";
"A":   PN = "1"  !CDS_PN = "1";
"B":   PN = "2"  !CDS_PN = "2";
BODY = "Q_CAP","I236": LOCATION = "C2045" #&CDS_LOCATION = "C2045" &SEC = "1" #&CDS_SEC = "1";
"A":   PN = "1"  !CDS_PN = "1";
"B":   PN = "2"  !CDS_PN = "2";
BODY = "Q_CAP","I238": LOCATION = "C2050" #&CDS_LOCATION = "C2050" &SEC = "1" #&CDS_SEC = "1";
"A":   PN = "1"  !CDS_PN = "1";
"B":   PN = "2"  !CDS_PN = "2";
BODY = "Q_RES","I240": LOCATION = "R3687" #&CDS_LOCATION = "R3687" &SEC = "1" #&CDS_SEC = "1";
"A":   PN = "1"  !CDS_PN = "1";
"B":   PN = "2"  !CDS_PN = "2";
BODY = "Q_RES","I241": LOCATION = "R3688" #&CDS_LOCATION = "R3688" &SEC = "1" #&CDS_SEC = "1";
"A":   PN = "1"  !CDS_PN = "1";
"B":   PN = "2"  !CDS_PN = "2";
BODY = "Q_CAP","I304": LOCATION = "C2176" #&CDS_LOCATION = "C2176" &SEC = "1" #&CDS_SEC = "1";
"A":   PN = "1"  !CDS_PN = "1";
"B":   PN = "2"  !CDS_PN = "2";
BODY = "Q_CAP","I305": LOCATION = "C2178" #&CDS_LOCATION = "C2178" &SEC = "1" #&CDS_SEC = "1";
"A":   PN = "1"  !CDS_PN = "1";
"B":   PN = "2"  !CDS_PN = "2";
BODY = "Q_CAP","I309": LOCATION = "C2175" #&CDS_LOCATION = "C2175" &SEC = "1" #&CDS_SEC = "1";
"A":   PN = "1"  !CDS_PN = "1";
"B":   PN = "2"  !CDS_PN = "2";
BODY = "Q_CAP","I311": LOCATION = "C2177" #&CDS_LOCATION = "C2177" &SEC = "1" #&CDS_SEC = "1";
"A":   PN = "1"  !CDS_PN = "1";
"B":   PN = "2"  !CDS_PN = "2";
BODY = "Q_RES","I313": LOCATION = "R3863" #&CDS_LOCATION = "R3863" &SEC = "1" #&CDS_SEC = "1";
"A":   PN = "1"  !CDS_PN = "1";
"B":   PN = "2"  !CDS_PN = "2";
BODY = "Q_RES","I314": LOCATION = "R3864" #&CDS_LOCATION = "R3864" &SEC = "1" #&CDS_SEC = "1";
"A":   PN = "1"  !CDS_PN = "1";
"B":   PN = "2"  !CDS_PN = "2";
BODY = "Q_RES","I315": LOCATION = "R3865" #&CDS_LOCATION = "R3865" &SEC = "1" #&CDS_SEC = "1";
"A":   PN = "1"  !CDS_PN = "1";
"B":   PN = "2"  !CDS_PN = "2";
BODY = "Q_RES","I316": LOCATION = "R3866" #&CDS_LOCATION = "R3866" &SEC = "1" #&CDS_SEC = "1";
"A":   PN = "1"  !CDS_PN = "1";
"B":   PN = "2"  !CDS_PN = "2";
BODY = "Q_RES","I321": LOCATION = "R3859" #&CDS_LOCATION = "R3859" &SEC = "1" #&CDS_SEC = "1";
"A":   PN = "1"  !CDS_PN = "1";
"B":   PN = "2"  !CDS_PN = "2";
BODY = "Q_RES","I322": LOCATION = "R3860" #&CDS_LOCATION = "R3860" &SEC = "1" #&CDS_SEC = "1";
"A":   PN = "1"  !CDS_PN = "1";
"B":   PN = "2"  !CDS_PN = "2";
BODY = "Q_RES","I323": LOCATION = "R3861" #&CDS_LOCATION = "R3861" &SEC = "1" #&CDS_SEC = "1";
"A":   PN = "1"  !CDS_PN = "1";
"B":   PN = "2"  !CDS_PN = "2";
BODY = "Q_RES","I324": LOCATION = "R3862" #&CDS_LOCATION = "R3862" &SEC = "1" #&CDS_SEC = "1";
"A":   PN = "1"  !CDS_PN = "1";
"B":   PN = "2"  !CDS_PN = "2";
BODY = "Q_RES","I330": LOCATION = "R3939" #&CDS_LOCATION = "R3939" &SEC = "1" #&CDS_SEC = "1";
"A":   PN = "1"  !CDS_PN = "1";
"B":   PN = "2"  !CDS_PN = "2";
BODY = "Q_CAP","I333": LOCATION = "C2195" #&CDS_LOCATION = "C2195" &SEC = "1" #&CDS_SEC = "1";
"A":   PN = "1"  !CDS_PN = "1";
"B":   PN = "2"  !CDS_PN = "2";
BODY = "Q_CAP","I336": LOCATION = "C2194" #&CDS_LOCATION = "C2194" &SEC = "1" #&CDS_SEC = "1";
"A":   PN = "1"  !CDS_PN = "1";
"B":   PN = "2"  !CDS_PN = "2";
BODY = "Q_RES","I337": LOCATION = "R3940" #&CDS_LOCATION = "R3940" &SEC = "1" #&CDS_SEC = "1";
"A":   PN = "1"  !CDS_PN = "1";
"B":   PN = "2"  !CDS_PN = "2";
BODY = "Q_RES","I338": LOCATION = "R3941" #&CDS_LOCATION = "R3941" &SEC = "1" #&CDS_SEC = "1";
"A":   PN = "1"  !CDS_PN = "1";
"B":   PN = "2"  !CDS_PN = "2";
BODY = "Q_RES","I339": LOCATION = "R3942" #&CDS_LOCATION = "R3942" &SEC = "1" #&CDS_SEC = "1";
"A":   PN = "1"  !CDS_PN = "1";
"B":   PN = "2"  !CDS_PN = "2";
BODY = "Q_RES","I346": LOCATION = "R4568" #&CDS_LOCATION = "R4568" &SEC = "1" #&CDS_SEC = "1";
"A":   PN = "1"  !CDS_PN = "1";
"B":   PN = "2"  !CDS_PN = "2";
BODY = "Q_RES","I348": LOCATION = "R4567" #&CDS_LOCATION = "R4567" &SEC = "1" #&CDS_SEC = "1";
"A":   PN = "1"  !CDS_PN = "1";
"B":   PN = "2"  !CDS_PN = "2";
DRAWING = "@s9s_mb_2u_lib.s9s_mb_2u(sch_1):page240";
BODY = "INA183A1IDBVR","I22": #LOCATION = "U103" !CDS_LOCATION = "U103" #SEC = "1" !CDS_SEC = "1";
"GND0":   PN = "1"  !CDS_PN = "1";
"GND1":   PN = "2"  !CDS_PN = "2";
"IN+":   PN = "5"  !CDS_PN = "5";
"IN-":   PN = "4"  !CDS_PN = "4";
"OUT":   PN = "3"  !CDS_PN = "3";
BODY = "Q_RES_4P_12","I3": #LOCATION = "R1837" !CDS_LOCATION = "R1837" &SEC = "1" #&CDS_SEC = "1";
"1":   PN = "1"  !CDS_PN = "1";
"2":   PN = "2"  !CDS_PN = "2";
"3":   PN = "3"  !CDS_PN = "3";
"4":   PN = "4"  !CDS_PN = "4";
BODY = "Q_RES_4P_12","I11": #LOCATION = "R1838" !CDS_LOCATION = "R1838" &SEC = "1" #&CDS_SEC = "1";
"1":   PN = "1"  !CDS_PN = "1";
"2":   PN = "2"  !CDS_PN = "2";
"3":   PN = "3"  !CDS_PN = "3";
"4":   PN = "4"  !CDS_PN = "4";
BODY = "Q_CAP","I15": LOCATION = "C2363" #&CDS_LOCATION = "C2363" &SEC = "1" #&CDS_SEC = "1";
"A":   PN = "1"  !CDS_PN = "1";
"B":   PN = "2"  !CDS_PN = "2";
BODY = "Q_RES","I16": LOCATION = "R4691" #&CDS_LOCATION = "R4691" &SEC = "1" #&CDS_SEC = "1";
"A":   PN = "1"  !CDS_PN = "1";
"B":   PN = "2"  !CDS_PN = "2";
BODY = "Q_RES","I18": LOCATION = "R4688" #&CDS_LOCATION = "R4688" &SEC = "1" #&CDS_SEC = "1";
"A":   PN = "1"  !CDS_PN = "1";
"B":   PN = "2"  !CDS_PN = "2";
BODY = "Q_RES","I19": LOCATION = "R4687" #&CDS_LOCATION = "R4687" &SEC = "1" #&CDS_SEC = "1";
"A":   PN = "1"  !CDS_PN = "1";
"B":   PN = "2"  !CDS_PN = "2";
BODY = "INA183A1IDBVR","I29": #LOCATION = "U102" !CDS_LOCATION = "U102" #SEC = "1" !CDS_SEC = "1";
"GND0":   PN = "1"  !CDS_PN = "1";
"GND1":   PN = "2"  !CDS_PN = "2";
"IN+":   PN = "5"  !CDS_PN = "5";
"IN-":   PN = "4"  !CDS_PN = "4";
"OUT":   PN = "3"  !CDS_PN = "3";
BODY = "Q_CAP","I33": LOCATION = "C2364" #&CDS_LOCATION = "C2364" &SEC = "1" #&CDS_SEC = "1";
"A":   PN = "1"  !CDS_PN = "1";
"B":   PN = "2"  !CDS_PN = "2";
BODY = "Q_RES","I35": LOCATION = "R4692" #&CDS_LOCATION = "R4692" &SEC = "1" #&CDS_SEC = "1";
"A":   PN = "1"  !CDS_PN = "1";
"B":   PN = "2"  !CDS_PN = "2";
BODY = "Q_RES","I37": LOCATION = "R4690" #&CDS_LOCATION = "R4690" &SEC = "1" #&CDS_SEC = "1";
"A":   PN = "1"  !CDS_PN = "1";
"B":   PN = "2"  !CDS_PN = "2";
BODY = "Q_RES","I38": LOCATION = "R4689" #&CDS_LOCATION = "R4689" &SEC = "1" #&CDS_SEC = "1";
"A":   PN = "1"  !CDS_PN = "1";
"B":   PN = "2"  !CDS_PN = "2";
BODY = "INA230AIRGTR","I39": #LOCATION = "U331" !CDS_LOCATION = "U331" &SEC = "1" #&CDS_SEC = "1";
"A0":   PN = "2"  !CDS_PN = "2";
"A1":   PN = "1"  !CDS_PN = "1";
"ALERT":   PN = "3"  !CDS_PN = "3";
"BUS":   PN = "11"  !CDS_PN = "11";
"GND":   PN = "10"  !CDS_PN = "10";
"IN+":   PN = "13"  !CDS_PN = "13";
"IN-":   PN = "12"  !CDS_PN = "12";
"NC0":   PN = "6"  !CDS_PN = "6";
"NC1":   PN = "7"  !CDS_PN = "7";
"NC2":   PN = "8"  !CDS_PN = "8";
"NC3":   PN = "14"  !CDS_PN = "14";
"NC4":   PN = "15"  !CDS_PN = "15";
"NC5":   PN = "16"  !CDS_PN = "16";
"SCL":   PN = "5"  !CDS_PN = "5";
"SDA":   PN = "4"  !CDS_PN = "4";
"TH":   PN = "TH"  !CDS_PN = "TH";
"VS":   PN = "9"  !CDS_PN = "9";
DRAWING = "@s9s_mb_2u_lib.s9s_mb_2u(sch_1):page243";
BODY = "Q_RES","I2": LOCATION = "R1747" #&CDS_LOCATION = "R1747" &SEC = "1" #&CDS_SEC = "1";
"A":   PN = "1"  !CDS_PN = "1";
"B":   PN = "2"  !CDS_PN = "2";
BODY = "Q_CAP","I4": LOCATION = "C535" #&CDS_LOCATION = "C535" &SEC = "1" #&CDS_SEC = "1";
"A":   PN = "1"  !CDS_PN = "1";
"B":   PN = "2"  !CDS_PN = "2";
BODY = "Q_CAP","I5": LOCATION = "C513" #&CDS_LOCATION = "C513" &SEC = "1" #&CDS_SEC = "1";
"A":   PN = "1"  !CDS_PN = "1";
"B":   PN = "2"  !CDS_PN = "2";
BODY = "Q_RES","I7": LOCATION = "R1763" #&CDS_LOCATION = "R1763" &SEC = "1" #&CDS_SEC = "1";
"A":   PN = "1"  !CDS_PN = "1";
"B":   PN = "2"  !CDS_PN = "2";
BODY = "Q_RES","I8": LOCATION = "R1764" #&CDS_LOCATION = "R1764" &SEC = "1" #&CDS_SEC = "1";
"A":   PN = "1"  !CDS_PN = "1";
"B":   PN = "2"  !CDS_PN = "2";
BODY = "Q_RES","I13": LOCATION = "R1765" #&CDS_LOCATION = "R1765" &SEC = "1" #&CDS_SEC = "1";
"A":   PN = "1"  !CDS_PN = "1";
"B":   PN = "2"  !CDS_PN = "2";
BODY = "MOSFET_N","I15": LOCATION = "U307" #&CDS_LOCATION = "U307" &SEC = "1" #&CDS_SEC = "1";
"DRAIN":   PN = "D"  !CDS_PN = "D";
"GATE":   PN = "G"  !CDS_PN = "G";
"SOURCE":   PN = "S"  !CDS_PN = "S";
BODY = "Q_RES","I16": LOCATION = "R4176" #&CDS_LOCATION = "R4176" &SEC = "1" #&CDS_SEC = "1";
"A":   PN = "1"  !CDS_PN = "1";
"B":   PN = "2"  !CDS_PN = "2";
BODY = "Q_RES","I19": LOCATION = "R4177" #&CDS_LOCATION = "R4177" &SEC = "1" #&CDS_SEC = "1";
"A":   PN = "1"  !CDS_PN = "1";
"B":   PN = "2"  !CDS_PN = "2";
DRAWING = "@s9s_mb_2u_lib.s9s_mb_2u(sch_1):page244";
BODY = "Q_RES","I25": #LOCATION = "PR91" !CDS_LOCATION = "PR91" &SEC = "1" #&CDS_SEC = "1";
"A":   PN = "1"  !CDS_PN = "1";
"B":   PN = "2"  !CDS_PN = "2";
BODY = "Q_CAP","I34": #LOCATION = "PC1856" !CDS_LOCATION = "PC1856" &SEC = "1" #&CDS_SEC = "1";
"A":   PN = "1"  !CDS_PN = "1";
"B":   PN = "2"  !CDS_PN = "2";
BODY = "Q_RES","I27": #LOCATION = "R2356" !CDS_LOCATION = "R2356" #SEC = "1" !CDS_SEC = "1";
"A":   PN = "1"  !CDS_PN = "1";
"B":   PN = "2"  !CDS_PN = "2";
BODY = "Q_RES","I28": #LOCATION = "R2316" !CDS_LOCATION = "R2316" &SEC = "1" #&CDS_SEC = "1";
"A":   PN = "1"  !CDS_PN = "1";
"B":   PN = "2"  !CDS_PN = "2";
BODY = "Q_INDUCTOR","I30": #LOCATION = "PL65" !CDS_LOCATION = "PL65" &SEC = "1" #&CDS_SEC = "1";
"1":   PN = "1"  !CDS_PN = "1";
"2":   PN = "2"  !CDS_PN = "2";
BODY = "Q_RES","I10": #LOCATION = "PR3337" !CDS_LOCATION = "PR3337" &SEC = "1" #&CDS_SEC = "1";
"A":   PN = "1"  !CDS_PN = "1";
"B":   PN = "2"  !CDS_PN = "2";
BODY = "Q_RES","I16": #LOCATION = "PR89" !CDS_LOCATION = "PR89" #SEC = "1" !CDS_SEC = "1";
"A":   PN = "1"  !CDS_PN = "1";
"B":   PN = "2"  !CDS_PN = "2";
BODY = "Q_CAP","I12": #LOCATION = "PC1898" !CDS_LOCATION = "PC1898" &SEC = "1" #&CDS_SEC = "1";
"A":   PN = "1"  !CDS_PN = "1";
"B":   PN = "2"  !CDS_PN = "2";
BODY = "Q_CAP","I26": #LOCATION = "PC1847" !CDS_LOCATION = "PC1847" &SEC = "1" #&CDS_SEC = "1";
"A":   PN = "1"  !CDS_PN = "1";
"B":   PN = "2"  !CDS_PN = "2";
BODY = "Q_CAP","I2": #LOCATION = "PC1648" !CDS_LOCATION = "PC1648" &SEC = "1" #&CDS_SEC = "1";
"A":   PN = "1"  !CDS_PN = "1";
"B":   PN = "2"  !CDS_PN = "2";
BODY = "Q_INDUCTOR","I5": #LOCATION = "PL64" !CDS_LOCATION = "PL64" &SEC = "1" #&CDS_SEC = "1";
"1":   PN = "1"  !CDS_PN = "1";
"2":   PN = "2"  !CDS_PN = "2";
BODY = "Q_CAP","I7": #LOCATION = "PC1849" !CDS_LOCATION = "PC1849" &SEC = "1" #&CDS_SEC = "1";
"A":   PN = "1"  !CDS_PN = "1";
"B":   PN = "2"  !CDS_PN = "2";
BODY = "Q_CAP","I8": #LOCATION = "PC1848" !CDS_LOCATION = "PC1848" #SEC = "1" !CDS_SEC = "1";
"A":   PN = "1"  !CDS_PN = "1";
"B":   PN = "2"  !CDS_PN = "2";
BODY = "Q_CAP","I11": #LOCATION = "PC1850" !CDS_LOCATION = "PC1850" &SEC = "1" #&CDS_SEC = "1";
"A":   PN = "1"  !CDS_PN = "1";
"B":   PN = "2"  !CDS_PN = "2";
BODY = "Q_CAP","I14": #LOCATION = "PC1846" !CDS_LOCATION = "PC1846" &SEC = "1" #&CDS_SEC = "1";
"A":   PN = "1"  !CDS_PN = "1";
"B":   PN = "2"  !CDS_PN = "2";
BODY = "RS53318LR","I20": #LOCATION = "PU181" !CDS_LOCATION = "PU181" #SEC = "1" !CDS_SEC = "1";
"AGND":   PN = "2"  !CDS_PN = "2";
"BST":   PN = "1"  !CDS_PN = "1";
"CS":   PN = "3"  !CDS_PN = "3";
"EN":   PN = "8"  !CDS_PN = "8";
"FB":   PN = "7"  !CDS_PN = "7";
"MODE":   PN = "4"  !CDS_PN = "4";
"PGND":   PN = "11_18"  !CDS_PN = "11_18";
"PGOOD":   PN = "9"  !CDS_PN = "9";
"REF":   PN = "5"  !CDS_PN = "5";
"RTN":   PN = "6"  !CDS_PN = "6";
"SW":   PN = "20"  !CDS_PN = "20";
"VCC":   PN = "19"  !CDS_PN = "19";
"VIN1":   PN = "10"  !CDS_PN = "10";
"VIN2":   PN = "21"  !CDS_PN = "21";
BODY = "Q_CAP","I21": #LOCATION = "PC1853" !CDS_LOCATION = "PC1853" &SEC = "1" #&CDS_SEC = "1";
"A":   PN = "1"  !CDS_PN = "1";
"B":   PN = "2"  !CDS_PN = "2";
BODY = "Q_CAP","I22": #LOCATION = "PC1877" !CDS_LOCATION = "PC1877" &SEC = "1" #&CDS_SEC = "1";
"A":   PN = "1"  !CDS_PN = "1";
"B":   PN = "2"  !CDS_PN = "2";
BODY = "Q_CAPP","I32": #LOCATION = "PC1845" !CDS_LOCATION = "PC1845" &SEC = "1" #&CDS_SEC = "1";
"A":   PN = "1"  !CDS_PN = "1";
"B":   PN = "2"  !CDS_PN = "2";
BODY = "Q_CAP","I33": #LOCATION = "PC1855" !CDS_LOCATION = "PC1855" &SEC = "1" #&CDS_SEC = "1";
"A":   PN = "1"  !CDS_PN = "1";
"B":   PN = "2"  !CDS_PN = "2";
BODY = "Q_CAP","I36": #LOCATION = "PC1852" !CDS_LOCATION = "PC1852" #SEC = "1" !CDS_SEC = "1";
"A":   PN = "1"  !CDS_PN = "1";
"B":   PN = "2"  !CDS_PN = "2";
BODY = "Q_RES","I39": #LOCATION = "PR92" !CDS_LOCATION = "PR92" &SEC = "1" #&CDS_SEC = "1";
"A":   PN = "1"  !CDS_PN = "1";
"B":   PN = "2"  !CDS_PN = "2";
DRAWING = "@s9s_mb_2u_lib.s9s_mb_2u(sch_1):page248";
BODY = "Q_CAP","I8": #LOCATION = "PC2286" !CDS_LOCATION = "PC2286" &SEC = "1" #&CDS_SEC = "1";
"A":   PN = "1"  !CDS_PN = "1";
"B":   PN = "2"  !CDS_PN = "2";
BODY = "Q_CAP","I30": #LOCATION = "PC1219" !CDS_LOCATION = "PC1219" &SEC = "1" #&CDS_SEC = "1";
"A":   PN = "1"  !CDS_PN = "1";
"B":   PN = "2"  !CDS_PN = "2";
BODY = "Q_RES","I34": #LOCATION = "PR187" !CDS_LOCATION = "PR187" &SEC = "1" #&CDS_SEC = "1";
"A":   PN = "1"  !CDS_PN = "1";
"B":   PN = "2"  !CDS_PN = "2";
BODY = "Q_CAP","I35": #LOCATION = "PC1223" !CDS_LOCATION = "PC1223" &SEC = "1" #&CDS_SEC = "1";
"A":   PN = "1"  !CDS_PN = "1";
"B":   PN = "2"  !CDS_PN = "2";
BODY = "Q_RES","I36": #LOCATION = "PR1328" !CDS_LOCATION = "PR1328" &SEC = "1" #&CDS_SEC = "1";
"A":   PN = "1"  !CDS_PN = "1";
"B":   PN = "2"  !CDS_PN = "2";
BODY = "Q_CAP","I37": #LOCATION = "PC2279" !CDS_LOCATION = "PC2279" &SEC = "1" #&CDS_SEC = "1";
"A":   PN = "1"  !CDS_PN = "1";
"B":   PN = "2"  !CDS_PN = "2";
BODY = "Q_CAPP","I41": #LOCATION = "PC1227" !CDS_LOCATION = "PC1227" &SEC = "1" #&CDS_SEC = "1";
"A":   PN = "1"  !CDS_PN = "1";
"B":   PN = "2"  !CDS_PN = "2";
BODY = "Q_SHORT","I43": #LOCATION = "PJ62" !CDS_LOCATION = "PJ62" &SEC = "1" #&CDS_SEC = "1";
"1":   PN = "1"  !CDS_PN = "1";
"2":   PN = "2"  !CDS_PN = "2";
BODY = "Q_RES","I9": #LOCATION = "PR1649" !CDS_LOCATION = "PR1649" &SEC = "1" #&CDS_SEC = "1";
"A":   PN = "1"  !CDS_PN = "1";
"B":   PN = "2"  !CDS_PN = "2";
BODY = "Q_CAPP","I23": LOCATION = "PC1215" #&CDS_LOCATION = "PC1215" &SEC = "1" #&CDS_SEC = "1";
"A":   PN = "1"  !CDS_PN = "1";
"B":   PN = "2"  !CDS_PN = "2";
BODY = "Q_RES","I26": #LOCATION = "PR1647" !CDS_LOCATION = "PR1647" &SEC = "1" #&CDS_SEC = "1";
"A":   PN = "1"  !CDS_PN = "1";
"B":   PN = "2"  !CDS_PN = "2";
BODY = "Q_CAP","I44": #LOCATION = "PC1225" !CDS_LOCATION = "PC1225" &SEC = "1" #&CDS_SEC = "1";
"A":   PN = "1"  !CDS_PN = "1";
"B":   PN = "2"  !CDS_PN = "2";
BODY = "Q_RES","I51": #LOCATION = "R1650" !CDS_LOCATION = "R1650" &SEC = "1" #&CDS_SEC = "1";
"A":   PN = "1"  !CDS_PN = "1";
"B":   PN = "2"  !CDS_PN = "2";
BODY = "Q_CAP","I29": #LOCATION = "PC1218" !CDS_LOCATION = "PC1218" &SEC = "1" #&CDS_SEC = "1";
"A":   PN = "1"  !CDS_PN = "1";
"B":   PN = "2"  !CDS_PN = "2";
BODY = "Q_CAP","I31": #LOCATION = "PC1222" !CDS_LOCATION = "PC1222" &SEC = "1" #&CDS_SEC = "1";
"A":   PN = "1"  !CDS_PN = "1";
"B":   PN = "2"  !CDS_PN = "2";
BODY = "Q_RES","I32": #LOCATION = "R2357" !CDS_LOCATION = "R2357" &SEC = "1" #&CDS_SEC = "1";
"A":   PN = "1"  !CDS_PN = "1";
"B":   PN = "2"  !CDS_PN = "2";
BODY = "Q_SHORT","I42": #LOCATION = "PJ63" !CDS_LOCATION = "PJ63" &SEC = "1" #&CDS_SEC = "1";
"1":   PN = "1"  !CDS_PN = "1";
"2":   PN = "2"  !CDS_PN = "2";
BODY = "Q_INDUCTOR","I53": #LOCATION = "PL150" !CDS_LOCATION = "PL150" &SEC = "1" #&CDS_SEC = "1";
"1":   PN = "1"  !CDS_PN = "1";
"2":   PN = "2"  !CDS_PN = "2";
BODY = "Q_RES","I27": #LOCATION = "R1389" !CDS_LOCATION = "R1389" &SEC = "1" #&CDS_SEC = "1";
"A":   PN = "1"  !CDS_PN = "1";
"B":   PN = "2"  !CDS_PN = "2";
BODY = "Q_CAP","I45": #LOCATION = "PC1226" !CDS_LOCATION = "PC1226" &SEC = "1" #&CDS_SEC = "1";
"A":   PN = "1"  !CDS_PN = "1";
"B":   PN = "2"  !CDS_PN = "2";
BODY = "Q_RES","I3": #LOCATION = "PR1326" !CDS_LOCATION = "PR1326" &SEC = "1" #&CDS_SEC = "1";
"A":   PN = "1"  !CDS_PN = "1";
"B":   PN = "2"  !CDS_PN = "2";
BODY = "Q_RES","I6": #LOCATION = "PR1327" !CDS_LOCATION = "PR1327" &SEC = "1" #&CDS_SEC = "1";
"A":   PN = "1"  !CDS_PN = "1";
"B":   PN = "2"  !CDS_PN = "2";
BODY = "RS53319LR","I11": #LOCATION = "PU73" !CDS_LOCATION = "PU73" #SEC = "1" !CDS_SEC = "1";
"AGND":   PN = "2"  !CDS_PN = "2";
"BST":   PN = "1"  !CDS_PN = "1";
"CS":   PN = "3"  !CDS_PN = "3";
"EN":   PN = "8"  !CDS_PN = "8";
"FB":   PN = "7"  !CDS_PN = "7";
"MODE":   PN = "4"  !CDS_PN = "4";
"PGND":   PN = "11_18"  !CDS_PN = "11_18";
"PGOOD":   PN = "9"  !CDS_PN = "9";
"REF":   PN = "5"  !CDS_PN = "5";
"RTN":   PN = "6"  !CDS_PN = "6";
"SW":   PN = "20"  !CDS_PN = "20";
"VCC":   PN = "19"  !CDS_PN = "19";
"VIN1":   PN = "10"  !CDS_PN = "10";
"VIN2":   PN = "21"  !CDS_PN = "21";
BODY = "Q_CAP","I18": #LOCATION = "PC1650" !CDS_LOCATION = "PC1650" &SEC = "1" #&CDS_SEC = "1";
"A":   PN = "1"  !CDS_PN = "1";
"B":   PN = "2"  !CDS_PN = "2";
BODY = "Q_CAP","I28": #LOCATION = "PC1217" !CDS_LOCATION = "PC1217" &SEC = "1" #&CDS_SEC = "1";
"A":   PN = "1"  !CDS_PN = "1";
"B":   PN = "2"  !CDS_PN = "2";
BODY = "Q_CAPP","I47": #LOCATION = "PC1229" !CDS_LOCATION = "PC1229" &SEC = "1" #&CDS_SEC = "1";
"A":   PN = "1"  !CDS_PN = "1";
"B":   PN = "2"  !CDS_PN = "2";
BODY = "Q_CAP","I2": #LOCATION = "PC113" !CDS_LOCATION = "PC113" #SEC = "1" !CDS_SEC = "1";
"A":   PN = "1"  !CDS_PN = "1";
"B":   PN = "2"  !CDS_PN = "2";
BODY = "Q_RES","I10": #LOCATION = "PR338" !CDS_LOCATION = "PR338" &SEC = "1" #&CDS_SEC = "1";
"A":   PN = "1"  !CDS_PN = "1";
"B":   PN = "2"  !CDS_PN = "2";
BODY = "Q_CAP","I14": #LOCATION = "PC2000" !CDS_LOCATION = "PC2000" &SEC = "1" #&CDS_SEC = "1";
"A":   PN = "1"  !CDS_PN = "1";
"B":   PN = "2"  !CDS_PN = "2";
BODY = "Q_CAP","I16": #LOCATION = "PC1221" !CDS_LOCATION = "PC1221" &SEC = "1" #&CDS_SEC = "1";
"A":   PN = "1"  !CDS_PN = "1";
"B":   PN = "2"  !CDS_PN = "2";
BODY = "Q_INDUCTOR","I19": #LOCATION = "PL110" !CDS_LOCATION = "PL110" &SEC = "1" #&CDS_SEC = "1";
"1":   PN = "1"  !CDS_PN = "1";
"2":   PN = "2"  !CDS_PN = "2";
BODY = "Q_CAP","I25": #LOCATION = "PC1216" !CDS_LOCATION = "PC1216" &SEC = "1" #&CDS_SEC = "1";
"A":   PN = "1"  !CDS_PN = "1";
"B":   PN = "2"  !CDS_PN = "2";
BODY = "Q_CAP","I38": #LOCATION = "PC1224" !CDS_LOCATION = "PC1224" &SEC = "1" #&CDS_SEC = "1";
"A":   PN = "1"  !CDS_PN = "1";
"B":   PN = "2"  !CDS_PN = "2";
BODY = "Q_CAPP","I40": #LOCATION = "PC117" !CDS_LOCATION = "PC117" &SEC = "1" #&CDS_SEC = "1";
"A":   PN = "1"  !CDS_PN = "1";
"B":   PN = "2"  !CDS_PN = "2";
BODY = "Q_CAPP","I48": #LOCATION = "PC1230" !CDS_LOCATION = "PC1230" &SEC = "1" #&CDS_SEC = "1";
"A":   PN = "1"  !CDS_PN = "1";
"B":   PN = "2"  !CDS_PN = "2";
BODY = "Q_RES","I52": #LOCATION = "R4780" !CDS_LOCATION = "R4780" &SEC = "1" #&CDS_SEC = "1";
"A":   PN = "1"  !CDS_PN = "1";
"B":   PN = "2"  !CDS_PN = "2";
DRAWING = "@s9s_mb_2u_lib.s9s_mb_2u(sch_1):page249";
BODY = "NB682GDZ","I26": #LOCATION = "PU74" !CDS_LOCATION = "PU74" #SEC = "1" !CDS_SEC = "1";
"3V3":   PN = "10"  !CDS_PN = "10";
"AGND":   PN = "11"  !CDS_PN = "11";
"BST":   PN = "9"  !CDS_PN = "9";
"C0":   PN = "4"  !CDS_PN = "4";
"C1":   PN = "3"  !CDS_PN = "3";
"EN":   PN = "5"  !CDS_PN = "5";
"LP#":   PN = "6"  !CDS_PN = "6";
"MODE":   PN = "7"  !CDS_PN = "7";
"PG":   PN = "13"  !CDS_PN = "13";
"PGND":   PN = "2"  !CDS_PN = "2";
"SW":   PN = "8"  !CDS_PN = "8";
"VIN":   PN = "1"  !CDS_PN = "1";
"VOUT":   PN = "12"  !CDS_PN = "12";
BODY = "Q_CAP","I28": #LOCATION = "PC1236" !CDS_LOCATION = "PC1236" &SEC = "1" #&CDS_SEC = "1";
"A":   PN = "1"  !CDS_PN = "1";
"B":   PN = "2"  !CDS_PN = "2";
BODY = "Q_CAP","I30": #LOCATION = "PC1235" !CDS_LOCATION = "PC1235" &SEC = "1" #&CDS_SEC = "1";
"A":   PN = "1"  !CDS_PN = "1";
"B":   PN = "2"  !CDS_PN = "2";
BODY = "Q_CAP","I39": #LOCATION = "PC1240" !CDS_LOCATION = "PC1240" &SEC = "1" #&CDS_SEC = "1";
"A":   PN = "1"  !CDS_PN = "1";
"B":   PN = "2"  !CDS_PN = "2";
BODY = "Q_RES","I8": #LOCATION = "PR395" !CDS_LOCATION = "PR395" &SEC = "1" #&CDS_SEC = "1";
"A":   PN = "1"  !CDS_PN = "1";
"B":   PN = "2"  !CDS_PN = "2";
BODY = "Q_CAP","I14": #LOCATION = "PC1651" !CDS_LOCATION = "PC1651" &SEC = "1" #&CDS_SEC = "1";
"A":   PN = "1"  !CDS_PN = "1";
"B":   PN = "2"  !CDS_PN = "2";
BODY = "Q_RES","I24": #LOCATION = "PR1330" !CDS_LOCATION = "PR1330" &SEC = "1" #&CDS_SEC = "1";
"A":   PN = "1"  !CDS_PN = "1";
"B":   PN = "2"  !CDS_PN = "2";
BODY = "Q_CAP","I4": #LOCATION = "PC1642" !CDS_LOCATION = "PC1642" #SEC = "1" !CDS_SEC = "1";
"A":   PN = "1"  !CDS_PN = "1";
"B":   PN = "2"  !CDS_PN = "2";
BODY = "Q_RES","I17": #LOCATION = "R2358" !CDS_LOCATION = "R2358" &SEC = "1" #&CDS_SEC = "1";
"A":   PN = "1"  !CDS_PN = "1";
"B":   PN = "2"  !CDS_PN = "2";
BODY = "Q_CAP","I21": #LOCATION = "PC1234" !CDS_LOCATION = "PC1234" &SEC = "1" #&CDS_SEC = "1";
"A":   PN = "1"  !CDS_PN = "1";
"B":   PN = "2"  !CDS_PN = "2";
BODY = "Q_CAP","I29": #LOCATION = "PC1237" !CDS_LOCATION = "PC1237" &SEC = "1" #&CDS_SEC = "1";
"A":   PN = "1"  !CDS_PN = "1";
"B":   PN = "2"  !CDS_PN = "2";
BODY = "Q_CAP","I36": #LOCATION = "C2287" !CDS_LOCATION = "C2287" &SEC = "1" #&CDS_SEC = "1";
"A":   PN = "1"  !CDS_PN = "1";
"B":   PN = "2"  !CDS_PN = "2";
BODY = "Q_CAP","I37": #LOCATION = "PC1238" !CDS_LOCATION = "PC1238" &SEC = "1" #&CDS_SEC = "1";
"A":   PN = "1"  !CDS_PN = "1";
"B":   PN = "2"  !CDS_PN = "2";
BODY = "Q_CAP","I38": #LOCATION = "PC1239" !CDS_LOCATION = "PC1239" &SEC = "1" #&CDS_SEC = "1";
"A":   PN = "1"  !CDS_PN = "1";
"B":   PN = "2"  !CDS_PN = "2";
BODY = "Q_RES","I2": #LOCATION = "PR396" !CDS_LOCATION = "PR396" &SEC = "1" #&CDS_SEC = "1";
"A":   PN = "1"  !CDS_PN = "1";
"B":   PN = "2"  !CDS_PN = "2";
BODY = "Q_RES","I5": #LOCATION = "PR1329" !CDS_LOCATION = "PR1329" &SEC = "1" #&CDS_SEC = "1";
"A":   PN = "1"  !CDS_PN = "1";
"B":   PN = "2"  !CDS_PN = "2";
BODY = "Q_RES","I11": #LOCATION = "PR1850" !CDS_LOCATION = "PR1850" &SEC = "1" #&CDS_SEC = "1";
"A":   PN = "1"  !CDS_PN = "1";
"B":   PN = "2"  !CDS_PN = "2";
BODY = "Q_INDUCTOR","I16": #LOCATION = "PL16" !CDS_LOCATION = "PL16" &SEC = "1" #&CDS_SEC = "1";
"1":   PN = "1"  !CDS_PN = "1";
"2":   PN = "2"  !CDS_PN = "2";
BODY = "Q_CAP","I19": #LOCATION = "PC1232" !CDS_LOCATION = "PC1232" &SEC = "1" #&CDS_SEC = "1";
"A":   PN = "1"  !CDS_PN = "1";
"B":   PN = "2"  !CDS_PN = "2";
BODY = "Q_CAP","I20": #LOCATION = "PC1233" !CDS_LOCATION = "PC1233" &SEC = "1" #&CDS_SEC = "1";
"A":   PN = "1"  !CDS_PN = "1";
"B":   PN = "2"  !CDS_PN = "2";
BODY = "Q_RES","I31": #LOCATION = "R2359" !CDS_LOCATION = "R2359" &SEC = "1" #&CDS_SEC = "1";
"A":   PN = "1"  !CDS_PN = "1";
"B":   PN = "2"  !CDS_PN = "2";
BODY = "Q_RES","I34": #LOCATION = "R2360" !CDS_LOCATION = "R2360" &SEC = "1" #&CDS_SEC = "1";
"A":   PN = "1"  !CDS_PN = "1";
"B":   PN = "2"  !CDS_PN = "2";
BODY = "Q_CAP","I41": #LOCATION = "PC1241" !CDS_LOCATION = "PC1241" &SEC = "1" #&CDS_SEC = "1";
"A":   PN = "1"  !CDS_PN = "1";
"B":   PN = "2"  !CDS_PN = "2";
BODY = "Q_RES","I42": #LOCATION = "PR1653" !CDS_LOCATION = "PR1653" &SEC = "1" #&CDS_SEC = "1";
"A":   PN = "1"  !CDS_PN = "1";
"B":   PN = "2"  !CDS_PN = "2";
BODY = "Q_INDUCTOR","I45": #LOCATION = "PL170" !CDS_LOCATION = "PL170" &SEC = "1" #&CDS_SEC = "1";
"1":   PN = "1"  !CDS_PN = "1";
"2":   PN = "2"  !CDS_PN = "2";
DRAWING = "@s9s_mb_2u_lib.s9s_mb_2u(sch_1):page252";
BODY = "Q_RES","I19": #LOCATION = "R2375" !CDS_LOCATION = "R2375" &SEC = "1" #&CDS_SEC = "1";
"A":   PN = "1"  !CDS_PN = "1";
"B":   PN = "2"  !CDS_PN = "2";
BODY = "Q_SHORT","I24": #LOCATION = "PJ53" !CDS_LOCATION = "PJ53" &SEC = "1" #&CDS_SEC = "1";
"1":   PN = "1"  !CDS_PN = "1";
"2":   PN = "2"  !CDS_PN = "2";
BODY = "Q_RES","I50": #LOCATION = "R2365" !CDS_LOCATION = "R2365" &SEC = "1" #&CDS_SEC = "1";
"A":   PN = "1"  !CDS_PN = "1";
"B":   PN = "2"  !CDS_PN = "2";
BODY = "Q_RES","I15": #LOCATION = "PR586" !CDS_LOCATION = "PR586" &SEC = "1" #&CDS_SEC = "1";
"A":   PN = "1"  !CDS_PN = "1";
"B":   PN = "2"  !CDS_PN = "2";
BODY = "Q_RES","I38": #LOCATION = "PR531" !CDS_LOCATION = "PR531" &SEC = "1" #&CDS_SEC = "1";
"A":   PN = "1"  !CDS_PN = "1";
"B":   PN = "2"  !CDS_PN = "2";
BODY = "Q_RES","I74": #LOCATION = "PR4217" !CDS_LOCATION = "PR4217" &SEC = "1" #&CDS_SEC = "1";
"A":   PN = "1"  !CDS_PN = "1";
"B":   PN = "2"  !CDS_PN = "2";
BODY = "Q_SHORT","I37": #LOCATION = "PJ47" !CDS_LOCATION = "PJ47" &SEC = "1" #&CDS_SEC = "1";
"1":   PN = "1"  !CDS_PN = "1";
"2":   PN = "2"  !CDS_PN = "2";
BODY = "Q_RES","I49": #LOCATION = "R2366" !CDS_LOCATION = "R2366" &SEC = "1" #&CDS_SEC = "1";
"A":   PN = "1"  !CDS_PN = "1";
"B":   PN = "2"  !CDS_PN = "2";
BODY = "Q_RES","I51": #LOCATION = "PR158" !CDS_LOCATION = "PR158" &SEC = "1" #&CDS_SEC = "1";
"A":   PN = "1"  !CDS_PN = "1";
"B":   PN = "2"  !CDS_PN = "2";
BODY = "RAA229126GNPHA0","I63": #LOCATION = "PU14" !CDS_LOCATION = "PU14" #SEC = "1" !CDS_SEC = "1";
"ADDR_CFG":   PN = "42"  !CDS_PN = "42";
"CFP":   PN = "41"  !CDS_PN = "41";
"CS0":   PN = "38"  !CDS_PN = "38";
"CS1":   PN = "37"  !CDS_PN = "37";
"CS2":   PN = "36"  !CDS_PN = "36";
"CS3":   PN = "35"  !CDS_PN = "35";
"CS4":   PN = "34"  !CDS_PN = "34";
"CS5":   PN = "33"  !CDS_PN = "33";
"CS6":   PN = "32"  !CDS_PN = "32";
"CS7":   PN = "31"  !CDS_PN = "31";
"CS8":   PN = "30"  !CDS_PN = "30";
"CS9":   PN = "29"  !CDS_PN = "29";
"CS10":   PN = "28"  !CDS_PN = "28";
"CS11":   PN = "27"  !CDS_PN = "27";
"EN0":   PN = "17"  !CDS_PN = "17";
"EN1":   PN = "24"  !CDS_PN = "24";
"NPINALERT||NPSYS_CRIT":   PN = "19"  !CDS_PN = "19";
"NPMALERT":   PN = "15"  !CDS_PN = "15";
"NSVALERT":   PN = "23"  !CDS_PN = "23";
"NVRHOT":   PN = "18"  !CDS_PN = "18";
"PG0":   PN = "16"  !CDS_PN = "16";
"PG1":   PN = "20"  !CDS_PN = "20";
"PMSCL":   PN = "14"  !CDS_PN = "14";
"PMSDA":   PN = "13"  !CDS_PN = "13";
"PWM0":   PN = "1"  !CDS_PN = "1";
"PWM1":   PN = "2"  !CDS_PN = "2";
"PWM2":   PN = "3"  !CDS_PN = "3";
"PWM3":   PN = "4"  !CDS_PN = "4";
"PWM4":   PN = "5"  !CDS_PN = "5";
"PWM5":   PN = "6"  !CDS_PN = "6";
"PWM6":   PN = "7"  !CDS_PN = "7";
"PWM7":   PN = "8"  !CDS_PN = "8";
"PWM8":   PN = "9"  !CDS_PN = "9";
"PWM9":   PN = "10"  !CDS_PN = "10";
"PWM10":   PN = "11"  !CDS_PN = "11";
"PWM11":   PN = "12"  !CDS_PN = "12";
"RGND0":   PN = "26"  !CDS_PN = "26";
"RGND1":   PN = "39"  !CDS_PN = "39";
"SVCLK":   PN = "21"  !CDS_PN = "21";
"SVDATA":   PN = "22"  !CDS_PN = "22";
"TEMP0":   PN = "43"  !CDS_PN = "43";
"TEMP1||ISYS":   PN = "44"  !CDS_PN = "44";
"TH_GND":   PN = "TH"  !CDS_PN = "TH";
"VCC":   PN = "47"  !CDS_PN = "47";
"VCCS":   PN = "48"  !CDS_PN = "48";
"VINSEN||VSYS":   PN = "46"  !CDS_PN = "46";
"VMON||IINSEN||VSYS||ISYS":   PN = "45"  !CDS_PN = "45";
"VSEN0":   PN = "25"  !CDS_PN = "25";
"VSEN1":   PN = "40"  !CDS_PN = "40";
BODY = "Q_RES","I66": #LOCATION = "R4593" !CDS_LOCATION = "R4593" &SEC = "1" #&CDS_SEC = "1";
"A":   PN = "1"  !CDS_PN = "1";
"B":   PN = "2"  !CDS_PN = "2";
BODY = "Q_CAP","I67": #LOCATION = "PC594" !CDS_LOCATION = "PC594" &SEC = "1" #&CDS_SEC = "1";
"A":   PN = "1"  !CDS_PN = "1";
"B":   PN = "2"  !CDS_PN = "2";
BODY = "Q_RES","I133": #LOCATION = "PR176" !CDS_LOCATION = "PR176" &SEC = "1" #&CDS_SEC = "1";
"A":   PN = "1"  !CDS_PN = "1";
"B":   PN = "2"  !CDS_PN = "2";
BODY = "Q_RES","I5": #LOCATION = "PR159" !CDS_LOCATION = "PR159" &SEC = "1" #&CDS_SEC = "1";
"A":   PN = "1"  !CDS_PN = "1";
"B":   PN = "2"  !CDS_PN = "2";
BODY = "Q_RES","I10": #LOCATION = "PR156" !CDS_LOCATION = "PR156" &SEC = "1" #&CDS_SEC = "1";
"A":   PN = "1"  !CDS_PN = "1";
"B":   PN = "2"  !CDS_PN = "2";
BODY = "Q_RES","I11": #LOCATION = "PR157" !CDS_LOCATION = "PR157" &SEC = "1" #&CDS_SEC = "1";
"A":   PN = "1"  !CDS_PN = "1";
"B":   PN = "2"  !CDS_PN = "2";
BODY = "Q_RES","I17": #LOCATION = "R2376" !CDS_LOCATION = "R2376" &SEC = "1" #&CDS_SEC = "1";
"A":   PN = "1"  !CDS_PN = "1";
"B":   PN = "2"  !CDS_PN = "2";
BODY = "Q_RES","I20": #LOCATION = "R2589" !CDS_LOCATION = "R2589" &SEC = "1" #&CDS_SEC = "1";
"A":   PN = "1"  !CDS_PN = "1";
"B":   PN = "2"  !CDS_PN = "2";
BODY = "Q_RES","I40": #LOCATION = "R1713" !CDS_LOCATION = "R1713" &SEC = "1" #&CDS_SEC = "1";
"A":   PN = "1"  !CDS_PN = "1";
"B":   PN = "2"  !CDS_PN = "2";
BODY = "Q_RES","I41": #LOCATION = "R2370" !CDS_LOCATION = "R2370" &SEC = "1" #&CDS_SEC = "1";
"A":   PN = "1"  !CDS_PN = "1";
"B":   PN = "2"  !CDS_PN = "2";
BODY = "Q_RES","I44": #LOCATION = "R2368" !CDS_LOCATION = "R2368" &SEC = "1" #&CDS_SEC = "1";
"A":   PN = "1"  !CDS_PN = "1";
"B":   PN = "2"  !CDS_PN = "2";
BODY = "Q_RES","I48": #LOCATION = "R2591" !CDS_LOCATION = "R2591" &SEC = "1" #&CDS_SEC = "1";
"A":   PN = "1"  !CDS_PN = "1";
"B":   PN = "2"  !CDS_PN = "2";
BODY = "Q_CAP","I58": #LOCATION = "C3268" !CDS_LOCATION = "C3268" &SEC = "1" #&CDS_SEC = "1";
"A":   PN = "1"  !CDS_PN = "1";
"B":   PN = "2"  !CDS_PN = "2";
BODY = "Q_RES","I60": #LOCATION = "PR166" !CDS_LOCATION = "PR166" &SEC = "1" #&CDS_SEC = "1";
"A":   PN = "1"  !CDS_PN = "1";
"B":   PN = "2"  !CDS_PN = "2";
BODY = "Q_CAP","I61": #LOCATION = "PC330" !CDS_LOCATION = "PC330" &SEC = "1" #&CDS_SEC = "1";
"A":   PN = "1"  !CDS_PN = "1";
"B":   PN = "2"  !CDS_PN = "2";
BODY = "Q_CAP","I79": #LOCATION = "PC331" !CDS_LOCATION = "PC331" &SEC = "1" #&CDS_SEC = "1";
"A":   PN = "1"  !CDS_PN = "1";
"B":   PN = "2"  !CDS_PN = "2";
BODY = "Q_CAP","I86": #LOCATION = "PC335" !CDS_LOCATION = "PC335" &SEC = "1" #&CDS_SEC = "1";
"A":   PN = "1"  !CDS_PN = "1";
"B":   PN = "2"  !CDS_PN = "2";
BODY = "Q_RES","I123": #LOCATION = "R2382" !CDS_LOCATION = "R2382" &SEC = "1" #&CDS_SEC = "1";
"A":   PN = "1"  !CDS_PN = "1";
"B":   PN = "2"  !CDS_PN = "2";
BODY = "Q_RES","I8": #LOCATION = "PR171" !CDS_LOCATION = "PR171" &SEC = "1" #&CDS_SEC = "1";
"A":   PN = "1"  !CDS_PN = "1";
"B":   PN = "2"  !CDS_PN = "2";
BODY = "Q_RES","I23": #LOCATION = "R2373" !CDS_LOCATION = "R2373" &SEC = "1" #&CDS_SEC = "1";
"A":   PN = "1"  !CDS_PN = "1";
"B":   PN = "2"  !CDS_PN = "2";
BODY = "Q_RES","I25": #LOCATION = "PR587" !CDS_LOCATION = "PR587" &SEC = "1" #&CDS_SEC = "1";
"A":   PN = "1"  !CDS_PN = "1";
"B":   PN = "2"  !CDS_PN = "2";
BODY = "Q_RES","I26": #LOCATION = "PR527" !CDS_LOCATION = "PR527" &SEC = "1" #&CDS_SEC = "1";
"A":   PN = "1"  !CDS_PN = "1";
"B":   PN = "2"  !CDS_PN = "2";
BODY = "CONN3_210HP1030BR1","I32": #LOCATION = "PJP1" !CDS_LOCATION = "PJP1" #SEC = "1" !CDS_SEC = "1";
"1":   PN = "1"  !CDS_PN = "1";
"2":   PN = "2"  !CDS_PN = "2";
"3":   PN = "3"  !CDS_PN = "3";
BODY = "Q_RES","I42": #LOCATION = "R1712" !CDS_LOCATION = "R1712" &SEC = "1" #&CDS_SEC = "1";
"A":   PN = "1"  !CDS_PN = "1";
"B":   PN = "2"  !CDS_PN = "2";
BODY = "Q_RES","I43": #LOCATION = "R2369" !CDS_LOCATION = "R2369" &SEC = "1" #&CDS_SEC = "1";
"A":   PN = "1"  !CDS_PN = "1";
"B":   PN = "2"  !CDS_PN = "2";
BODY = "Q_CAP","I53": #LOCATION = "PC329" !CDS_LOCATION = "PC329" &SEC = "1" #&CDS_SEC = "1";
"A":   PN = "1"  !CDS_PN = "1";
"B":   PN = "2"  !CDS_PN = "2";
BODY = "Q_RES","I54": #LOCATION = "R2377" !CDS_LOCATION = "R2377" &SEC = "1" #&CDS_SEC = "1";
"A":   PN = "1"  !CDS_PN = "1";
"B":   PN = "2"  !CDS_PN = "2";
BODY = "Q_RES","I55": #LOCATION = "R2379" !CDS_LOCATION = "R2379" &SEC = "1" #&CDS_SEC = "1";
"A":   PN = "1"  !CDS_PN = "1";
"B":   PN = "2"  !CDS_PN = "2";
BODY = "Q_RES","I56": LOCATION = "R4216" #&CDS_LOCATION = "R4216" &SEC = "1" #&CDS_SEC = "1";
"A":   PN = "1"  !CDS_PN = "1";
"B":   PN = "2"  !CDS_PN = "2";
BODY = "Q_CAP","I57": #LOCATION = "C3269" !CDS_LOCATION = "C3269" &SEC = "1" #&CDS_SEC = "1";
"A":   PN = "1"  !CDS_PN = "1";
"B":   PN = "2"  !CDS_PN = "2";
BODY = "Q_RES","I68": #LOCATION = "PR345" !CDS_LOCATION = "PR345" &SEC = "1" #&CDS_SEC = "1";
"A":   PN = "1"  !CDS_PN = "1";
"B":   PN = "2"  !CDS_PN = "2";
BODY = "Q_CAP","I70": #LOCATION = "PC336" !CDS_LOCATION = "PC336" &SEC = "1" #&CDS_SEC = "1";
"A":   PN = "1"  !CDS_PN = "1";
"B":   PN = "2"  !CDS_PN = "2";
BODY = "Q_RES","I72": #LOCATION = "PR400" !CDS_LOCATION = "PR400" &SEC = "1" #&CDS_SEC = "1";
"A":   PN = "1"  !CDS_PN = "1";
"B":   PN = "2"  !CDS_PN = "2";
BODY = "Q_RES","I73": #LOCATION = "PR4218" !CDS_LOCATION = "PR4218" &SEC = "1" #&CDS_SEC = "1";
"A":   PN = "1"  !CDS_PN = "1";
"B":   PN = "2"  !CDS_PN = "2";
BODY = "Q_RES","I77": #LOCATION = "PR170" !CDS_LOCATION = "PR170" &SEC = "1" #&CDS_SEC = "1";
"A":   PN = "1"  !CDS_PN = "1";
"B":   PN = "2"  !CDS_PN = "2";
BODY = "Q_RES","I78": #LOCATION = "R2372" !CDS_LOCATION = "R2372" &SEC = "1" #&CDS_SEC = "1";
"A":   PN = "1"  !CDS_PN = "1";
"B":   PN = "2"  !CDS_PN = "2";
BODY = "Q_RES","I80": #LOCATION = "R2371" !CDS_LOCATION = "R2371" &SEC = "1" #&CDS_SEC = "1";
"A":   PN = "1"  !CDS_PN = "1";
"B":   PN = "2"  !CDS_PN = "2";
BODY = "Q_CAP","I82": #LOCATION = "C3267" !CDS_LOCATION = "C3267" &SEC = "1" #&CDS_SEC = "1";
"A":   PN = "1"  !CDS_PN = "1";
"B":   PN = "2"  !CDS_PN = "2";
BODY = "Q_CAP","I84": #LOCATION = "C3266" !CDS_LOCATION = "C3266" &SEC = "1" #&CDS_SEC = "1";
"A":   PN = "1"  !CDS_PN = "1";
"B":   PN = "2"  !CDS_PN = "2";
BODY = "Q_CAP","I87": #LOCATION = "PC1173" !CDS_LOCATION = "PC1173" &SEC = "1" #&CDS_SEC = "1";
"A":   PN = "1"  !CDS_PN = "1";
"B":   PN = "2"  !CDS_PN = "2";
BODY = "Q_CAP","I88": #LOCATION = "PC334" !CDS_LOCATION = "PC334" &SEC = "1" #&CDS_SEC = "1";
"A":   PN = "1"  !CDS_PN = "1";
"B":   PN = "2"  !CDS_PN = "2";
BODY = "Q_CAP","I89": #LOCATION = "PC337" !CDS_LOCATION = "PC337" &SEC = "1" #&CDS_SEC = "1";
"A":   PN = "1"  !CDS_PN = "1";
"B":   PN = "2"  !CDS_PN = "2";
BODY = "Q_CAP","I116": #LOCATION = "PC100" !CDS_LOCATION = "PC100" &SEC = "1" #&CDS_SEC = "1";
"A":   PN = "1"  !CDS_PN = "1";
"B":   PN = "2"  !CDS_PN = "2";
BODY = "Q_RES","I121": #LOCATION = "PR451" !CDS_LOCATION = "PR451" &SEC = "1" #&CDS_SEC = "1";
"A":   PN = "1"  !CDS_PN = "1";
"B":   PN = "2"  !CDS_PN = "2";
BODY = "Q_RES","I124": #LOCATION = "R2590" !CDS_LOCATION = "R2590" &SEC = "1" #&CDS_SEC = "1";
"A":   PN = "1"  !CDS_PN = "1";
"B":   PN = "2"  !CDS_PN = "2";
BODY = "Q_RES","I125": #LOCATION = "R2381" !CDS_LOCATION = "R2381" &SEC = "1" #&CDS_SEC = "1";
"A":   PN = "1"  !CDS_PN = "1";
"B":   PN = "2"  !CDS_PN = "2";
BODY = "Q_CAP","I127": #LOCATION = "C3270" !CDS_LOCATION = "C3270" &SEC = "1" #&CDS_SEC = "1";
"A":   PN = "1"  !CDS_PN = "1";
"B":   PN = "2"  !CDS_PN = "2";
BODY = "Q_CAP","I128": #LOCATION = "C3271" !CDS_LOCATION = "C3271" &SEC = "1" #&CDS_SEC = "1";
"A":   PN = "1"  !CDS_PN = "1";
"B":   PN = "2"  !CDS_PN = "2";
BODY = "Q_CAP","I136": #LOCATION = "PC2361" !CDS_LOCATION = "PC2361" &SEC = "1" #&CDS_SEC = "1";
"A":   PN = "1"  !CDS_PN = "1";
"B":   PN = "2"  !CDS_PN = "2";
DRAWING = "@s9s_mb_2u_lib.s9s_mb_2u(sch_1):page253";
BODY = "Q_CAP","I11": #LOCATION = "PC1355" !CDS_LOCATION = "PC1355" &SEC = "1" #&CDS_SEC = "1";
"A":   PN = "1"  !CDS_PN = "1";
"B":   PN = "2"  !CDS_PN = "2";
BODY = "Q_CAP","I22": #LOCATION = "PC298_P0_2" !CDS_LOCATION = "PC298_P0_2" &SEC = "1" #&CDS_SEC = "1";
"A":   PN = "1"  !CDS_PN = "1";
"B":   PN = "2"  !CDS_PN = "2";
BODY = "Q_CAP","I24": #LOCATION = "PC304_P0_2" !CDS_LOCATION = "PC304_P0_2" &SEC = "1" #&CDS_SEC = "1";
"A":   PN = "1"  !CDS_PN = "1";
"B":   PN = "2"  !CDS_PN = "2";
BODY = "Q_CAP","I36": #LOCATION = "PC293" !CDS_LOCATION = "PC293" &SEC = "1" #&CDS_SEC = "1";
"A":   PN = "1"  !CDS_PN = "1";
"B":   PN = "2"  !CDS_PN = "2";
BODY = "Q_CAP","I39": #LOCATION = "PC295_P0_1" !CDS_LOCATION = "PC295_P0_1" &SEC = "1" #&CDS_SEC = "1";
"A":   PN = "1"  !CDS_PN = "1";
"B":   PN = "2"  !CDS_PN = "2";
BODY = "ISL99390FRZTR5935","I40": #LOCATION = "PU13_P0_1" !CDS_LOCATION = "PU13_P0_1" &SEC = "1" #&CDS_SEC = "1";
"AGND":   PN = "2"  !CDS_PN = "2";
"BOOT":   PN = "33"  !CDS_PN = "33";
"DNC":   PN = "31"  !CDS_PN = "31";
"EN":   PN = "35"  !CDS_PN = "35";
"GL1":   PN = "6"  !CDS_PN = "6";
"GL2":   PN = "41"  !CDS_PN = "41";
"IOUT":   PN = "38"  !CDS_PN = "38";
"LSET":   PN = "37"  !CDS_PN = "37";
"PGND1":   PN = "5"  !CDS_PN = "5";
"PGND2":   PN = "7_9-20_24"  !CDS_PN = "7_9-20_24";
"PGND3":   PN = "40"  !CDS_PN = "40";
"PHASE":   PN = "32"  !CDS_PN = "32";
"PVCC":   PN = "4"  !CDS_PN = "4";
"PWM":   PN = "34"  !CDS_PN = "34";
"REFIN":   PN = "39"  !CDS_PN = "39";
"SW":   PN = "10_19"  !CDS_PN = "10_19";
"TOUT_FLT":   PN = "36"  !CDS_PN = "36";
"VCC":   PN = "3"  !CDS_PN = "3";
"VIN1":   PN = "25_29"  !CDS_PN = "25_29";
"VIN2":   PN = "30"  !CDS_PN = "30";
"VOS":   PN = "1"  !CDS_PN = "1";
BODY = "Q_INDUCTOR4P_14","I46": #LOCATION = "PL114" !CDS_LOCATION = "PL114" #SEC = "1" !CDS_SEC = "1";
"1":   PN = "1"  !CDS_PN = "1";
"2":   PN = "2"  !CDS_PN = "2";
"3":   PN = "3"  !CDS_PN = "3";
"4":   PN = "4"  !CDS_PN = "4";
BODY = "Q_CAP","I54": #LOCATION = "PC306_P0_2" !CDS_LOCATION = "PC306_P0_2" &SEC = "1" #&CDS_SEC = "1";
"A":   PN = "1"  !CDS_PN = "1";
"B":   PN = "2"  !CDS_PN = "2";
BODY = "Q_CAPP","I56": #LOCATION = "PC16" !CDS_LOCATION = "PC16" &SEC = "1" #&CDS_SEC = "1";
"A":   PN = "1"  !CDS_PN = "1";
"B":   PN = "2"  !CDS_PN = "2";
BODY = "Q_CAPP","I62": #LOCATION = "PC319" !CDS_LOCATION = "PC319" &SEC = "1" #&CDS_SEC = "1";
"A":   PN = "1"  !CDS_PN = "1";
"B":   PN = "2"  !CDS_PN = "2";
BODY = "Q_CAP","I84": #LOCATION = "PC310_P0_1" !CDS_LOCATION = "PC310_P0_1" &SEC = "1" #&CDS_SEC = "1";
"A":   PN = "1"  !CDS_PN = "1";
"B":   PN = "2"  !CDS_PN = "2";
BODY = "Q_RES","I37": #LOCATION = "PR153" !CDS_LOCATION = "PR153" &SEC = "1" #&CDS_SEC = "1";
"A":   PN = "1"  !CDS_PN = "1";
"B":   PN = "2"  !CDS_PN = "2";
BODY = "Q_CAP","I48": #LOCATION = "PC301" !CDS_LOCATION = "PC301" &SEC = "1" #&CDS_SEC = "1";
"A":   PN = "1"  !CDS_PN = "1";
"B":   PN = "2"  !CDS_PN = "2";
BODY = "Q_CAP","I50": #LOCATION = "PC305_P0_1" !CDS_LOCATION = "PC305_P0_1" &SEC = "1" #&CDS_SEC = "1";
"A":   PN = "1"  !CDS_PN = "1";
"B":   PN = "2"  !CDS_PN = "2";
BODY = "Q_RES","I51": #LOCATION = "PR154" !CDS_LOCATION = "PR154" &SEC = "1" #&CDS_SEC = "1";
"A":   PN = "1"  !CDS_PN = "1";
"B":   PN = "2"  !CDS_PN = "2";
BODY = "Q_CAPP","I61": #LOCATION = "PC316" !CDS_LOCATION = "PC316" &SEC = "1" #&CDS_SEC = "1";
"A":   PN = "1"  !CDS_PN = "1";
"B":   PN = "2"  !CDS_PN = "2";
BODY = "Q_CAPP","I64": #LOCATION = "PC323" !CDS_LOCATION = "PC323" &SEC = "1" #&CDS_SEC = "1";
"A":   PN = "1"  !CDS_PN = "1";
"B":   PN = "2"  !CDS_PN = "2";
BODY = "Q_CAPP","I70": #LOCATION = "PC325" !CDS_LOCATION = "PC325" &SEC = "1" #&CDS_SEC = "1";
"A":   PN = "1"  !CDS_PN = "1";
"B":   PN = "2"  !CDS_PN = "2";
BODY = "Q_RES","I73": #LOCATION = "PR155" !CDS_LOCATION = "PR155" &SEC = "1" #&CDS_SEC = "1";
"A":   PN = "1"  !CDS_PN = "1";
"B":   PN = "2"  !CDS_PN = "2";
BODY = "Q_CAP","I86": #LOCATION = "PC314_P0_1" !CDS_LOCATION = "PC314_P0_1" &SEC = "1" #&CDS_SEC = "1";
"A":   PN = "1"  !CDS_PN = "1";
"B":   PN = "2"  !CDS_PN = "2";
BODY = "Q_CAPP","I91": #LOCATION = "PC315" !CDS_LOCATION = "PC315" &SEC = "1" #&CDS_SEC = "1";
"A":   PN = "1"  !CDS_PN = "1";
"B":   PN = "2"  !CDS_PN = "2";
BODY = "Q_CAPP","I92": #LOCATION = "PC318" !CDS_LOCATION = "PC318" &SEC = "1" #&CDS_SEC = "1";
"A":   PN = "1"  !CDS_PN = "1";
"B":   PN = "2"  !CDS_PN = "2";
BODY = "Q_CAPP","I95": #LOCATION = "PC2345" !CDS_LOCATION = "PC2345" &SEC = "1" #&CDS_SEC = "1";
"A":   PN = "1"  !CDS_PN = "1";
"B":   PN = "2"  !CDS_PN = "2";
BODY = "Q_RES","I2": #LOCATION = "PR150" !CDS_LOCATION = "PR150" &SEC = "1" #&CDS_SEC = "1";
"A":   PN = "1"  !CDS_PN = "1";
"B":   PN = "2"  !CDS_PN = "2";
BODY = "Q_CAP","I19": #LOCATION = "PC296_P0_2" !CDS_LOCATION = "PC296_P0_2" &SEC = "1" #&CDS_SEC = "1";
"A":   PN = "1"  !CDS_PN = "1";
"B":   PN = "2"  !CDS_PN = "2";
BODY = "Q_INDUCTOR4P_14","I21": #LOCATION = "PL13" !CDS_LOCATION = "PL13" #SEC = "1" !CDS_SEC = "1";
"1":   PN = "1"  !CDS_PN = "1";
"2":   PN = "2"  !CDS_PN = "2";
"3":   PN = "3"  !CDS_PN = "3";
"4":   PN = "4"  !CDS_PN = "4";
BODY = "Q_RES","I26": #LOCATION = "PR402" !CDS_LOCATION = "PR402" &SEC = "1" #&CDS_SEC = "1";
"A":   PN = "1"  !CDS_PN = "1";
"B":   PN = "2"  !CDS_PN = "2";
BODY = "Q_CAP","I34": #LOCATION = "PC1356" !CDS_LOCATION = "PC1356" &SEC = "1" #&CDS_SEC = "1";
"A":   PN = "1"  !CDS_PN = "1";
"B":   PN = "2"  !CDS_PN = "2";
BODY = "Q_CAP","I49": #LOCATION = "PC303_P0_1" !CDS_LOCATION = "PC303_P0_1" &SEC = "1" #&CDS_SEC = "1";
"A":   PN = "1"  !CDS_PN = "1";
"B":   PN = "2"  !CDS_PN = "2";
BODY = "Q_RES","I59": #LOCATION = "PR4219" !CDS_LOCATION = "PR4219" &SEC = "1" #&CDS_SEC = "1";
"A":   PN = "1"  !CDS_PN = "1";
"B":   PN = "2"  !CDS_PN = "2";
BODY = "Q_CAPP","I63": #LOCATION = "PC1920" !CDS_LOCATION = "PC1920" &SEC = "1" #&CDS_SEC = "1";
"A":   PN = "1"  !CDS_PN = "1";
"B":   PN = "2"  !CDS_PN = "2";
BODY = "Q_CAPP","I66": #LOCATION = "PC326" !CDS_LOCATION = "PC326" &SEC = "1" #&CDS_SEC = "1";
"A":   PN = "1"  !CDS_PN = "1";
"B":   PN = "2"  !CDS_PN = "2";
BODY = "Q_CAPP","I67": #LOCATION = "PC322" !CDS_LOCATION = "PC322" &SEC = "1" #&CDS_SEC = "1";
"A":   PN = "1"  !CDS_PN = "1";
"B":   PN = "2"  !CDS_PN = "2";
BODY = "Q_CAP","I75": #LOCATION = "PC307_P0_1" !CDS_LOCATION = "PC307_P0_1" &SEC = "1" #&CDS_SEC = "1";
"A":   PN = "1"  !CDS_PN = "1";
"B":   PN = "2"  !CDS_PN = "2";
BODY = "Q_RES","I81": #LOCATION = "PR2554" !CDS_LOCATION = "PR2554" &SEC = "1" #&CDS_SEC = "1";
"A":   PN = "1"  !CDS_PN = "1";
"B":   PN = "2"  !CDS_PN = "2";
BODY = "ISL99390FRZTR5935","I6": #LOCATION = "PU12_P0_2" !CDS_LOCATION = "PU12_P0_2" #SEC = "1" !CDS_SEC = "1";
"AGND":   PN = "2"  !CDS_PN = "2";
"BOOT":   PN = "33"  !CDS_PN = "33";
"DNC":   PN = "31"  !CDS_PN = "31";
"EN":   PN = "35"  !CDS_PN = "35";
"GL1":   PN = "6"  !CDS_PN = "6";
"GL2":   PN = "41"  !CDS_PN = "41";
"IOUT":   PN = "38"  !CDS_PN = "38";
"LSET":   PN = "37"  !CDS_PN = "37";
"PGND1":   PN = "5"  !CDS_PN = "5";
"PGND2":   PN = "7_9-20_24"  !CDS_PN = "7_9-20_24";
"PGND3":   PN = "40"  !CDS_PN = "40";
"PHASE":   PN = "32"  !CDS_PN = "32";
"PVCC":   PN = "4"  !CDS_PN = "4";
"PWM":   PN = "34"  !CDS_PN = "34";
"REFIN":   PN = "39"  !CDS_PN = "39";
"SW":   PN = "10_19"  !CDS_PN = "10_19";
"TOUT_FLT":   PN = "36"  !CDS_PN = "36";
"VCC":   PN = "3"  !CDS_PN = "3";
"VIN1":   PN = "25_29"  !CDS_PN = "25_29";
"VIN2":   PN = "30"  !CDS_PN = "30";
"VOS":   PN = "1"  !CDS_PN = "1";
BODY = "Q_CAP","I9": #LOCATION = "PC292" !CDS_LOCATION = "PC292" &SEC = "1" #&CDS_SEC = "1";
"A":   PN = "1"  !CDS_PN = "1";
"B":   PN = "2"  !CDS_PN = "2";
BODY = "Q_RES","I12": #LOCATION = "PR152" !CDS_LOCATION = "PR152" &SEC = "1" #&CDS_SEC = "1";
"A":   PN = "1"  !CDS_PN = "1";
"B":   PN = "2"  !CDS_PN = "2";
BODY = "Q_CAP","I15": #LOCATION = "PC294_P0_2" !CDS_LOCATION = "PC294_P0_2" &SEC = "1" #&CDS_SEC = "1";
"A":   PN = "1"  !CDS_PN = "1";
"B":   PN = "2"  !CDS_PN = "2";
BODY = "Q_RES","I18": #LOCATION = "PR1786" !CDS_LOCATION = "PR1786" &SEC = "1" #&CDS_SEC = "1";
"A":   PN = "1"  !CDS_PN = "1";
"B":   PN = "2"  !CDS_PN = "2";
BODY = "Q_CAP","I20": #LOCATION = "PC300" !CDS_LOCATION = "PC300" &SEC = "1" #&CDS_SEC = "1";
"A":   PN = "1"  !CDS_PN = "1";
"B":   PN = "2"  !CDS_PN = "2";
BODY = "Q_CAP","I23": #LOCATION = "PC302_P0_2" !CDS_LOCATION = "PC302_P0_2" &SEC = "1" #&CDS_SEC = "1";
"A":   PN = "1"  !CDS_PN = "1";
"B":   PN = "2"  !CDS_PN = "2";
BODY = "Q_RES","I29": #LOCATION = "PR151" !CDS_LOCATION = "PR151" &SEC = "1" #&CDS_SEC = "1";
"A":   PN = "1"  !CDS_PN = "1";
"B":   PN = "2"  !CDS_PN = "2";
BODY = "Q_RES","I42": #LOCATION = "PR403" !CDS_LOCATION = "PR403" &SEC = "1" #&CDS_SEC = "1";
"A":   PN = "1"  !CDS_PN = "1";
"B":   PN = "2"  !CDS_PN = "2";
BODY = "Q_CAP","I44": #LOCATION = "PC297_P0_1" !CDS_LOCATION = "PC297_P0_1" &SEC = "1" #&CDS_SEC = "1";
"A":   PN = "1"  !CDS_PN = "1";
"B":   PN = "2"  !CDS_PN = "2";
BODY = "Q_CAP","I47": #LOCATION = "PC299_P0_1" !CDS_LOCATION = "PC299_P0_1" &SEC = "1" #&CDS_SEC = "1";
"A":   PN = "1"  !CDS_PN = "1";
"B":   PN = "2"  !CDS_PN = "2";
BODY = "Q_CAP","I57": #LOCATION = "PC311_P0_2" !CDS_LOCATION = "PC311_P0_2" &SEC = "1" #&CDS_SEC = "1";
"A":   PN = "1"  !CDS_PN = "1";
"B":   PN = "2"  !CDS_PN = "2";
BODY = "Q_CAP","I58": #LOCATION = "PC313_P0_2" !CDS_LOCATION = "PC313_P0_2" &SEC = "1" #&CDS_SEC = "1";
"A":   PN = "1"  !CDS_PN = "1";
"B":   PN = "2"  !CDS_PN = "2";
BODY = "Q_CAPP","I60": #LOCATION = "PC2336" !CDS_LOCATION = "PC2336" &SEC = "1" #&CDS_SEC = "1";
"A":   PN = "1"  !CDS_PN = "1";
"B":   PN = "2"  !CDS_PN = "2";
BODY = "Q_CAP","I80": #LOCATION = "PC1652" !CDS_LOCATION = "PC1652" &SEC = "1" #&CDS_SEC = "1";
"A":   PN = "1"  !CDS_PN = "1";
"B":   PN = "2"  !CDS_PN = "2";
BODY = "Q_INDUCTOR","I82": #LOCATION = "PL15" !CDS_LOCATION = "PL15" &SEC = "1" #&CDS_SEC = "1";
"1":   PN = "1"  !CDS_PN = "1";
"2":   PN = "2"  !CDS_PN = "2";
BODY = "Q_CAP","I83": #LOCATION = "PC308_P0_1" !CDS_LOCATION = "PC308_P0_1" &SEC = "1" #&CDS_SEC = "1";
"A":   PN = "1"  !CDS_PN = "1";
"B":   PN = "2"  !CDS_PN = "2";
BODY = "Q_CAP","I85": #LOCATION = "PC312_P0_1" !CDS_LOCATION = "PC312_P0_1" &SEC = "1" #&CDS_SEC = "1";
"A":   PN = "1"  !CDS_PN = "1";
"B":   PN = "2"  !CDS_PN = "2";
BODY = "Q_CAPP","I93": #LOCATION = "PC321" !CDS_LOCATION = "PC321" &SEC = "1" #&CDS_SEC = "1";
"A":   PN = "1"  !CDS_PN = "1";
"B":   PN = "2"  !CDS_PN = "2";
BODY = "Q_CAPP","I94": #LOCATION = "PC324" !CDS_LOCATION = "PC324" &SEC = "1" #&CDS_SEC = "1";
"A":   PN = "1"  !CDS_PN = "1";
"B":   PN = "2"  !CDS_PN = "2";
BODY = "Q_RES","I97": #LOCATION = "PR1787" !CDS_LOCATION = "PR1787" &SEC = "1" #&CDS_SEC = "1";
"A":   PN = "1"  !CDS_PN = "1";
"B":   PN = "2"  !CDS_PN = "2";
DRAWING = "@s9s_mb_2u_lib.s9s_mb_2u(sch_1):page254";
BODY = "Q_RES","I2": #LOCATION = "PR144" !CDS_LOCATION = "PR144" &SEC = "1" #&CDS_SEC = "1";
"A":   PN = "1"  !CDS_PN = "1";
"B":   PN = "2"  !CDS_PN = "2";
BODY = "ISL99390FRZTR5935","I13": #LOCATION = "PU10_P0_4" !CDS_LOCATION = "PU10_P0_4" &SEC = "1" #&CDS_SEC = "1";
"AGND":   PN = "2"  !CDS_PN = "2";
"BOOT":   PN = "33"  !CDS_PN = "33";
"DNC":   PN = "31"  !CDS_PN = "31";
"EN":   PN = "35"  !CDS_PN = "35";
"GL1":   PN = "6"  !CDS_PN = "6";
"GL2":   PN = "41"  !CDS_PN = "41";
"IOUT":   PN = "38"  !CDS_PN = "38";
"LSET":   PN = "37"  !CDS_PN = "37";
"PGND1":   PN = "5"  !CDS_PN = "5";
"PGND2":   PN = "7_9-20_24"  !CDS_PN = "7_9-20_24";
"PGND3":   PN = "40"  !CDS_PN = "40";
"PHASE":   PN = "32"  !CDS_PN = "32";
"PVCC":   PN = "4"  !CDS_PN = "4";
"PWM":   PN = "34"  !CDS_PN = "34";
"REFIN":   PN = "39"  !CDS_PN = "39";
"SW":   PN = "10_19"  !CDS_PN = "10_19";
"TOUT_FLT":   PN = "36"  !CDS_PN = "36";
"VCC":   PN = "3"  !CDS_PN = "3";
"VIN1":   PN = "25_29"  !CDS_PN = "25_29";
"VIN2":   PN = "30"  !CDS_PN = "30";
"VOS":   PN = "1"  !CDS_PN = "1";
BODY = "Q_RES","I14": #LOCATION = "PR146" !CDS_LOCATION = "PR146" &SEC = "1" #&CDS_SEC = "1";
"A":   PN = "1"  !CDS_PN = "1";
"B":   PN = "2"  !CDS_PN = "2";
BODY = "Q_CAP","I17": #LOCATION = "PC272_P0_4" !CDS_LOCATION = "PC272_P0_4" &SEC = "1" #&CDS_SEC = "1";
"A":   PN = "1"  !CDS_PN = "1";
"B":   PN = "2"  !CDS_PN = "2";
BODY = "Q_CAP","I26": #LOCATION = "PC1341" !CDS_LOCATION = "PC1341" &SEC = "1" #&CDS_SEC = "1";
"A":   PN = "1"  !CDS_PN = "1";
"B":   PN = "2"  !CDS_PN = "2";
BODY = "Q_RES","I27": #LOCATION = "PR147" !CDS_LOCATION = "PR147" &SEC = "1" #&CDS_SEC = "1";
"A":   PN = "1"  !CDS_PN = "1";
"B":   PN = "2"  !CDS_PN = "2";
BODY = "Q_CAP","I30": #LOCATION = "PC273_P0_3" !CDS_LOCATION = "PC273_P0_3" &SEC = "1" #&CDS_SEC = "1";
"A":   PN = "1"  !CDS_PN = "1";
"B":   PN = "2"  !CDS_PN = "2";
BODY = "Q_CAP","I35": #LOCATION = "PC274_P0_4" !CDS_LOCATION = "PC274_P0_4" &SEC = "1" #&CDS_SEC = "1";
"A":   PN = "1"  !CDS_PN = "1";
"B":   PN = "2"  !CDS_PN = "2";
BODY = "Q_RES","I36": #LOCATION = "PR1768" !CDS_LOCATION = "PR1768" &SEC = "1" #&CDS_SEC = "1";
"A":   PN = "1"  !CDS_PN = "1";
"B":   PN = "2"  !CDS_PN = "2";
BODY = "Q_CAP","I38": #LOCATION = "PC276_P0_4" !CDS_LOCATION = "PC276_P0_4" &SEC = "1" #&CDS_SEC = "1";
"A":   PN = "1"  !CDS_PN = "1";
"B":   PN = "2"  !CDS_PN = "2";
BODY = "Q_CAP","I39": #LOCATION = "PC280_P0_4" !CDS_LOCATION = "PC280_P0_4" &SEC = "1" #&CDS_SEC = "1";
"A":   PN = "1"  !CDS_PN = "1";
"B":   PN = "2"  !CDS_PN = "2";
BODY = "Q_CAP","I40": #LOCATION = "PC282_P0_4" !CDS_LOCATION = "PC282_P0_4" &SEC = "1" #&CDS_SEC = "1";
"A":   PN = "1"  !CDS_PN = "1";
"B":   PN = "2"  !CDS_PN = "2";
BODY = "Q_CAP","I48": #LOCATION = "PC275_P0_3" !CDS_LOCATION = "PC275_P0_3" &SEC = "1" #&CDS_SEC = "1";
"A":   PN = "1"  !CDS_PN = "1";
"B":   PN = "2"  !CDS_PN = "2";
BODY = "Q_RES","I49": #LOCATION = "PR1769" !CDS_LOCATION = "PR1769" &SEC = "1" #&CDS_SEC = "1";
"A":   PN = "1"  !CDS_PN = "1";
"B":   PN = "2"  !CDS_PN = "2";
BODY = "Q_INDUCTOR4P_14","I50": #LOCATION = "PL112" !CDS_LOCATION = "PL112" #SEC = "1" !CDS_SEC = "1";
"1":   PN = "1"  !CDS_PN = "1";
"2":   PN = "2"  !CDS_PN = "2";
"3":   PN = "3"  !CDS_PN = "3";
"4":   PN = "4"  !CDS_PN = "4";
BODY = "Q_CAP","I51": #LOCATION = "PC279" !CDS_LOCATION = "PC279" &SEC = "1" #&CDS_SEC = "1";
"A":   PN = "1"  !CDS_PN = "1";
"B":   PN = "2"  !CDS_PN = "2";
BODY = "Q_CAP","I53": #LOCATION = "PC281_P0_3" !CDS_LOCATION = "PC281_P0_3" &SEC = "1" #&CDS_SEC = "1";
"A":   PN = "1"  !CDS_PN = "1";
"B":   PN = "2"  !CDS_PN = "2";
BODY = "Q_CAP","I56": #LOCATION = "PC285_P0_3" !CDS_LOCATION = "PC285_P0_3" &SEC = "1" #&CDS_SEC = "1";
"A":   PN = "1"  !CDS_PN = "1";
"B":   PN = "2"  !CDS_PN = "2";
BODY = "Q_RES","I4": #LOCATION = "PR145" !CDS_LOCATION = "PR145" &SEC = "1" #&CDS_SEC = "1";
"A":   PN = "1"  !CDS_PN = "1";
"B":   PN = "2"  !CDS_PN = "2";
BODY = "Q_CAP","I11": #LOCATION = "PC270" !CDS_LOCATION = "PC270" &SEC = "1" #&CDS_SEC = "1";
"A":   PN = "1"  !CDS_PN = "1";
"B":   PN = "2"  !CDS_PN = "2";
BODY = "Q_CAP","I12": #LOCATION = "PC1340" !CDS_LOCATION = "PC1340" &SEC = "1" #&CDS_SEC = "1";
"A":   PN = "1"  !CDS_PN = "1";
"B":   PN = "2"  !CDS_PN = "2";
BODY = "ISL99390FRZTR5935","I20": #LOCATION = "PU11_P0_3" !CDS_LOCATION = "PU11_P0_3" &SEC = "1" #&CDS_SEC = "1";
"AGND":   PN = "2"  !CDS_PN = "2";
"BOOT":   PN = "33"  !CDS_PN = "33";
"DNC":   PN = "31"  !CDS_PN = "31";
"EN":   PN = "35"  !CDS_PN = "35";
"GL1":   PN = "6"  !CDS_PN = "6";
"GL2":   PN = "41"  !CDS_PN = "41";
"IOUT":   PN = "38"  !CDS_PN = "38";
"LSET":   PN = "37"  !CDS_PN = "37";
"PGND1":   PN = "5"  !CDS_PN = "5";
"PGND2":   PN = "7_9-20_24"  !CDS_PN = "7_9-20_24";
"PGND3":   PN = "40"  !CDS_PN = "40";
"PHASE":   PN = "32"  !CDS_PN = "32";
"PVCC":   PN = "4"  !CDS_PN = "4";
"PWM":   PN = "34"  !CDS_PN = "34";
"REFIN":   PN = "39"  !CDS_PN = "39";
"SW":   PN = "10_19"  !CDS_PN = "10_19";
"TOUT_FLT":   PN = "36"  !CDS_PN = "36";
"VCC":   PN = "3"  !CDS_PN = "3";
"VIN1":   PN = "25_29"  !CDS_PN = "25_29";
"VIN2":   PN = "30"  !CDS_PN = "30";
"VOS":   PN = "1"  !CDS_PN = "1";
BODY = "Q_CAP","I25": #LOCATION = "PC271" !CDS_LOCATION = "PC271" &SEC = "1" #&CDS_SEC = "1";
"A":   PN = "1"  !CDS_PN = "1";
"B":   PN = "2"  !CDS_PN = "2";
BODY = "Q_INDUCTOR4P_14","I33": #LOCATION = "PL11" !CDS_LOCATION = "PL11" #SEC = "1" !CDS_SEC = "1";
"1":   PN = "1"  !CDS_PN = "1";
"2":   PN = "2"  !CDS_PN = "2";
"3":   PN = "3"  !CDS_PN = "3";
"4":   PN = "4"  !CDS_PN = "4";
BODY = "Q_CAP","I34": #LOCATION = "PC278" !CDS_LOCATION = "PC278" &SEC = "1" #&CDS_SEC = "1";
"A":   PN = "1"  !CDS_PN = "1";
"B":   PN = "2"  !CDS_PN = "2";
BODY = "Q_RES","I41": #LOCATION = "PR148" !CDS_LOCATION = "PR148" &SEC = "1" #&CDS_SEC = "1";
"A":   PN = "1"  !CDS_PN = "1";
"B":   PN = "2"  !CDS_PN = "2";
BODY = "Q_CAP","I43": #LOCATION = "PC284_P0_4" !CDS_LOCATION = "PC284_P0_4" &SEC = "1" #&CDS_SEC = "1";
"A":   PN = "1"  !CDS_PN = "1";
"B":   PN = "2"  !CDS_PN = "2";
BODY = "Q_RES","I46": #LOCATION = "PR149" !CDS_LOCATION = "PR149" &SEC = "1" #&CDS_SEC = "1";
"A":   PN = "1"  !CDS_PN = "1";
"B":   PN = "2"  !CDS_PN = "2";
BODY = "Q_CAP","I52": #LOCATION = "PC277_P0_3" !CDS_LOCATION = "PC277_P0_3" &SEC = "1" #&CDS_SEC = "1";
"A":   PN = "1"  !CDS_PN = "1";
"B":   PN = "2"  !CDS_PN = "2";
BODY = "Q_CAP","I54": #LOCATION = "PC283_P0_3" !CDS_LOCATION = "PC283_P0_3" &SEC = "1" #&CDS_SEC = "1";
"A":   PN = "1"  !CDS_PN = "1";
"B":   PN = "2"  !CDS_PN = "2";
BODY = "Q_CAP","I59": #LOCATION = "PC289_P0_3" !CDS_LOCATION = "PC289_P0_3" &SEC = "1" #&CDS_SEC = "1";
"A":   PN = "1"  !CDS_PN = "1";
"B":   PN = "2"  !CDS_PN = "2";
BODY = "Q_CAP","I60": #LOCATION = "PC288_P0_4" !CDS_LOCATION = "PC288_P0_4" &SEC = "1" #&CDS_SEC = "1";
"A":   PN = "1"  !CDS_PN = "1";
"B":   PN = "2"  !CDS_PN = "2";
BODY = "Q_CAP","I61": #LOCATION = "PC290_P0_4" !CDS_LOCATION = "PC290_P0_4" &SEC = "1" #&CDS_SEC = "1";
"A":   PN = "1"  !CDS_PN = "1";
"B":   PN = "2"  !CDS_PN = "2";
BODY = "Q_CAP","I65": #LOCATION = "PC291_P0_3" !CDS_LOCATION = "PC291_P0_3" &SEC = "1" #&CDS_SEC = "1";
"A":   PN = "1"  !CDS_PN = "1";
"B":   PN = "2"  !CDS_PN = "2";
DRAWING = "@s9s_mb_2u_lib.s9s_mb_2u(sch_1):page255";
BODY = "Q_RES","I2": #LOCATION = "PR138" !CDS_LOCATION = "PR138" &SEC = "1" #&CDS_SEC = "1";
"A":   PN = "1"  !CDS_PN = "1";
"B":   PN = "2"  !CDS_PN = "2";
BODY = "Q_CAP","I11": #LOCATION = "PC1342" !CDS_LOCATION = "PC1342" &SEC = "1" #&CDS_SEC = "1";
"A":   PN = "1"  !CDS_PN = "1";
"B":   PN = "2"  !CDS_PN = "2";
BODY = "ISL99390FRZTR5935","I12": #LOCATION = "PU8_P0_6" !CDS_LOCATION = "PU8_P0_6" #SEC = "1" !CDS_SEC = "1";
"AGND":   PN = "2"  !CDS_PN = "2";
"BOOT":   PN = "33"  !CDS_PN = "33";
"DNC":   PN = "31"  !CDS_PN = "31";
"EN":   PN = "35"  !CDS_PN = "35";
"GL1":   PN = "6"  !CDS_PN = "6";
"GL2":   PN = "41"  !CDS_PN = "41";
"IOUT":   PN = "38"  !CDS_PN = "38";
"LSET":   PN = "37"  !CDS_PN = "37";
"PGND1":   PN = "5"  !CDS_PN = "5";
"PGND2":   PN = "7_9-20_24"  !CDS_PN = "7_9-20_24";
"PGND3":   PN = "40"  !CDS_PN = "40";
"PHASE":   PN = "32"  !CDS_PN = "32";
"PVCC":   PN = "4"  !CDS_PN = "4";
"PWM":   PN = "34"  !CDS_PN = "34";
"REFIN":   PN = "39"  !CDS_PN = "39";
"SW":   PN = "10_19"  !CDS_PN = "10_19";
"TOUT_FLT":   PN = "36"  !CDS_PN = "36";
"VCC":   PN = "3"  !CDS_PN = "3";
"VIN1":   PN = "25_29"  !CDS_PN = "25_29";
"VIN2":   PN = "30"  !CDS_PN = "30";
"VOS":   PN = "1"  !CDS_PN = "1";
BODY = "Q_CAP","I17": #LOCATION = "PC250_P0_6" !CDS_LOCATION = "PC250_P0_6" &SEC = "1" #&CDS_SEC = "1";
"A":   PN = "1"  !CDS_PN = "1";
"B":   PN = "2"  !CDS_PN = "2";
BODY = "Q_INDUCTOR4P_14","I32": #LOCATION = "PL9" !CDS_LOCATION = "PL9" #SEC = "1" !CDS_SEC = "1";
"1":   PN = "1"  !CDS_PN = "1";
"2":   PN = "2"  !CDS_PN = "2";
"3":   PN = "3"  !CDS_PN = "3";
"4":   PN = "4"  !CDS_PN = "4";
BODY = "Q_CAP","I34": #LOCATION = "PC252_P0_6" !CDS_LOCATION = "PC252_P0_6" &SEC = "1" #&CDS_SEC = "1";
"A":   PN = "1"  !CDS_PN = "1";
"B":   PN = "2"  !CDS_PN = "2";
BODY = "Q_CAP","I37": #LOCATION = "PC254_P0_6" !CDS_LOCATION = "PC254_P0_6" &SEC = "1" #&CDS_SEC = "1";
"A":   PN = "1"  !CDS_PN = "1";
"B":   PN = "2"  !CDS_PN = "2";
BODY = "Q_CAP","I38": #LOCATION = "PC258_P0_6" !CDS_LOCATION = "PC258_P0_6" &SEC = "1" #&CDS_SEC = "1";
"A":   PN = "1"  !CDS_PN = "1";
"B":   PN = "2"  !CDS_PN = "2";
BODY = "Q_CAP","I39": #LOCATION = "PC260_P0_6" !CDS_LOCATION = "PC260_P0_6" &SEC = "1" #&CDS_SEC = "1";
"A":   PN = "1"  !CDS_PN = "1";
"B":   PN = "2"  !CDS_PN = "2";
BODY = "Q_RES","I40": #LOCATION = "PR142" !CDS_LOCATION = "PR142" &SEC = "1" #&CDS_SEC = "1";
"A":   PN = "1"  !CDS_PN = "1";
"B":   PN = "2"  !CDS_PN = "2";
BODY = "Q_CAP","I42": #LOCATION = "PC266_P0_6" !CDS_LOCATION = "PC266_P0_6" &SEC = "1" #&CDS_SEC = "1";
"A":   PN = "1"  !CDS_PN = "1";
"B":   PN = "2"  !CDS_PN = "2";
BODY = "Q_CAP","I59": #LOCATION = "PC268_P0_6" !CDS_LOCATION = "PC268_P0_6" &SEC = "1" #&CDS_SEC = "1";
"A":   PN = "1"  !CDS_PN = "1";
"B":   PN = "2"  !CDS_PN = "2";
BODY = "Q_RES","I4": #LOCATION = "PR139" !CDS_LOCATION = "PR139" &SEC = "1" #&CDS_SEC = "1";
"A":   PN = "1"  !CDS_PN = "1";
"B":   PN = "2"  !CDS_PN = "2";
BODY = "Q_CAP","I13": #LOCATION = "PC248" !CDS_LOCATION = "PC248" &SEC = "1" #&CDS_SEC = "1";
"A":   PN = "1"  !CDS_PN = "1";
"B":   PN = "2"  !CDS_PN = "2";
BODY = "Q_RES","I14": #LOCATION = "PR140" !CDS_LOCATION = "PR140" &SEC = "1" #&CDS_SEC = "1";
"A":   PN = "1"  !CDS_PN = "1";
"B":   PN = "2"  !CDS_PN = "2";
BODY = "Q_CAP","I24": #LOCATION = "PC249" !CDS_LOCATION = "PC249" &SEC = "1" #&CDS_SEC = "1";
"A":   PN = "1"  !CDS_PN = "1";
"B":   PN = "2"  !CDS_PN = "2";
BODY = "Q_CAP","I25": #LOCATION = "PC1343" !CDS_LOCATION = "PC1343" &SEC = "1" #&CDS_SEC = "1";
"A":   PN = "1"  !CDS_PN = "1";
"B":   PN = "2"  !CDS_PN = "2";
BODY = "Q_RES","I26": #LOCATION = "PR141" !CDS_LOCATION = "PR141" &SEC = "1" #&CDS_SEC = "1";
"A":   PN = "1"  !CDS_PN = "1";
"B":   PN = "2"  !CDS_PN = "2";
BODY = "Q_CAP","I29": #LOCATION = "PC251_P0_5" !CDS_LOCATION = "PC251_P0_5" &SEC = "1" #&CDS_SEC = "1";
"A":   PN = "1"  !CDS_PN = "1";
"B":   PN = "2"  !CDS_PN = "2";
BODY = "Q_CAP","I33": #LOCATION = "PC256" !CDS_LOCATION = "PC256" &SEC = "1" #&CDS_SEC = "1";
"A":   PN = "1"  !CDS_PN = "1";
"B":   PN = "2"  !CDS_PN = "2";
BODY = "Q_RES","I35": #LOCATION = "PR1770" !CDS_LOCATION = "PR1770" &SEC = "1" #&CDS_SEC = "1";
"A":   PN = "1"  !CDS_PN = "1";
"B":   PN = "2"  !CDS_PN = "2";
BODY = "Q_CAP","I43": #LOCATION = "PC262_P0_6" !CDS_LOCATION = "PC262_P0_6" &SEC = "1" #&CDS_SEC = "1";
"A":   PN = "1"  !CDS_PN = "1";
"B":   PN = "2"  !CDS_PN = "2";
BODY = "Q_RES","I46": #LOCATION = "PR143" !CDS_LOCATION = "PR143" &SEC = "1" #&CDS_SEC = "1";
"A":   PN = "1"  !CDS_PN = "1";
"B":   PN = "2"  !CDS_PN = "2";
BODY = "Q_CAP","I48": #LOCATION = "PC253_P0_5" !CDS_LOCATION = "PC253_P0_5" &SEC = "1" #&CDS_SEC = "1";
"A":   PN = "1"  !CDS_PN = "1";
"B":   PN = "2"  !CDS_PN = "2";
BODY = "Q_RES","I49": #LOCATION = "PR1771" !CDS_LOCATION = "PR1771" &SEC = "1" #&CDS_SEC = "1";
"A":   PN = "1"  !CDS_PN = "1";
"B":   PN = "2"  !CDS_PN = "2";
BODY = "Q_INDUCTOR4P_14","I50": #LOCATION = "PL10" !CDS_LOCATION = "PL10" #SEC = "1" !CDS_SEC = "1";
"1":   PN = "1"  !CDS_PN = "1";
"2":   PN = "2"  !CDS_PN = "2";
"3":   PN = "3"  !CDS_PN = "3";
"4":   PN = "4"  !CDS_PN = "4";
BODY = "Q_CAP","I51": #LOCATION = "PC257" !CDS_LOCATION = "PC257" &SEC = "1" #&CDS_SEC = "1";
"A":   PN = "1"  !CDS_PN = "1";
"B":   PN = "2"  !CDS_PN = "2";
BODY = "Q_CAP","I52": #LOCATION = "PC255_P0_5" !CDS_LOCATION = "PC255_P0_5" &SEC = "1" #&CDS_SEC = "1";
"A":   PN = "1"  !CDS_PN = "1";
"B":   PN = "2"  !CDS_PN = "2";
BODY = "Q_CAP","I53": #LOCATION = "PC259_P0_5" !CDS_LOCATION = "PC259_P0_5" &SEC = "1" #&CDS_SEC = "1";
"A":   PN = "1"  !CDS_PN = "1";
"B":   PN = "2"  !CDS_PN = "2";
BODY = "Q_CAP","I54": #LOCATION = "PC261_P0_5" !CDS_LOCATION = "PC261_P0_5" &SEC = "1" #&CDS_SEC = "1";
"A":   PN = "1"  !CDS_PN = "1";
"B":   PN = "2"  !CDS_PN = "2";
BODY = "Q_CAP","I56": #LOCATION = "PC263_P0_5" !CDS_LOCATION = "PC263_P0_5" &SEC = "1" #&CDS_SEC = "1";
"A":   PN = "1"  !CDS_PN = "1";
"B":   PN = "2"  !CDS_PN = "2";
BODY = "Q_CAP","I63": #LOCATION = "PC267_P0_5" !CDS_LOCATION = "PC267_P0_5" &SEC = "1" #&CDS_SEC = "1";
"A":   PN = "1"  !CDS_PN = "1";
"B":   PN = "2"  !CDS_PN = "2";
BODY = "Q_CAP","I64": #LOCATION = "PC269_P0_5" !CDS_LOCATION = "PC269_P0_5" &SEC = "1" #&CDS_SEC = "1";
"A":   PN = "1"  !CDS_PN = "1";
"B":   PN = "2"  !CDS_PN = "2";
BODY = "ISL99390FRZTR5935","I66": #LOCATION = "PU9_P0_5" !CDS_LOCATION = "PU9_P0_5" &SEC = "1" #&CDS_SEC = "1";
"AGND":   PN = "2"  !CDS_PN = "2";
"BOOT":   PN = "33"  !CDS_PN = "33";
"DNC":   PN = "31"  !CDS_PN = "31";
"EN":   PN = "35"  !CDS_PN = "35";
"GL1":   PN = "6"  !CDS_PN = "6";
"GL2":   PN = "41"  !CDS_PN = "41";
"IOUT":   PN = "38"  !CDS_PN = "38";
"LSET":   PN = "37"  !CDS_PN = "37";
"PGND1":   PN = "5"  !CDS_PN = "5";
"PGND2":   PN = "7_9-20_24"  !CDS_PN = "7_9-20_24";
"PGND3":   PN = "40"  !CDS_PN = "40";
"PHASE":   PN = "32"  !CDS_PN = "32";
"PVCC":   PN = "4"  !CDS_PN = "4";
"PWM":   PN = "34"  !CDS_PN = "34";
"REFIN":   PN = "39"  !CDS_PN = "39";
"SW":   PN = "10_19"  !CDS_PN = "10_19";
"TOUT_FLT":   PN = "36"  !CDS_PN = "36";
"VCC":   PN = "3"  !CDS_PN = "3";
"VIN1":   PN = "25_29"  !CDS_PN = "25_29";
"VIN2":   PN = "30"  !CDS_PN = "30";
"VOS":   PN = "1"  !CDS_PN = "1";
DRAWING = "@s9s_mb_2u_lib.s9s_mb_2u(sch_1):page256";
BODY = "ISL99390FRZTR5935","I2": #LOCATION = "PU6_P0_8" !CDS_LOCATION = "PU6_P0_8" &SEC = "1" #&CDS_SEC = "1";
"AGND":   PN = "2"  !CDS_PN = "2";
"BOOT":   PN = "33"  !CDS_PN = "33";
"DNC":   PN = "31"  !CDS_PN = "31";
"EN":   PN = "35"  !CDS_PN = "35";
"GL1":   PN = "6"  !CDS_PN = "6";
"GL2":   PN = "41"  !CDS_PN = "41";
"IOUT":   PN = "38"  !CDS_PN = "38";
"LSET":   PN = "37"  !CDS_PN = "37";
"PGND1":   PN = "5"  !CDS_PN = "5";
"PGND2":   PN = "7_9-20_24"  !CDS_PN = "7_9-20_24";
"PGND3":   PN = "40"  !CDS_PN = "40";
"PHASE":   PN = "32"  !CDS_PN = "32";
"PVCC":   PN = "4"  !CDS_PN = "4";
"PWM":   PN = "34"  !CDS_PN = "34";
"REFIN":   PN = "39"  !CDS_PN = "39";
"SW":   PN = "10_19"  !CDS_PN = "10_19";
"TOUT_FLT":   PN = "36"  !CDS_PN = "36";
"VCC":   PN = "3"  !CDS_PN = "3";
"VIN1":   PN = "25_29"  !CDS_PN = "25_29";
"VIN2":   PN = "30"  !CDS_PN = "30";
"VOS":   PN = "1"  !CDS_PN = "1";
BODY = "Q_RES","I19": #LOCATION = "PR1772" !CDS_LOCATION = "PR1772" &SEC = "1" #&CDS_SEC = "1";
"A":   PN = "1"  !CDS_PN = "1";
"B":   PN = "2"  !CDS_PN = "2";
BODY = "Q_CAP","I20": #LOCATION = "PC232_P0_8" !CDS_LOCATION = "PC232_P0_8" &SEC = "1" #&CDS_SEC = "1";
"A":   PN = "1"  !CDS_PN = "1";
"B":   PN = "2"  !CDS_PN = "2";
BODY = "Q_RES","I33": #LOCATION = "PR135" !CDS_LOCATION = "PR135" &SEC = "1" #&CDS_SEC = "1";
"A":   PN = "1"  !CDS_PN = "1";
"B":   PN = "2"  !CDS_PN = "2";
BODY = "Q_CAP","I36": #LOCATION = "PC229_P0_7" !CDS_LOCATION = "PC229_P0_7" &SEC = "1" #&CDS_SEC = "1";
"A":   PN = "1"  !CDS_PN = "1";
"B":   PN = "2"  !CDS_PN = "2";
BODY = "Q_INDUCTOR","I39": #LOCATION = "PL105" !CDS_LOCATION = "PL105" &SEC = "1" #&CDS_SEC = "1";
"1":   PN = "1"  !CDS_PN = "1";
"2":   PN = "2"  !CDS_PN = "2";
BODY = "Q_RES","I40": #LOCATION = "PR1773" !CDS_LOCATION = "PR1773" &SEC = "1" #&CDS_SEC = "1";
"A":   PN = "1"  !CDS_PN = "1";
"B":   PN = "2"  !CDS_PN = "2";
BODY = "Q_CAP","I52": #LOCATION = "PC242_P0_8" !CDS_LOCATION = "PC242_P0_8" &SEC = "1" #&CDS_SEC = "1";
"A":   PN = "1"  !CDS_PN = "1";
"B":   PN = "2"  !CDS_PN = "2";
BODY = "Q_RES","I57": #LOCATION = "PR137" !CDS_LOCATION = "PR137" &SEC = "1" #&CDS_SEC = "1";
"A":   PN = "1"  !CDS_PN = "1";
"B":   PN = "2"  !CDS_PN = "2";
BODY = "Q_INDUCTOR4P_14","I58": #LOCATION = "PL8" !CDS_LOCATION = "PL8" #SEC = "1" !CDS_SEC = "1";
"1":   PN = "1"  !CDS_PN = "1";
"2":   PN = "2"  !CDS_PN = "2";
"3":   PN = "3"  !CDS_PN = "3";
"4":   PN = "4"  !CDS_PN = "4";
BODY = "Q_CAP","I64": #LOCATION = "PC241_P0_7" !CDS_LOCATION = "PC241_P0_7" &SEC = "1" #&CDS_SEC = "1";
"A":   PN = "1"  !CDS_PN = "1";
"B":   PN = "2"  !CDS_PN = "2";
BODY = "Q_RES","I4": #LOCATION = "PR132" !CDS_LOCATION = "PR132" &SEC = "1" #&CDS_SEC = "1";
"A":   PN = "1"  !CDS_PN = "1";
"B":   PN = "2"  !CDS_PN = "2";
BODY = "Q_CAP","I7": #LOCATION = "PC1344" !CDS_LOCATION = "PC1344" &SEC = "1" #&CDS_SEC = "1";
"A":   PN = "1"  !CDS_PN = "1";
"B":   PN = "2"  !CDS_PN = "2";
BODY = "Q_CAP","I11": #LOCATION = "PC226" !CDS_LOCATION = "PC226" &SEC = "1" #&CDS_SEC = "1";
"A":   PN = "1"  !CDS_PN = "1";
"B":   PN = "2"  !CDS_PN = "2";
BODY = "Q_RES","I12": #LOCATION = "PR134" !CDS_LOCATION = "PR134" &SEC = "1" #&CDS_SEC = "1";
"A":   PN = "1"  !CDS_PN = "1";
"B":   PN = "2"  !CDS_PN = "2";
BODY = "Q_CAP","I15": #LOCATION = "PC228_P0_8" !CDS_LOCATION = "PC228_P0_8" &SEC = "1" #&CDS_SEC = "1";
"A":   PN = "1"  !CDS_PN = "1";
"B":   PN = "2"  !CDS_PN = "2";
BODY = "Q_CAP","I17": #LOCATION = "PC230_P0_8" !CDS_LOCATION = "PC230_P0_8" &SEC = "1" #&CDS_SEC = "1";
"A":   PN = "1"  !CDS_PN = "1";
"B":   PN = "2"  !CDS_PN = "2";
BODY = "Q_CAP","I21": #LOCATION = "PC236_P0_8" !CDS_LOCATION = "PC236_P0_8" &SEC = "1" #&CDS_SEC = "1";
"A":   PN = "1"  !CDS_PN = "1";
"B":   PN = "2"  !CDS_PN = "2";
BODY = "Q_RES","I23": #LOCATION = "PR133" !CDS_LOCATION = "PR133" &SEC = "1" #&CDS_SEC = "1";
"A":   PN = "1"  !CDS_PN = "1";
"B":   PN = "2"  !CDS_PN = "2";
BODY = "Q_CAP","I29": #LOCATION = "PC1345" !CDS_LOCATION = "PC1345" &SEC = "1" #&CDS_SEC = "1";
"A":   PN = "1"  !CDS_PN = "1";
"B":   PN = "2"  !CDS_PN = "2";
BODY = "Q_CAP","I31": #LOCATION = "PC227" !CDS_LOCATION = "PC227" &SEC = "1" #&CDS_SEC = "1";
"A":   PN = "1"  !CDS_PN = "1";
"B":   PN = "2"  !CDS_PN = "2";
BODY = "ISL99390FRZTR5935","I32": #LOCATION = "PU7_P0_7" !CDS_LOCATION = "PU7_P0_7" &SEC = "1" #&CDS_SEC = "1";
"AGND":   PN = "2"  !CDS_PN = "2";
"BOOT":   PN = "33"  !CDS_PN = "33";
"DNC":   PN = "31"  !CDS_PN = "31";
"EN":   PN = "35"  !CDS_PN = "35";
"GL1":   PN = "6"  !CDS_PN = "6";
"GL2":   PN = "41"  !CDS_PN = "41";
"IOUT":   PN = "38"  !CDS_PN = "38";
"LSET":   PN = "37"  !CDS_PN = "37";
"PGND1":   PN = "5"  !CDS_PN = "5";
"PGND2":   PN = "7_9-20_24"  !CDS_PN = "7_9-20_24";
"PGND3":   PN = "40"  !CDS_PN = "40";
"PHASE":   PN = "32"  !CDS_PN = "32";
"PVCC":   PN = "4"  !CDS_PN = "4";
"PWM":   PN = "34"  !CDS_PN = "34";
"REFIN":   PN = "39"  !CDS_PN = "39";
"SW":   PN = "10_19"  !CDS_PN = "10_19";
"TOUT_FLT":   PN = "36"  !CDS_PN = "36";
"VCC":   PN = "3"  !CDS_PN = "3";
"VIN1":   PN = "25_29"  !CDS_PN = "25_29";
"VIN2":   PN = "30"  !CDS_PN = "30";
"VOS":   PN = "1"  !CDS_PN = "1";
BODY = "Q_CAP","I41": #LOCATION = "PC231_P0_7" !CDS_LOCATION = "PC231_P0_7" &SEC = "1" #&CDS_SEC = "1";
"A":   PN = "1"  !CDS_PN = "1";
"B":   PN = "2"  !CDS_PN = "2";
BODY = "Q_CAP","I42": #LOCATION = "PC233_P0_7" !CDS_LOCATION = "PC233_P0_7" &SEC = "1" #&CDS_SEC = "1";
"A":   PN = "1"  !CDS_PN = "1";
"B":   PN = "2"  !CDS_PN = "2";
BODY = "Q_CAP","I43": #LOCATION = "PC237_P0_7" !CDS_LOCATION = "PC237_P0_7" &SEC = "1" #&CDS_SEC = "1";
"A":   PN = "1"  !CDS_PN = "1";
"B":   PN = "2"  !CDS_PN = "2";
BODY = "Q_INDUCTOR4P_14","I44": #LOCATION = "PL7" !CDS_LOCATION = "PL7" #SEC = "1" !CDS_SEC = "1";
"1":   PN = "1"  !CDS_PN = "1";
"2":   PN = "2"  !CDS_PN = "2";
"3":   PN = "3"  !CDS_PN = "3";
"4":   PN = "4"  !CDS_PN = "4";
BODY = "Q_CAP","I45": #LOCATION = "PC234" !CDS_LOCATION = "PC234" &SEC = "1" #&CDS_SEC = "1";
"A":   PN = "1"  !CDS_PN = "1";
"B":   PN = "2"  !CDS_PN = "2";
BODY = "Q_RES","I46": #LOCATION = "PR136" !CDS_LOCATION = "PR136" &SEC = "1" #&CDS_SEC = "1";
"A":   PN = "1"  !CDS_PN = "1";
"B":   PN = "2"  !CDS_PN = "2";
BODY = "Q_CAP","I47": #LOCATION = "PC238_P0_8" !CDS_LOCATION = "PC238_P0_8" &SEC = "1" #&CDS_SEC = "1";
"A":   PN = "1"  !CDS_PN = "1";
"B":   PN = "2"  !CDS_PN = "2";
BODY = "Q_CAP","I48": #LOCATION = "PC240_P0_8" !CDS_LOCATION = "PC240_P0_8" &SEC = "1" #&CDS_SEC = "1";
"A":   PN = "1"  !CDS_PN = "1";
"B":   PN = "2"  !CDS_PN = "2";
BODY = "Q_CAP","I53": #LOCATION = "PC244_P0_8" !CDS_LOCATION = "PC244_P0_8" &SEC = "1" #&CDS_SEC = "1";
"A":   PN = "1"  !CDS_PN = "1";
"B":   PN = "2"  !CDS_PN = "2";
BODY = "Q_CAP","I54": #LOCATION = "PC246_P0_8" !CDS_LOCATION = "PC246_P0_8" &SEC = "1" #&CDS_SEC = "1";
"A":   PN = "1"  !CDS_PN = "1";
"B":   PN = "2"  !CDS_PN = "2";
BODY = "Q_CAP","I59": #LOCATION = "PC235" !CDS_LOCATION = "PC235" &SEC = "1" #&CDS_SEC = "1";
"A":   PN = "1"  !CDS_PN = "1";
"B":   PN = "2"  !CDS_PN = "2";
BODY = "Q_CAP","I62": #LOCATION = "PC243_P0_7" !CDS_LOCATION = "PC243_P0_7" &SEC = "1" #&CDS_SEC = "1";
"A":   PN = "1"  !CDS_PN = "1";
"B":   PN = "2"  !CDS_PN = "2";
BODY = "Q_CAP","I63": #LOCATION = "PC239_P0_7" !CDS_LOCATION = "PC239_P0_7" &SEC = "1" #&CDS_SEC = "1";
"A":   PN = "1"  !CDS_PN = "1";
"B":   PN = "2"  !CDS_PN = "2";
BODY = "Q_CAP","I66": #LOCATION = "PC245_P0_7" !CDS_LOCATION = "PC245_P0_7" &SEC = "1" #&CDS_SEC = "1";
"A":   PN = "1"  !CDS_PN = "1";
"B":   PN = "2"  !CDS_PN = "2";
BODY = "Q_CAP","I67": #LOCATION = "PC247_P0_7" !CDS_LOCATION = "PC247_P0_7" &SEC = "1" #&CDS_SEC = "1";
"A":   PN = "1"  !CDS_PN = "1";
"B":   PN = "2"  !CDS_PN = "2";
DRAWING = "@s9s_mb_2u_lib.s9s_mb_2u(sch_1):page257";
BODY = "Q_RES","I2": #LOCATION = "PR353" !CDS_LOCATION = "PR353" &SEC = "1" #&CDS_SEC = "1";
"A":   PN = "1"  !CDS_PN = "1";
"B":   PN = "2"  !CDS_PN = "2";
BODY = "Q_RES","I39": #LOCATION = "PR355" !CDS_LOCATION = "PR355" &SEC = "1" #&CDS_SEC = "1";
"A":   PN = "1"  !CDS_PN = "1";
"B":   PN = "2"  !CDS_PN = "2";
BODY = "Q_RES","I46": #LOCATION = "PR1780" !CDS_LOCATION = "PR1780" &SEC = "1" #&CDS_SEC = "1";
"A":   PN = "1"  !CDS_PN = "1";
"B":   PN = "2"  !CDS_PN = "2";
BODY = "Q_CAP","I48": #LOCATION = "PC610_P0_1" !CDS_LOCATION = "PC610_P0_1" &SEC = "1" #&CDS_SEC = "1";
"A":   PN = "1"  !CDS_PN = "1";
"B":   PN = "2"  !CDS_PN = "2";
BODY = "Q_INDUCTOR","I49": #LOCATION = "PL34" !CDS_LOCATION = "PL34" &SEC = "1" #&CDS_SEC = "1";
"1":   PN = "1"  !CDS_PN = "1";
"2":   PN = "2"  !CDS_PN = "2";
BODY = "Q_RES","I50": #LOCATION = "PR1323" !CDS_LOCATION = "PR1323" &SEC = "1" #&CDS_SEC = "1";
"A":   PN = "1"  !CDS_PN = "1";
"B":   PN = "2"  !CDS_PN = "2";
BODY = "Q_CAP","I59": #LOCATION = "PC618_P0_2" !CDS_LOCATION = "PC618_P0_2" &SEC = "1" #&CDS_SEC = "1";
"A":   PN = "1"  !CDS_PN = "1";
"B":   PN = "2"  !CDS_PN = "2";
BODY = "Q_CAPP","I62": #LOCATION = "PC621" !CDS_LOCATION = "PC621" &SEC = "1" #&CDS_SEC = "1";
"A":   PN = "1"  !CDS_PN = "1";
"B":   PN = "2"  !CDS_PN = "2";
BODY = "Q_CAP","I27": #LOCATION = "PC603_P0_2" !CDS_LOCATION = "PC603_P0_2" &SEC = "1" #&CDS_SEC = "1";
"A":   PN = "1"  !CDS_PN = "1";
"B":   PN = "2"  !CDS_PN = "2";
BODY = "Q_CAP","I44": #LOCATION = "PC602_P0_1" !CDS_LOCATION = "PC602_P0_1" &SEC = "1" #&CDS_SEC = "1";
"A":   PN = "1"  !CDS_PN = "1";
"B":   PN = "2"  !CDS_PN = "2";
BODY = "Q_CAP","I45": #LOCATION = "PC604_P0_1" !CDS_LOCATION = "PC604_P0_1" &SEC = "1" #&CDS_SEC = "1";
"A":   PN = "1"  !CDS_PN = "1";
"B":   PN = "2"  !CDS_PN = "2";
BODY = "Q_RES","I22": #LOCATION = "PR633" !CDS_LOCATION = "PR633" &SEC = "1" #&CDS_SEC = "1";
"A":   PN = "1"  !CDS_PN = "1";
"B":   PN = "2"  !CDS_PN = "2";
BODY = "Q_CAP","I47": #LOCATION = "PC608_P0_1" !CDS_LOCATION = "PC608_P0_1" &SEC = "1" #&CDS_SEC = "1";
"A":   PN = "1"  !CDS_PN = "1";
"B":   PN = "2"  !CDS_PN = "2";
BODY = "Q_CAP","I51": #LOCATION = "PC613_P0_2" !CDS_LOCATION = "PC613_P0_2" &SEC = "1" #&CDS_SEC = "1";
"A":   PN = "1"  !CDS_PN = "1";
"B":   PN = "2"  !CDS_PN = "2";
BODY = "Q_CAP","I84": #LOCATION = "PC1670" !CDS_LOCATION = "PC1670" &SEC = "1" #&CDS_SEC = "1";
"A":   PN = "1"  !CDS_PN = "1";
"B":   PN = "2"  !CDS_PN = "2";
BODY = "Q_RES","I8": #LOCATION = "PR354" !CDS_LOCATION = "PR354" &SEC = "1" #&CDS_SEC = "1";
"A":   PN = "1"  !CDS_PN = "1";
"B":   PN = "2"  !CDS_PN = "2";
BODY = "ISL99390FRZTR5935","I16": #LOCATION = "PU70_P0_2" !CDS_LOCATION = "PU70_P0_2" &SEC = "1" #&CDS_SEC = "1";
"AGND":   PN = "2"  !CDS_PN = "2";
"BOOT":   PN = "33"  !CDS_PN = "33";
"DNC":   PN = "31"  !CDS_PN = "31";
"EN":   PN = "35"  !CDS_PN = "35";
"GL1":   PN = "6"  !CDS_PN = "6";
"GL2":   PN = "41"  !CDS_PN = "41";
"IOUT":   PN = "38"  !CDS_PN = "38";
"LSET":   PN = "37"  !CDS_PN = "37";
"PGND1":   PN = "5"  !CDS_PN = "5";
"PGND2":   PN = "7_9-20_24"  !CDS_PN = "7_9-20_24";
"PGND3":   PN = "40"  !CDS_PN = "40";
"PHASE":   PN = "32"  !CDS_PN = "32";
"PVCC":   PN = "4"  !CDS_PN = "4";
"PWM":   PN = "34"  !CDS_PN = "34";
"REFIN":   PN = "39"  !CDS_PN = "39";
"SW":   PN = "10_19"  !CDS_PN = "10_19";
"TOUT_FLT":   PN = "36"  !CDS_PN = "36";
"VCC":   PN = "3"  !CDS_PN = "3";
"VIN1":   PN = "25_29"  !CDS_PN = "25_29";
"VIN2":   PN = "30"  !CDS_PN = "30";
"VOS":   PN = "1"  !CDS_PN = "1";
BODY = "Q_RES","I69": #LOCATION = "PR1322" !CDS_LOCATION = "PR1322" &SEC = "1" #&CDS_SEC = "1";
"A":   PN = "1"  !CDS_PN = "1";
"B":   PN = "2"  !CDS_PN = "2";
BODY = "Q_CAP","I77": #LOCATION = "PC615_P0_1" !CDS_LOCATION = "PC615_P0_1" &SEC = "1" #&CDS_SEC = "1";
"A":   PN = "1"  !CDS_PN = "1";
"B":   PN = "2"  !CDS_PN = "2";
BODY = "Q_RES","I4": #LOCATION = "PR447" !CDS_LOCATION = "PR447" &SEC = "1" #&CDS_SEC = "1";
"A":   PN = "1"  !CDS_PN = "1";
"B":   PN = "2"  !CDS_PN = "2";
BODY = "Q_RES","I9": #LOCATION = "PR444" !CDS_LOCATION = "PR444" &SEC = "1" #&CDS_SEC = "1";
"A":   PN = "1"  !CDS_PN = "1";
"B":   PN = "2"  !CDS_PN = "2";
BODY = "Q_CAP","I15": #LOCATION = "PC1350" !CDS_LOCATION = "PC1350" &SEC = "1" #&CDS_SEC = "1";
"A":   PN = "1"  !CDS_PN = "1";
"B":   PN = "2"  !CDS_PN = "2";
BODY = "Q_CAP","I18": #LOCATION = "PC601" !CDS_LOCATION = "PC601" &SEC = "1" #&CDS_SEC = "1";
"A":   PN = "1"  !CDS_PN = "1";
"B":   PN = "2"  !CDS_PN = "2";
BODY = "Q_RES","I19": #LOCATION = "PR356" !CDS_LOCATION = "PR356" &SEC = "1" #&CDS_SEC = "1";
"A":   PN = "1"  !CDS_PN = "1";
"B":   PN = "2"  !CDS_PN = "2";
BODY = "Q_CAP","I21": #LOCATION = "PC1212_P0_2" !CDS_LOCATION = "PC1212_P0_2" &SEC = "1" #&CDS_SEC = "1";
"A":   PN = "1"  !CDS_PN = "1";
"B":   PN = "2"  !CDS_PN = "2";
BODY = "Q_RES","I30": #LOCATION = "PR1781" !CDS_LOCATION = "PR1781" &SEC = "1" #&CDS_SEC = "1";
"A":   PN = "1"  !CDS_PN = "1";
"B":   PN = "2"  !CDS_PN = "2";
BODY = "Q_CAP","I31": #LOCATION = "PC609_P0_2" !CDS_LOCATION = "PC609_P0_2" &SEC = "1" #&CDS_SEC = "1";
"A":   PN = "1"  !CDS_PN = "1";
"B":   PN = "2"  !CDS_PN = "2";
BODY = "Q_CAP","I52": #LOCATION = "PC616_P0_2" !CDS_LOCATION = "PC616_P0_2" &SEC = "1" #&CDS_SEC = "1";
"A":   PN = "1"  !CDS_PN = "1";
"B":   PN = "2"  !CDS_PN = "2";
BODY = "Q_CAPP","I57": #LOCATION = "PC619" !CDS_LOCATION = "PC619" &SEC = "1" #&CDS_SEC = "1";
"A":   PN = "1"  !CDS_PN = "1";
"B":   PN = "2"  !CDS_PN = "2";
BODY = "Q_CAPP","I58": #LOCATION = "PC620" !CDS_LOCATION = "PC620" &SEC = "1" #&CDS_SEC = "1";
"A":   PN = "1"  !CDS_PN = "1";
"B":   PN = "2"  !CDS_PN = "2";
BODY = "Q_INDUCTOR","I70": #LOCATION = "PL33" !CDS_LOCATION = "PL33" &SEC = "1" #&CDS_SEC = "1";
"1":   PN = "1"  !CDS_PN = "1";
"2":   PN = "2"  !CDS_PN = "2";
BODY = "Q_INDUCTOR","I80": #LOCATION = "PL44" !CDS_LOCATION = "PL44" &SEC = "1" #&CDS_SEC = "1";
"1":   PN = "1"  !CDS_PN = "1";
"2":   PN = "2"  !CDS_PN = "2";
BODY = "Q_CAP","I83": #LOCATION = "PC1669" !CDS_LOCATION = "PC1669" &SEC = "1" #&CDS_SEC = "1";
"A":   PN = "1"  !CDS_PN = "1";
"B":   PN = "2"  !CDS_PN = "2";
BODY = "Q_CAP","I85": #LOCATION = "PC1671" !CDS_LOCATION = "PC1671" &SEC = "1" #&CDS_SEC = "1";
"A":   PN = "1"  !CDS_PN = "1";
"B":   PN = "2"  !CDS_PN = "2";
BODY = "ISL99390FRZTR5935","I25": #LOCATION = "PU69_P0_1" !CDS_LOCATION = "PU69_P0_1" &SEC = "1" #&CDS_SEC = "1";
"AGND":   PN = "2"  !CDS_PN = "2";
"BOOT":   PN = "33"  !CDS_PN = "33";
"DNC":   PN = "31"  !CDS_PN = "31";
"EN":   PN = "35"  !CDS_PN = "35";
"GL1":   PN = "6"  !CDS_PN = "6";
"GL2":   PN = "41"  !CDS_PN = "41";
"IOUT":   PN = "38"  !CDS_PN = "38";
"LSET":   PN = "37"  !CDS_PN = "37";
"PGND1":   PN = "5"  !CDS_PN = "5";
"PGND2":   PN = "7_9-20_24"  !CDS_PN = "7_9-20_24";
"PGND3":   PN = "40"  !CDS_PN = "40";
"PHASE":   PN = "32"  !CDS_PN = "32";
"PVCC":   PN = "4"  !CDS_PN = "4";
"PWM":   PN = "34"  !CDS_PN = "34";
"REFIN":   PN = "39"  !CDS_PN = "39";
"SW":   PN = "10_19"  !CDS_PN = "10_19";
"TOUT_FLT":   PN = "36"  !CDS_PN = "36";
"VCC":   PN = "3"  !CDS_PN = "3";
"VIN1":   PN = "25_29"  !CDS_PN = "25_29";
"VIN2":   PN = "30"  !CDS_PN = "30";
"VOS":   PN = "1"  !CDS_PN = "1";
BODY = "Q_CAP","I28": #LOCATION = "PC605_P0_2" !CDS_LOCATION = "PC605_P0_2" &SEC = "1" #&CDS_SEC = "1";
"A":   PN = "1"  !CDS_PN = "1";
"B":   PN = "2"  !CDS_PN = "2";
BODY = "Q_CAP","I32": #LOCATION = "PC611_P0_2" !CDS_LOCATION = "PC611_P0_2" &SEC = "1" #&CDS_SEC = "1";
"A":   PN = "1"  !CDS_PN = "1";
"B":   PN = "2"  !CDS_PN = "2";
BODY = "Q_CAP","I35": #LOCATION = "PC1349" !CDS_LOCATION = "PC1349" &SEC = "1" #&CDS_SEC = "1";
"A":   PN = "1"  !CDS_PN = "1";
"B":   PN = "2"  !CDS_PN = "2";
BODY = "Q_CAP","I37": #LOCATION = "PC600" !CDS_LOCATION = "PC600" &SEC = "1" #&CDS_SEC = "1";
"A":   PN = "1"  !CDS_PN = "1";
"B":   PN = "2"  !CDS_PN = "2";
BODY = "Q_RES","I40": #LOCATION = "PR632" !CDS_LOCATION = "PR632" &SEC = "1" #&CDS_SEC = "1";
"A":   PN = "1"  !CDS_PN = "1";
"B":   PN = "2"  !CDS_PN = "2";
BODY = "Q_CAP","I42": #LOCATION = "PC1211_P0_1" !CDS_LOCATION = "PC1211_P0_1" &SEC = "1" #&CDS_SEC = "1";
"A":   PN = "1"  !CDS_PN = "1";
"B":   PN = "2"  !CDS_PN = "2";
BODY = "Q_CAP","I53": #LOCATION = "PC607" !CDS_LOCATION = "PC607" &SEC = "1" #&CDS_SEC = "1";
"A":   PN = "1"  !CDS_PN = "1";
"B":   PN = "2"  !CDS_PN = "2";
BODY = "Q_CAP","I55": #LOCATION = "PC721_P0_2" !CDS_LOCATION = "PC721_P0_2" &SEC = "1" #&CDS_SEC = "1";
"A":   PN = "1"  !CDS_PN = "1";
"B":   PN = "2"  !CDS_PN = "2";
BODY = "Q_RES","I60": #LOCATION = "PR4265" !CDS_LOCATION = "PR4265" &SEC = "1" #&CDS_SEC = "1";
"A":   PN = "1"  !CDS_PN = "1";
"B":   PN = "2"  !CDS_PN = "2";
BODY = "Q_CAPP","I63": #LOCATION = "PC623" !CDS_LOCATION = "PC623" &SEC = "1" #&CDS_SEC = "1";
"A":   PN = "1"  !CDS_PN = "1";
"B":   PN = "2"  !CDS_PN = "2";
BODY = "Q_CAPP","I67": #LOCATION = "PC2645" !CDS_LOCATION = "PC2645" &SEC = "1" #&CDS_SEC = "1";
"A":   PN = "1"  !CDS_PN = "1";
"B":   PN = "2"  !CDS_PN = "2";
BODY = "Q_CAP","I71": #LOCATION = "PC606" !CDS_LOCATION = "PC606" &SEC = "1" #&CDS_SEC = "1";
"A":   PN = "1"  !CDS_PN = "1";
"B":   PN = "2"  !CDS_PN = "2";
BODY = "Q_CAP","I73": #LOCATION = "PC720_P0_1" !CDS_LOCATION = "PC720_P0_1" &SEC = "1" #&CDS_SEC = "1";
"A":   PN = "1"  !CDS_PN = "1";
"B":   PN = "2"  !CDS_PN = "2";
BODY = "Q_CAP","I75": #LOCATION = "PC612_P0_1" !CDS_LOCATION = "PC612_P0_1" &SEC = "1" #&CDS_SEC = "1";
"A":   PN = "1"  !CDS_PN = "1";
"B":   PN = "2"  !CDS_PN = "2";
BODY = "Q_CAP","I78": #LOCATION = "PC1653" !CDS_LOCATION = "PC1653" &SEC = "1" #&CDS_SEC = "1";
"A":   PN = "1"  !CDS_PN = "1";
"B":   PN = "2"  !CDS_PN = "2";
BODY = "Q_CAP","I81": #LOCATION = "PC617_P0_1" !CDS_LOCATION = "PC617_P0_1" &SEC = "1" #&CDS_SEC = "1";
"A":   PN = "1"  !CDS_PN = "1";
"B":   PN = "2"  !CDS_PN = "2";
BODY = "Q_CAP","I86": #LOCATION = "PC1672" !CDS_LOCATION = "PC1672" &SEC = "1" #&CDS_SEC = "1";
"A":   PN = "1"  !CDS_PN = "1";
"B":   PN = "2"  !CDS_PN = "2";
BODY = "Q_CAPP","I88": #LOCATION = "PC622" !CDS_LOCATION = "PC622" &SEC = "1" #&CDS_SEC = "1";
"A":   PN = "1"  !CDS_PN = "1";
"B":   PN = "2"  !CDS_PN = "2";
DRAWING = "@s9s_mb_2u_lib.s9s_mb_2u(sch_1):page258";
BODY = "Q_CAP","I23": #LOCATION = "PC1171" !CDS_LOCATION = "PC1171" &SEC = "1" #&CDS_SEC = "1";
"A":   PN = "1"  !CDS_PN = "1";
"B":   PN = "2"  !CDS_PN = "2";
BODY = "Q_RES","I33": #LOCATION = "PR1783" !CDS_LOCATION = "PR1783" &SEC = "1" #&CDS_SEC = "1";
"A":   PN = "1"  !CDS_PN = "1";
"B":   PN = "2"  !CDS_PN = "2";
BODY = "Q_CAP","I36": #LOCATION = "PC1182_P0_4" !CDS_LOCATION = "PC1182_P0_4" &SEC = "1" #&CDS_SEC = "1";
"A":   PN = "1"  !CDS_PN = "1";
"B":   PN = "2"  !CDS_PN = "2";
BODY = "Q_INDUCTOR","I39": #LOCATION = "PL210" !CDS_LOCATION = "PL210" &SEC = "1" #&CDS_SEC = "1";
"1":   PN = "1"  !CDS_PN = "1";
"2":   PN = "2"  !CDS_PN = "2";
BODY = "Q_CAP","I40": #LOCATION = "PC1183_P0_4" !CDS_LOCATION = "PC1183_P0_4" &SEC = "1" #&CDS_SEC = "1";
"A":   PN = "1"  !CDS_PN = "1";
"B":   PN = "2"  !CDS_PN = "2";
BODY = "Q_CAP","I44": #LOCATION = "PC1173_P0_3" !CDS_LOCATION = "PC1173_P0_3" &SEC = "1" #&CDS_SEC = "1";
"A":   PN = "1"  !CDS_PN = "1";
"B":   PN = "2"  !CDS_PN = "2";
BODY = "Q_RES","I45": #LOCATION = "PR1782" !CDS_LOCATION = "PR1782" &SEC = "1" #&CDS_SEC = "1";
"A":   PN = "1"  !CDS_PN = "1";
"B":   PN = "2"  !CDS_PN = "2";
BODY = "Q_CAP","I46": #LOCATION = "PC1175_P0_3" !CDS_LOCATION = "PC1175_P0_3" &SEC = "1" #&CDS_SEC = "1";
"A":   PN = "1"  !CDS_PN = "1";
"B":   PN = "2"  !CDS_PN = "2";
BODY = "Q_CAP","I55": #LOCATION = "PC1183_P0_3" !CDS_LOCATION = "PC1183_P0_3" &SEC = "1" #&CDS_SEC = "1";
"A":   PN = "1"  !CDS_PN = "1";
"B":   PN = "2"  !CDS_PN = "2";
BODY = "Q_CAP","I61": #LOCATION = "PC1188_P0_4" !CDS_LOCATION = "PC1188_P0_4" &SEC = "1" #&CDS_SEC = "1";
"A":   PN = "1"  !CDS_PN = "1";
"B":   PN = "2"  !CDS_PN = "2";
BODY = "Q_CAPP","I68": #LOCATION = "PC1186" !CDS_LOCATION = "PC1186" &SEC = "1" #&CDS_SEC = "1";
"A":   PN = "1"  !CDS_PN = "1";
"B":   PN = "2"  !CDS_PN = "2";
BODY = "Q_CAP","I37": #LOCATION = "PC1178" !CDS_LOCATION = "PC1178" &SEC = "1" #&CDS_SEC = "1";
"A":   PN = "1"  !CDS_PN = "1";
"B":   PN = "2"  !CDS_PN = "2";
BODY = "Q_CAP","I41": #LOCATION = "PC723_P0_4" !CDS_LOCATION = "PC723_P0_4" &SEC = "1" #&CDS_SEC = "1";
"A":   PN = "1"  !CDS_PN = "1";
"B":   PN = "2"  !CDS_PN = "2";
BODY = "Q_INDUCTOR","I51": #LOCATION = "PL2" !CDS_LOCATION = "PL2" &SEC = "1" #&CDS_SEC = "1";
"1":   PN = "1"  !CDS_PN = "1";
"2":   PN = "2"  !CDS_PN = "2";
BODY = "Q_CAP","I77": #LOCATION = "PC1675" !CDS_LOCATION = "PC1675" &SEC = "1" #&CDS_SEC = "1";
"A":   PN = "1"  !CDS_PN = "1";
"B":   PN = "2"  !CDS_PN = "2";
BODY = "Q_RES","I11": #LOCATION = "PR1300" !CDS_LOCATION = "PR1300" &SEC = "1" #&CDS_SEC = "1";
"A":   PN = "1"  !CDS_PN = "1";
"B":   PN = "2"  !CDS_PN = "2";
BODY = "Q_RES","I15": #LOCATION = "PR1298" !CDS_LOCATION = "PR1298" &SEC = "1" #&CDS_SEC = "1";
"A":   PN = "1"  !CDS_PN = "1";
"B":   PN = "2"  !CDS_PN = "2";
BODY = "Q_CAP","I25": #LOCATION = "PC1351" !CDS_LOCATION = "PC1351" &SEC = "1" #&CDS_SEC = "1";
"A":   PN = "1"  !CDS_PN = "1";
"B":   PN = "2"  !CDS_PN = "2";
BODY = "Q_CAP","I31": #LOCATION = "PC1174_P0_4" !CDS_LOCATION = "PC1174_P0_4" &SEC = "1" #&CDS_SEC = "1";
"A":   PN = "1"  !CDS_PN = "1";
"B":   PN = "2"  !CDS_PN = "2";
BODY = "Q_RES","I38": #LOCATION = "PR1325" !CDS_LOCATION = "PR1325" &SEC = "1" #&CDS_SEC = "1";
"A":   PN = "1"  !CDS_PN = "1";
"B":   PN = "2"  !CDS_PN = "2";
BODY = "Q_CAP","I72": #LOCATION = "PC1185_P0_3" !CDS_LOCATION = "PC1185_P0_3" &SEC = "1" #&CDS_SEC = "1";
"A":   PN = "1"  !CDS_PN = "1";
"B":   PN = "2"  !CDS_PN = "2";
BODY = "Q_CAP","I76": #LOCATION = "PC1674" !CDS_LOCATION = "PC1674" &SEC = "1" #&CDS_SEC = "1";
"A":   PN = "1"  !CDS_PN = "1";
"B":   PN = "2"  !CDS_PN = "2";
BODY = "Q_CAP","I48": #LOCATION = "PC1181_P0_3" !CDS_LOCATION = "PC1181_P0_3" &SEC = "1" #&CDS_SEC = "1";
"A":   PN = "1"  !CDS_PN = "1";
"B":   PN = "2"  !CDS_PN = "2";
BODY = "Q_RES","I50": #LOCATION = "PR1324" !CDS_LOCATION = "PR1324" &SEC = "1" #&CDS_SEC = "1";
"A":   PN = "1"  !CDS_PN = "1";
"B":   PN = "2"  !CDS_PN = "2";
BODY = "Q_CAP","I57": #LOCATION = "PC1654" !CDS_LOCATION = "PC1654" &SEC = "1" #&CDS_SEC = "1";
"A":   PN = "1"  !CDS_PN = "1";
"B":   PN = "2"  !CDS_PN = "2";
BODY = "Q_CAP","I60": #LOCATION = "PC1186_P0_4" !CDS_LOCATION = "PC1186_P0_4" &SEC = "1" #&CDS_SEC = "1";
"A":   PN = "1"  !CDS_PN = "1";
"B":   PN = "2"  !CDS_PN = "2";
BODY = "Q_CAP","I75": #LOCATION = "PC1673" !CDS_LOCATION = "PC1673" &SEC = "1" #&CDS_SEC = "1";
"A":   PN = "1"  !CDS_PN = "1";
"B":   PN = "2"  !CDS_PN = "2";
BODY = "Q_CAPP","I80": #LOCATION = "PC1189" !CDS_LOCATION = "PC1189" &SEC = "1" #&CDS_SEC = "1";
"A":   PN = "1"  !CDS_PN = "1";
"B":   PN = "2"  !CDS_PN = "2";
BODY = "ISL99390FRZTR5935","I82": #LOCATION = "PU71_P0_3" !CDS_LOCATION = "PU71_P0_3" &SEC = "1" #&CDS_SEC = "1";
"AGND":   PN = "2"  !CDS_PN = "2";
"BOOT":   PN = "33"  !CDS_PN = "33";
"DNC":   PN = "31"  !CDS_PN = "31";
"EN":   PN = "35"  !CDS_PN = "35";
"GL1":   PN = "6"  !CDS_PN = "6";
"GL2":   PN = "41"  !CDS_PN = "41";
"IOUT":   PN = "38"  !CDS_PN = "38";
"LSET":   PN = "37"  !CDS_PN = "37";
"PGND1":   PN = "5"  !CDS_PN = "5";
"PGND2":   PN = "7_9-20_24"  !CDS_PN = "7_9-20_24";
"PGND3":   PN = "40"  !CDS_PN = "40";
"PHASE":   PN = "32"  !CDS_PN = "32";
"PVCC":   PN = "4"  !CDS_PN = "4";
"PWM":   PN = "34"  !CDS_PN = "34";
"REFIN":   PN = "39"  !CDS_PN = "39";
"SW":   PN = "10_19"  !CDS_PN = "10_19";
"TOUT_FLT":   PN = "36"  !CDS_PN = "36";
"VCC":   PN = "3"  !CDS_PN = "3";
"VIN1":   PN = "25_29"  !CDS_PN = "25_29";
"VIN2":   PN = "30"  !CDS_PN = "30";
"VOS":   PN = "1"  !CDS_PN = "1";
BODY = "Q_RES","I3": #LOCATION = "PR1297" !CDS_LOCATION = "PR1297" &SEC = "1" #&CDS_SEC = "1";
"A":   PN = "1"  !CDS_PN = "1";
"B":   PN = "2"  !CDS_PN = "2";
BODY = "Q_CAP","I9": #LOCATION = "PC1352" !CDS_LOCATION = "PC1352" &SEC = "1" #&CDS_SEC = "1";
"A":   PN = "1"  !CDS_PN = "1";
"B":   PN = "2"  !CDS_PN = "2";
BODY = "ISL99390FRZTR5935","I10": #LOCATION = "PU72_P0_4" !CDS_LOCATION = "PU72_P0_4" &SEC = "1" #&CDS_SEC = "1";
"AGND":   PN = "2"  !CDS_PN = "2";
"BOOT":   PN = "33"  !CDS_PN = "33";
"DNC":   PN = "31"  !CDS_PN = "31";
"EN":   PN = "35"  !CDS_PN = "35";
"GL1":   PN = "6"  !CDS_PN = "6";
"GL2":   PN = "41"  !CDS_PN = "41";
"IOUT":   PN = "38"  !CDS_PN = "38";
"LSET":   PN = "37"  !CDS_PN = "37";
"PGND1":   PN = "5"  !CDS_PN = "5";
"PGND2":   PN = "7_9-20_24"  !CDS_PN = "7_9-20_24";
"PGND3":   PN = "40"  !CDS_PN = "40";
"PHASE":   PN = "32"  !CDS_PN = "32";
"PVCC":   PN = "4"  !CDS_PN = "4";
"PWM":   PN = "34"  !CDS_PN = "34";
"REFIN":   PN = "39"  !CDS_PN = "39";
"SW":   PN = "10_19"  !CDS_PN = "10_19";
"TOUT_FLT":   PN = "36"  !CDS_PN = "36";
"VCC":   PN = "3"  !CDS_PN = "3";
"VIN1":   PN = "25_29"  !CDS_PN = "25_29";
"VIN2":   PN = "30"  !CDS_PN = "30";
"VOS":   PN = "1"  !CDS_PN = "1";
BODY = "Q_CAP","I13": #LOCATION = "PC1172" !CDS_LOCATION = "PC1172" &SEC = "1" #&CDS_SEC = "1";
"A":   PN = "1"  !CDS_PN = "1";
"B":   PN = "2"  !CDS_PN = "2";
BODY = "Q_CAP","I18": #LOCATION = "PC1214_P0_4" !CDS_LOCATION = "PC1214_P0_4" &SEC = "1" #&CDS_SEC = "1";
"A":   PN = "1"  !CDS_PN = "1";
"B":   PN = "2"  !CDS_PN = "2";
BODY = "Q_RES","I26": #LOCATION = "PR1299" !CDS_LOCATION = "PR1299" &SEC = "1" #&CDS_SEC = "1";
"A":   PN = "1"  !CDS_PN = "1";
"B":   PN = "2"  !CDS_PN = "2";
BODY = "Q_CAP","I28": #LOCATION = "PC1213_P0_3" !CDS_LOCATION = "PC1213_P0_3" &SEC = "1" #&CDS_SEC = "1";
"A":   PN = "1"  !CDS_PN = "1";
"B":   PN = "2"  !CDS_PN = "2";
BODY = "Q_CAP","I34": #LOCATION = "PC1176_P0_4" !CDS_LOCATION = "PC1176_P0_4" &SEC = "1" #&CDS_SEC = "1";
"A":   PN = "1"  !CDS_PN = "1";
"B":   PN = "2"  !CDS_PN = "2";
BODY = "Q_CAP","I35": #LOCATION = "PC1180_P0_4" !CDS_LOCATION = "PC1180_P0_4" &SEC = "1" #&CDS_SEC = "1";
"A":   PN = "1"  !CDS_PN = "1";
"B":   PN = "2"  !CDS_PN = "2";
BODY = "Q_CAP","I47": #LOCATION = "PC1179_P0_3" !CDS_LOCATION = "PC1179_P0_3" &SEC = "1" #&CDS_SEC = "1";
"A":   PN = "1"  !CDS_PN = "1";
"B":   PN = "2"  !CDS_PN = "2";
BODY = "Q_CAP","I49": #LOCATION = "PC1177" !CDS_LOCATION = "PC1177" &SEC = "1" #&CDS_SEC = "1";
"A":   PN = "1"  !CDS_PN = "1";
"B":   PN = "2"  !CDS_PN = "2";
BODY = "Q_CAP","I53": #LOCATION = "PC722_P0_3" !CDS_LOCATION = "PC722_P0_3" &SEC = "1" #&CDS_SEC = "1";
"A":   PN = "1"  !CDS_PN = "1";
"B":   PN = "2"  !CDS_PN = "2";
BODY = "Q_INDUCTOR","I59": #LOCATION = "PL101" !CDS_LOCATION = "PL101" &SEC = "1" #&CDS_SEC = "1";
"1":   PN = "1"  !CDS_PN = "1";
"2":   PN = "2"  !CDS_PN = "2";
BODY = "Q_CAPP","I64": #LOCATION = "PC1183" !CDS_LOCATION = "PC1183" &SEC = "1" #&CDS_SEC = "1";
"A":   PN = "1"  !CDS_PN = "1";
"B":   PN = "2"  !CDS_PN = "2";
BODY = "Q_CAPP","I65": #LOCATION = "PC1185" !CDS_LOCATION = "PC1185" &SEC = "1" #&CDS_SEC = "1";
"A":   PN = "1"  !CDS_PN = "1";
"B":   PN = "2"  !CDS_PN = "2";
BODY = "Q_CAPP","I69": #LOCATION = "PC1187" !CDS_LOCATION = "PC1187" &SEC = "1" #&CDS_SEC = "1";
"A":   PN = "1"  !CDS_PN = "1";
"B":   PN = "2"  !CDS_PN = "2";
BODY = "Q_CAPP","I70": #LOCATION = "PC2170" !CDS_LOCATION = "PC2170" &SEC = "1" #&CDS_SEC = "1";
"A":   PN = "1"  !CDS_PN = "1";
"B":   PN = "2"  !CDS_PN = "2";
BODY = "Q_CAP","I73": #LOCATION = "PC1187_P0_3" !CDS_LOCATION = "PC1187_P0_3" &SEC = "1" #&CDS_SEC = "1";
"A":   PN = "1"  !CDS_PN = "1";
"B":   PN = "2"  !CDS_PN = "2";
BODY = "Q_CAP","I79": #LOCATION = "PC1676" !CDS_LOCATION = "PC1676" &SEC = "1" #&CDS_SEC = "1";
"A":   PN = "1"  !CDS_PN = "1";
"B":   PN = "2"  !CDS_PN = "2";
DRAWING = "@s9s_mb_2u_lib.s9s_mb_2u(sch_1):page260";
BODY = "Q_RES","I37": #LOCATION = "R2386" !CDS_LOCATION = "R2386" &SEC = "1" #&CDS_SEC = "1";
"A":   PN = "1"  !CDS_PN = "1";
"B":   PN = "2"  !CDS_PN = "2";
BODY = "Q_RES","I59": #LOCATION = "R2383" !CDS_LOCATION = "R2383" &SEC = "1" #&CDS_SEC = "1";
"A":   PN = "1"  !CDS_PN = "1";
"B":   PN = "2"  !CDS_PN = "2";
BODY = "Q_CAP","I60": #LOCATION = "C3274" !CDS_LOCATION = "C3274" &SEC = "1" #&CDS_SEC = "1";
"A":   PN = "1"  !CDS_PN = "1";
"B":   PN = "2"  !CDS_PN = "2";
BODY = "Q_CAP","I61": #LOCATION = "C3273" !CDS_LOCATION = "C3273" &SEC = "1" #&CDS_SEC = "1";
"A":   PN = "1"  !CDS_PN = "1";
"B":   PN = "2"  !CDS_PN = "2";
BODY = "ISL69260IRAZT","I65": #LOCATION = "PU5" !CDS_LOCATION = "PU5" &SEC = "1" #&CDS_SEC = "1";
"ADDR_CFG":   PN = "34"  !CDS_PN = "34";
"CFP":   PN = "33"  !CDS_PN = "33";
"CS0":   PN = "30"  !CDS_PN = "30";
"CS1":   PN = "29"  !CDS_PN = "29";
"CS2":   PN = "28"  !CDS_PN = "28";
"CS3":   PN = "27"  !CDS_PN = "27";
"CS4":   PN = "26"  !CDS_PN = "26";
"CS5":   PN = "25"  !CDS_PN = "25";
"CS6":   PN = "24"  !CDS_PN = "24";
"CS7":   PN = "23"  !CDS_PN = "23";
"EN0":   PN = "13"  !CDS_PN = "13";
"EN1":   PN = "20"  !CDS_PN = "20";
"PG0":   PN = "12"  !CDS_PN = "12";
"PG1":   PN = "16"  !CDS_PN = "16";
"PMSCL":   PN = "10"  !CDS_PN = "10";
"PMSDA":   PN = "9"  !CDS_PN = "9";
"PWM0":   PN = "1"  !CDS_PN = "1";
"PWM1":   PN = "2"  !CDS_PN = "2";
"PWM2":   PN = "3"  !CDS_PN = "3";
"PWM3":   PN = "4"  !CDS_PN = "4";
"PWM4":   PN = "5"  !CDS_PN = "5";
"PWM5":   PN = "6"  !CDS_PN = "6";
"PWM6":   PN = "7"  !CDS_PN = "7";
"PWM7":   PN = "8"  !CDS_PN = "8";
"RGND0":   PN = "22"  !CDS_PN = "22";
"RGND1":   PN = "31"  !CDS_PN = "31";
"SVCLK":   PN = "17"  !CDS_PN = "17";
"SVDATA":   PN = "18"  !CDS_PN = "18";
"TEMP0":   PN = "35"  !CDS_PN = "35";
"TEMP1||ISYS":   PN = "36"  !CDS_PN = "36";
"TH_GND":   PN = "TH"  !CDS_PN = "TH";
"VCC":   PN = "39"  !CDS_PN = "39";
"VCCS":   PN = "40"  !CDS_PN = "40";
"VSEN0":   PN = "21"  !CDS_PN = "21";
"VSEN1":   PN = "32"  !CDS_PN = "32";
"NPINALERT#||NPSYSCRIT#":   PN = "15"  !CDS_PN = "15";
"NPMALERT#":   PN = "11"  !CDS_PN = "11";
"NSVALERT#":   PN = "19"  !CDS_PN = "19";
"NVRHOT#":   PN = "14"  !CDS_PN = "14";
"VINSEN||VSYS":   PN = "38"  !CDS_PN = "38";
"VMON||IINSEN||VSYS||ISYS":   PN = "37"  !CDS_PN = "37";
BODY = "Q_RES","I40": #LOCATION = "PR522" !CDS_LOCATION = "PR522" &SEC = "1" #&CDS_SEC = "1";
"A":   PN = "1"  !CDS_PN = "1";
"B":   PN = "2"  !CDS_PN = "2";
BODY = "Q_RES","I44": #LOCATION = "PR521" !CDS_LOCATION = "PR521" &SEC = "1" #&CDS_SEC = "1";
"A":   PN = "1"  !CDS_PN = "1";
"B":   PN = "2"  !CDS_PN = "2";
BODY = "Q_CAP","I48": #LOCATION = "PC216" !CDS_LOCATION = "PC216" &SEC = "1" #&CDS_SEC = "1";
"A":   PN = "1"  !CDS_PN = "1";
"B":   PN = "2"  !CDS_PN = "2";
BODY = "Q_CAP","I50": #LOCATION = "PC215" !CDS_LOCATION = "PC215" &SEC = "1" #&CDS_SEC = "1";
"A":   PN = "1"  !CDS_PN = "1";
"B":   PN = "2"  !CDS_PN = "2";
BODY = "Q_RES","I36": #LOCATION = "R2322" !CDS_LOCATION = "R2322" &SEC = "1" #&CDS_SEC = "1";
"A":   PN = "1"  !CDS_PN = "1";
"B":   PN = "2"  !CDS_PN = "2";
BODY = "Q_RES","I55": #LOCATION = "R2594" !CDS_LOCATION = "R2594" &SEC = "1" #&CDS_SEC = "1";
"A":   PN = "1"  !CDS_PN = "1";
"B":   PN = "2"  !CDS_PN = "2";
BODY = "Q_CAP","I63": #LOCATION = "PC221" !CDS_LOCATION = "PC221" &SEC = "1" #&CDS_SEC = "1";
"A":   PN = "1"  !CDS_PN = "1";
"B":   PN = "2"  !CDS_PN = "2";
BODY = "Q_RES","I79": #LOCATION = "R2398" !CDS_LOCATION = "R2398" &SEC = "1" #&CDS_SEC = "1";
"A":   PN = "1"  !CDS_PN = "1";
"B":   PN = "2"  !CDS_PN = "2";
BODY = "Q_RES","I14": #LOCATION = "R2394" !CDS_LOCATION = "R2394" &SEC = "1" #&CDS_SEC = "1";
"A":   PN = "1"  !CDS_PN = "1";
"B":   PN = "2"  !CDS_PN = "2";
BODY = "Q_RES","I18": #LOCATION = "R2392" !CDS_LOCATION = "R2392" &SEC = "1" #&CDS_SEC = "1";
"A":   PN = "1"  !CDS_PN = "1";
"B":   PN = "2"  !CDS_PN = "2";
BODY = "Q_CAP","I23": #LOCATION = "C3275" !CDS_LOCATION = "C3275" &SEC = "1" #&CDS_SEC = "1";
"A":   PN = "1"  !CDS_PN = "1";
"B":   PN = "2"  !CDS_PN = "2";
BODY = "Q_RES","I51": #LOCATION = "R2391" !CDS_LOCATION = "R2391" &SEC = "1" #&CDS_SEC = "1";
"A":   PN = "1"  !CDS_PN = "1";
"B":   PN = "2"  !CDS_PN = "2";
BODY = "Q_RES","I52": #LOCATION = "R2389" !CDS_LOCATION = "R2389" &SEC = "1" #&CDS_SEC = "1";
"A":   PN = "1"  !CDS_PN = "1";
"B":   PN = "2"  !CDS_PN = "2";
BODY = "Q_RES","I57": #LOCATION = "R2388" !CDS_LOCATION = "R2388" &SEC = "1" #&CDS_SEC = "1";
"A":   PN = "1"  !CDS_PN = "1";
"B":   PN = "2"  !CDS_PN = "2";
BODY = "Q_RES","I78": #LOCATION = "R2597" !CDS_LOCATION = "R2597" &SEC = "1" #&CDS_SEC = "1";
"A":   PN = "1"  !CDS_PN = "1";
"B":   PN = "2"  !CDS_PN = "2";
BODY = "Q_RES","I84": #LOCATION = "PR4224" !CDS_LOCATION = "PR4224" &SEC = "1" #&CDS_SEC = "1";
"A":   PN = "1"  !CDS_PN = "1";
"B":   PN = "2"  !CDS_PN = "2";
BODY = "Q_RES","I85": #LOCATION = "PR4223" !CDS_LOCATION = "PR4223" &SEC = "1" #&CDS_SEC = "1";
"A":   PN = "1"  !CDS_PN = "1";
"B":   PN = "2"  !CDS_PN = "2";
BODY = "Q_RES","I86": #LOCATION = "PR4222" !CDS_LOCATION = "PR4222" &SEC = "1" #&CDS_SEC = "1";
"A":   PN = "1"  !CDS_PN = "1";
"B":   PN = "2"  !CDS_PN = "2";
BODY = "Q_CAP","I92": #LOCATION = "PC224" !CDS_LOCATION = "PC224" &SEC = "1" #&CDS_SEC = "1";
"A":   PN = "1"  !CDS_PN = "1";
"B":   PN = "2"  !CDS_PN = "2";
BODY = "Q_RES","I7": #LOCATION = "PR105" !CDS_LOCATION = "PR105" &SEC = "1" #&CDS_SEC = "1";
"A":   PN = "1"  !CDS_PN = "1";
"B":   PN = "2"  !CDS_PN = "2";
BODY = "Q_RES","I9": #LOCATION = "PR108" !CDS_LOCATION = "PR108" &SEC = "1" #&CDS_SEC = "1";
"A":   PN = "1"  !CDS_PN = "1";
"B":   PN = "2"  !CDS_PN = "2";
BODY = "Q_RES","I10": #LOCATION = "PR107" !CDS_LOCATION = "PR107" &SEC = "1" #&CDS_SEC = "1";
"A":   PN = "1"  !CDS_PN = "1";
"B":   PN = "2"  !CDS_PN = "2";
BODY = "Q_RES","I11": #LOCATION = "R2397" !CDS_LOCATION = "R2397" &SEC = "1" #&CDS_SEC = "1";
"A":   PN = "1"  !CDS_PN = "1";
"B":   PN = "2"  !CDS_PN = "2";
BODY = "Q_RES","I13": #LOCATION = "R2396" !CDS_LOCATION = "R2396" &SEC = "1" #&CDS_SEC = "1";
"A":   PN = "1"  !CDS_PN = "1";
"B":   PN = "2"  !CDS_PN = "2";
BODY = "Q_RES","I17": #LOCATION = "R2393" !CDS_LOCATION = "R2393" &SEC = "1" #&CDS_SEC = "1";
"A":   PN = "1"  !CDS_PN = "1";
"B":   PN = "2"  !CDS_PN = "2";
BODY = "Q_RES","I19": #LOCATION = "PR4220" !CDS_LOCATION = "PR4220" &SEC = "1" #&CDS_SEC = "1";
"A":   PN = "1"  !CDS_PN = "1";
"B":   PN = "2"  !CDS_PN = "2";
BODY = "Q_CAP","I20": #LOCATION = "PC214" !CDS_LOCATION = "PC214" &SEC = "1" #&CDS_SEC = "1";
"A":   PN = "1"  !CDS_PN = "1";
"B":   PN = "2"  !CDS_PN = "2";
BODY = "Q_RES","I21": #LOCATION = "PR123" !CDS_LOCATION = "PR123" &SEC = "1" #&CDS_SEC = "1";
"A":   PN = "1"  !CDS_PN = "1";
"B":   PN = "2"  !CDS_PN = "2";
BODY = "Q_CAP","I22": #LOCATION = "C3276" !CDS_LOCATION = "C3276" &SEC = "1" #&CDS_SEC = "1";
"A":   PN = "1"  !CDS_PN = "1";
"B":   PN = "2"  !CDS_PN = "2";
BODY = "Q_RES","I38": #LOCATION = "PR520" !CDS_LOCATION = "PR520" &SEC = "1" #&CDS_SEC = "1";
"A":   PN = "1"  !CDS_PN = "1";
"B":   PN = "2"  !CDS_PN = "2";
BODY = "Q_SHORT","I39": #LOCATION = "PJ46" !CDS_LOCATION = "PJ46" &SEC = "1" #&CDS_SEC = "1";
"1":   PN = "1"  !CDS_PN = "1";
"2":   PN = "2"  !CDS_PN = "2";
BODY = "Q_RES","I42": #LOCATION = "PR519" !CDS_LOCATION = "PR519" &SEC = "1" #&CDS_SEC = "1";
"A":   PN = "1"  !CDS_PN = "1";
"B":   PN = "2"  !CDS_PN = "2";
BODY = "Q_SHORT","I43": #LOCATION = "PJ45" !CDS_LOCATION = "PJ45" &SEC = "1" #&CDS_SEC = "1";
"1":   PN = "1"  !CDS_PN = "1";
"2":   PN = "2"  !CDS_PN = "2";
BODY = "Q_RES","I47": #LOCATION = "PR121" !CDS_LOCATION = "PR121" &SEC = "1" #&CDS_SEC = "1";
"A":   PN = "1"  !CDS_PN = "1";
"B":   PN = "2"  !CDS_PN = "2";
BODY = "Q_RES","I49": #LOCATION = "PR120" !CDS_LOCATION = "PR120" &SEC = "1" #&CDS_SEC = "1";
"A":   PN = "1"  !CDS_PN = "1";
"B":   PN = "2"  !CDS_PN = "2";
BODY = "Q_RES","I53": #LOCATION = "R2390" !CDS_LOCATION = "R2390" #SEC = "1" !CDS_SEC = "1";
"A":   PN = "1"  !CDS_PN = "1";
"B":   PN = "2"  !CDS_PN = "2";
BODY = "Q_RES","I56": #LOCATION = "R2596" !CDS_LOCATION = "R2596" &SEC = "1" #&CDS_SEC = "1";
"A":   PN = "1"  !CDS_PN = "1";
"B":   PN = "2"  !CDS_PN = "2";
BODY = "Q_RES","I58": #LOCATION = "R2595" !CDS_LOCATION = "R2595" &SEC = "1" #&CDS_SEC = "1";
"A":   PN = "1"  !CDS_PN = "1";
"B":   PN = "2"  !CDS_PN = "2";
BODY = "Q_CAP","I69": #LOCATION = "PC222" !CDS_LOCATION = "PC222" &SEC = "1" #&CDS_SEC = "1";
"A":   PN = "1"  !CDS_PN = "1";
"B":   PN = "2"  !CDS_PN = "2";
BODY = "Q_RES","I71": #LOCATION = "PR435" !CDS_LOCATION = "PR435" &SEC = "1" #&CDS_SEC = "1";
"A":   PN = "1"  !CDS_PN = "1";
"B":   PN = "2"  !CDS_PN = "2";
BODY = "Q_CAP","I73": #LOCATION = "PC1271" !CDS_LOCATION = "PC1271" &SEC = "1" #&CDS_SEC = "1";
"A":   PN = "1"  !CDS_PN = "1";
"B":   PN = "2"  !CDS_PN = "2";
BODY = "Q_RES","I76": #LOCATION = "PR4225" !CDS_LOCATION = "PR4225" &SEC = "1" #&CDS_SEC = "1";
"A":   PN = "1"  !CDS_PN = "1";
"B":   PN = "2"  !CDS_PN = "2";
BODY = "Q_RES","I87": #LOCATION = "PR4221" !CDS_LOCATION = "PR4221" &SEC = "1" #&CDS_SEC = "1";
"A":   PN = "1"  !CDS_PN = "1";
"B":   PN = "2"  !CDS_PN = "2";
BODY = "Q_CAP","I95": #LOCATION = "PC1372" !CDS_LOCATION = "PC1372" &SEC = "1" #&CDS_SEC = "1";
"A":   PN = "1"  !CDS_PN = "1";
"B":   PN = "2"  !CDS_PN = "2";
BODY = "Q_CAP","I98": #LOCATION = "PC223" !CDS_LOCATION = "PC223" &SEC = "1" #&CDS_SEC = "1";
"A":   PN = "1"  !CDS_PN = "1";
"B":   PN = "2"  !CDS_PN = "2";
BODY = "Q_CAP","I99": #LOCATION = "PC225" !CDS_LOCATION = "PC225" &SEC = "1" #&CDS_SEC = "1";
"A":   PN = "1"  !CDS_PN = "1";
"B":   PN = "2"  !CDS_PN = "2";
BODY = "Q_RES","I100": #LOCATION = "PR130" !CDS_LOCATION = "PR130" &SEC = "1" #&CDS_SEC = "1";
"A":   PN = "1"  !CDS_PN = "1";
"B":   PN = "2"  !CDS_PN = "2";
BODY = "Q_RES","I106": #LOCATION = "PR436" !CDS_LOCATION = "PR436" &SEC = "1" #&CDS_SEC = "1";
"A":   PN = "1"  !CDS_PN = "1";
"B":   PN = "2"  !CDS_PN = "2";
BODY = "Q_RES","I109": #LOCATION = "PR106" !CDS_LOCATION = "PR106" &SEC = "1" #&CDS_SEC = "1";
"A":   PN = "1"  !CDS_PN = "1";
"B":   PN = "2"  !CDS_PN = "2";
BODY = "Q_CAP","I110": #LOCATION = "PC2362" !CDS_LOCATION = "PC2362" &SEC = "1" #&CDS_SEC = "1";
"A":   PN = "1"  !CDS_PN = "1";
"B":   PN = "2"  !CDS_PN = "2";
DRAWING = "@s9s_mb_2u_lib.s9s_mb_2u(sch_1):page262";
BODY = "Q_RES","I15": #LOCATION = "PR4228" !CDS_LOCATION = "PR4228" &SEC = "1" #&CDS_SEC = "1";
"A":   PN = "1"  !CDS_PN = "1";
"B":   PN = "2"  !CDS_PN = "2";
BODY = "Q_RES","I21": #LOCATION = "PR97" !CDS_LOCATION = "PR97" &SEC = "1" #&CDS_SEC = "1";
"A":   PN = "1"  !CDS_PN = "1";
"B":   PN = "2"  !CDS_PN = "2";
BODY = "Q_CAP","I24": #LOCATION = "PC176" !CDS_LOCATION = "PC176" &SEC = "1" #&CDS_SEC = "1";
"A":   PN = "1"  !CDS_PN = "1";
"B":   PN = "2"  !CDS_PN = "2";
BODY = "Q_CAP","I25": #LOCATION = "PC177" !CDS_LOCATION = "PC177" &SEC = "1" #&CDS_SEC = "1";
"A":   PN = "1"  !CDS_PN = "1";
"B":   PN = "2"  !CDS_PN = "2";
BODY = "Q_CAP","I27": #LOCATION = "PC180" !CDS_LOCATION = "PC180" &SEC = "1" #&CDS_SEC = "1";
"A":   PN = "1"  !CDS_PN = "1";
"B":   PN = "2"  !CDS_PN = "2";
BODY = "Q_CAP","I28": #LOCATION = "PC181" !CDS_LOCATION = "PC181" &SEC = "1" #&CDS_SEC = "1";
"A":   PN = "1"  !CDS_PN = "1";
"B":   PN = "2"  !CDS_PN = "2";
BODY = "Q_CAP","I31": #LOCATION = "PC184" !CDS_LOCATION = "PC184" &SEC = "1" #&CDS_SEC = "1";
"A":   PN = "1"  !CDS_PN = "1";
"B":   PN = "2"  !CDS_PN = "2";
BODY = "Q_CAP","I12": #LOCATION = "PC175" !CDS_LOCATION = "PC175" &SEC = "1" #&CDS_SEC = "1";
"A":   PN = "1"  !CDS_PN = "1";
"B":   PN = "2"  !CDS_PN = "2";
BODY = "Q_INDUCTOR","I29": #LOCATION = "PL3" !CDS_LOCATION = "PL3" &SEC = "1" #&CDS_SEC = "1";
"1":   PN = "1"  !CDS_PN = "1";
"2":   PN = "2"  !CDS_PN = "2";
BODY = "Q_CAPP","I33": #LOCATION = "PC2180" !CDS_LOCATION = "PC2180" &SEC = "1" #&CDS_SEC = "1";
"A":   PN = "1"  !CDS_PN = "1";
"B":   PN = "2"  !CDS_PN = "2";
BODY = "Q_RES","I8": #LOCATION = "PR442" !CDS_LOCATION = "PR442" &SEC = "1" #&CDS_SEC = "1";
"A":   PN = "1"  !CDS_PN = "1";
"B":   PN = "2"  !CDS_PN = "2";
BODY = "Q_RES","I17": #LOCATION = "PR1778" !CDS_LOCATION = "PR1778" &SEC = "1" #&CDS_SEC = "1";
"A":   PN = "1"  !CDS_PN = "1";
"B":   PN = "2"  !CDS_PN = "2";
BODY = "Q_CAP","I26": #LOCATION = "PC179" !CDS_LOCATION = "PC179" &SEC = "1" #&CDS_SEC = "1";
"A":   PN = "1"  !CDS_PN = "1";
"B":   PN = "2"  !CDS_PN = "2";
BODY = "Q_CAP","I32": #LOCATION = "PC186" !CDS_LOCATION = "PC186" &SEC = "1" #&CDS_SEC = "1";
"A":   PN = "1"  !CDS_PN = "1";
"B":   PN = "2"  !CDS_PN = "2";
BODY = "Q_CAPP","I34": #LOCATION = "PC1900" !CDS_LOCATION = "PC1900" &SEC = "1" #&CDS_SEC = "1";
"A":   PN = "1"  !CDS_PN = "1";
"B":   PN = "2"  !CDS_PN = "2";
BODY = "Q_RES","I36": #LOCATION = "PR4229" !CDS_LOCATION = "PR4229" &SEC = "1" #&CDS_SEC = "1";
"A":   PN = "1"  !CDS_PN = "1";
"B":   PN = "2"  !CDS_PN = "2";
BODY = "Q_RES","I2": #LOCATION = "PR1709" !CDS_LOCATION = "PR1709" &SEC = "1" #&CDS_SEC = "1";
"A":   PN = "1"  !CDS_PN = "1";
"B":   PN = "2"  !CDS_PN = "2";
BODY = "Q_CAP","I10": #LOCATION = "PC1348" !CDS_LOCATION = "PC1348" &SEC = "1" #&CDS_SEC = "1";
"A":   PN = "1"  !CDS_PN = "1";
"B":   PN = "2"  !CDS_PN = "2";
BODY = "Q_RES","I13": #LOCATION = "PR4227" !CDS_LOCATION = "PR4227" &SEC = "1" #&CDS_SEC = "1";
"A":   PN = "1"  !CDS_PN = "1";
"B":   PN = "2"  !CDS_PN = "2";
BODY = "RAA2213404GNPHB0","I14": #LOCATION = "PU42" !CDS_LOCATION = "PU42" &SEC = "1" #&CDS_SEC = "1";
"BOOT":   PN = "20"  !CDS_PN = "20";
"FAULT#":   PN = "2"  !CDS_PN = "2";
"GL1":   PN = "5"  !CDS_PN = "5";
"GL2":   PN = "27"  !CDS_PN = "27";
"GND1":   PN = "6_7-13_15-29"  !CDS_PN = "6_7-13_15-29";
"GND2":   PN = "23"  !CDS_PN = "23";
"GND3":   PN = "26"  !CDS_PN = "26";
"IMON":   PN = "25"  !CDS_PN = "25";
"LGCTRL":   PN = "3"  !CDS_PN = "3";
"NC1":   PN = "22"  !CDS_PN = "22";
"PHASE":   PN = "19"  !CDS_PN = "19";
"PWM":   PN = "21"  !CDS_PN = "21";
"REFIN":   PN = "24"  !CDS_PN = "24";
"SW":   PN = "8_12"  !CDS_PN = "8_12";
"TMON":   PN = "1"  !CDS_PN = "1";
"VCC":   PN = "4"  !CDS_PN = "4";
"VIN":   PN = "16_18-28"  !CDS_PN = "16_18-28";
BODY = "Q_RES","I16": #LOCATION = "PR1779" !CDS_LOCATION = "PR1779" &SEC = "1" #&CDS_SEC = "1";
"A":   PN = "1"  !CDS_PN = "1";
"B":   PN = "2"  !CDS_PN = "2";
BODY = "Q_CAP","I20": #LOCATION = "PC178" !CDS_LOCATION = "PC178" &SEC = "1" #&CDS_SEC = "1";
"A":   PN = "1"  !CDS_PN = "1";
"B":   PN = "2"  !CDS_PN = "2";
BODY = "Q_RES","I22": #LOCATION = "PR443" !CDS_LOCATION = "PR443" &SEC = "1" #&CDS_SEC = "1";
"A":   PN = "1"  !CDS_PN = "1";
"B":   PN = "2"  !CDS_PN = "2";
DRAWING = "@s9s_mb_2u_lib.s9s_mb_2u(sch_1):page264";
BODY = "Q_RES","I38": #LOCATION = "R2403" !CDS_LOCATION = "R2403" &SEC = "1" #&CDS_SEC = "1";
"A":   PN = "1"  !CDS_PN = "1";
"B":   PN = "2"  !CDS_PN = "2";
BODY = "Q_RES","I45": #LOCATION = "R363" !CDS_LOCATION = "R363" &SEC = "1" #&CDS_SEC = "1";
"A":   PN = "1"  !CDS_PN = "1";
"B":   PN = "2"  !CDS_PN = "2";
BODY = "Q_RES","I46": #LOCATION = "R361" !CDS_LOCATION = "R361" &SEC = "1" #&CDS_SEC = "1";
"A":   PN = "1"  !CDS_PN = "1";
"B":   PN = "2"  !CDS_PN = "2";
BODY = "Q_RES","I48": #LOCATION = "PR373" !CDS_LOCATION = "PR373" &SEC = "1" #&CDS_SEC = "1";
"A":   PN = "1"  !CDS_PN = "1";
"B":   PN = "2"  !CDS_PN = "2";
BODY = "Q_RES","I60": #LOCATION = "R2405" !CDS_LOCATION = "R2405" &SEC = "1" #&CDS_SEC = "1";
"A":   PN = "1"  !CDS_PN = "1";
"B":   PN = "2"  !CDS_PN = "2";
BODY = "Q_CAP","I72": #LOCATION = "PC629" !CDS_LOCATION = "PC629" &SEC = "1" #&CDS_SEC = "1";
"A":   PN = "1"  !CDS_PN = "1";
"B":   PN = "2"  !CDS_PN = "2";
BODY = "Q_CAP","I47": #LOCATION = "C626" !CDS_LOCATION = "C626" &SEC = "1" #&CDS_SEC = "1";
"A":   PN = "1"  !CDS_PN = "1";
"B":   PN = "2"  !CDS_PN = "2";
BODY = "Q_CAP","I50": #LOCATION = "PC628" !CDS_LOCATION = "PC628" &SEC = "1" #&CDS_SEC = "1";
"A":   PN = "1"  !CDS_PN = "1";
"B":   PN = "2"  !CDS_PN = "2";
BODY = "ISL69260IRAZT","I53": #LOCATION = "PU35" !CDS_LOCATION = "PU35" &SEC = "1" #&CDS_SEC = "1";
"ADDR_CFG":   PN = "34"  !CDS_PN = "34";
"CFP":   PN = "33"  !CDS_PN = "33";
"CS0":   PN = "30"  !CDS_PN = "30";
"CS1":   PN = "29"  !CDS_PN = "29";
"CS2":   PN = "28"  !CDS_PN = "28";
"CS3":   PN = "27"  !CDS_PN = "27";
"CS4":   PN = "26"  !CDS_PN = "26";
"CS5":   PN = "25"  !CDS_PN = "25";
"CS6":   PN = "24"  !CDS_PN = "24";
"CS7":   PN = "23"  !CDS_PN = "23";
"EN0":   PN = "13"  !CDS_PN = "13";
"EN1":   PN = "20"  !CDS_PN = "20";
"PG0":   PN = "12"  !CDS_PN = "12";
"PG1":   PN = "16"  !CDS_PN = "16";
"PMSCL":   PN = "10"  !CDS_PN = "10";
"PMSDA":   PN = "9"  !CDS_PN = "9";
"PWM0":   PN = "1"  !CDS_PN = "1";
"PWM1":   PN = "2"  !CDS_PN = "2";
"PWM2":   PN = "3"  !CDS_PN = "3";
"PWM3":   PN = "4"  !CDS_PN = "4";
"PWM4":   PN = "5"  !CDS_PN = "5";
"PWM5":   PN = "6"  !CDS_PN = "6";
"PWM6":   PN = "7"  !CDS_PN = "7";
"PWM7":   PN = "8"  !CDS_PN = "8";
"RGND0":   PN = "22"  !CDS_PN = "22";
"RGND1":   PN = "31"  !CDS_PN = "31";
"SVCLK":   PN = "17"  !CDS_PN = "17";
"SVDATA":   PN = "18"  !CDS_PN = "18";
"TEMP0":   PN = "35"  !CDS_PN = "35";
"TEMP1||ISYS":   PN = "36"  !CDS_PN = "36";
"TH_GND":   PN = "TH"  !CDS_PN = "TH";
"VCC":   PN = "39"  !CDS_PN = "39";
"VCCS":   PN = "40"  !CDS_PN = "40";
"VSEN0":   PN = "21"  !CDS_PN = "21";
"VSEN1":   PN = "32"  !CDS_PN = "32";
"NPINALERT#||NPSYSCRIT#":   PN = "15"  !CDS_PN = "15";
"NPMALERT#":   PN = "11"  !CDS_PN = "11";
"NSVALERT#":   PN = "19"  !CDS_PN = "19";
"NVRHOT#":   PN = "14"  !CDS_PN = "14";
"VINSEN||VSYS":   PN = "38"  !CDS_PN = "38";
"VMON||IINSEN||VSYS||ISYS":   PN = "37"  !CDS_PN = "37";
BODY = "Q_RES","I61": #LOCATION = "PR4236" !CDS_LOCATION = "PR4236" &SEC = "1" #&CDS_SEC = "1";
"A":   PN = "1"  !CDS_PN = "1";
"B":   PN = "2"  !CDS_PN = "2";
BODY = "Q_RES","I62": #LOCATION = "PR4235" !CDS_LOCATION = "PR4235" &SEC = "1" #&CDS_SEC = "1";
"A":   PN = "1"  !CDS_PN = "1";
"B":   PN = "2"  !CDS_PN = "2";
BODY = "Q_RES","I14": #LOCATION = "PR372" !CDS_LOCATION = "PR372" &SEC = "1" #&CDS_SEC = "1";
"A":   PN = "1"  !CDS_PN = "1";
"B":   PN = "2"  !CDS_PN = "2";
BODY = "Q_RES","I25": #LOCATION = "R1717" !CDS_LOCATION = "R1717" &SEC = "1" #&CDS_SEC = "1";
"A":   PN = "1"  !CDS_PN = "1";
"B":   PN = "2"  !CDS_PN = "2";
BODY = "Q_RES","I30": #LOCATION = "PR591" !CDS_LOCATION = "PR591" &SEC = "1" #&CDS_SEC = "1";
"A":   PN = "1"  !CDS_PN = "1";
"B":   PN = "2"  !CDS_PN = "2";
BODY = "Q_SHORT","I32": #LOCATION = "PJ54" !CDS_LOCATION = "PJ54" &SEC = "1" #&CDS_SEC = "1";
"1":   PN = "1"  !CDS_PN = "1";
"2":   PN = "2"  !CDS_PN = "2";
BODY = "Q_RES","I39": #LOCATION = "R2402" !CDS_LOCATION = "R2402" &SEC = "1" #&CDS_SEC = "1";
"A":   PN = "1"  !CDS_PN = "1";
"B":   PN = "2"  !CDS_PN = "2";
BODY = "Q_RES","I57": #LOCATION = "PR634" !CDS_LOCATION = "PR634" &SEC = "1" #&CDS_SEC = "1";
"A":   PN = "1"  !CDS_PN = "1";
"B":   PN = "2"  !CDS_PN = "2";
BODY = "Q_RES","I59": #LOCATION = "PR1311" !CDS_LOCATION = "PR1311" &SEC = "1" #&CDS_SEC = "1";
"A":   PN = "1"  !CDS_PN = "1";
"B":   PN = "2"  !CDS_PN = "2";
BODY = "Q_RES","I31": #LOCATION = "PR592" !CDS_LOCATION = "PR592" &SEC = "1" #&CDS_SEC = "1";
"A":   PN = "1"  !CDS_PN = "1";
"B":   PN = "2"  !CDS_PN = "2";
BODY = "Q_RES","I40": #LOCATION = "R2401" !CDS_LOCATION = "R2401" &SEC = "1" #&CDS_SEC = "1";
"A":   PN = "1"  !CDS_PN = "1";
"B":   PN = "2"  !CDS_PN = "2";
BODY = "Q_RES","I42": #LOCATION = "R2400" !CDS_LOCATION = "R2400" &SEC = "1" #&CDS_SEC = "1";
"A":   PN = "1"  !CDS_PN = "1";
"B":   PN = "2"  !CDS_PN = "2";
BODY = "Q_RES","I63": #LOCATION = "PR409" !CDS_LOCATION = "PR409" &SEC = "1" #&CDS_SEC = "1";
"A":   PN = "1"  !CDS_PN = "1";
"B":   PN = "2"  !CDS_PN = "2";
BODY = "Q_RES","I66": #LOCATION = "PR4234" !CDS_LOCATION = "PR4234" &SEC = "1" #&CDS_SEC = "1";
"A":   PN = "1"  !CDS_PN = "1";
"B":   PN = "2"  !CDS_PN = "2";
BODY = "Q_RES","I67": #LOCATION = "PR4233" !CDS_LOCATION = "PR4233" &SEC = "1" #&CDS_SEC = "1";
"A":   PN = "1"  !CDS_PN = "1";
"B":   PN = "2"  !CDS_PN = "2";
BODY = "Q_RES","I68": #LOCATION = "PR4232" !CDS_LOCATION = "PR4232" &SEC = "1" #&CDS_SEC = "1";
"A":   PN = "1"  !CDS_PN = "1";
"B":   PN = "2"  !CDS_PN = "2";
BODY = "Q_RES","I85": #LOCATION = "R2404" !CDS_LOCATION = "R2404" &SEC = "1" #&CDS_SEC = "1";
"A":   PN = "1"  !CDS_PN = "1";
"B":   PN = "2"  !CDS_PN = "2";
BODY = "Q_RES","I5": #LOCATION = "PR357" !CDS_LOCATION = "PR357" &SEC = "1" #&CDS_SEC = "1";
"A":   PN = "1"  !CDS_PN = "1";
"B":   PN = "2"  !CDS_PN = "2";
BODY = "Q_RES","I7": #LOCATION = "PR369" !CDS_LOCATION = "PR369" &SEC = "1" #&CDS_SEC = "1";
"A":   PN = "1"  !CDS_PN = "1";
"B":   PN = "2"  !CDS_PN = "2";
BODY = "Q_CAP","I9": #LOCATION = "PC624" !CDS_LOCATION = "PC624" &SEC = "1" #&CDS_SEC = "1";
"A":   PN = "1"  !CDS_PN = "1";
"B":   PN = "2"  !CDS_PN = "2";
BODY = "Q_RES","I10": #LOCATION = "PR1390" !CDS_LOCATION = "PR1390" &SEC = "1" #&CDS_SEC = "1";
"A":   PN = "1"  !CDS_PN = "1";
"B":   PN = "2"  !CDS_PN = "2";
BODY = "Q_RES","I11": #LOCATION = "PR1380" !CDS_LOCATION = "PR1380" &SEC = "1" #&CDS_SEC = "1";
"A":   PN = "1"  !CDS_PN = "1";
"B":   PN = "2"  !CDS_PN = "2";
BODY = "Q_RES","I13": #LOCATION = "PR370" !CDS_LOCATION = "PR370" &SEC = "1" #&CDS_SEC = "1";
"A":   PN = "1"  !CDS_PN = "1";
"B":   PN = "2"  !CDS_PN = "2";
BODY = "Q_CAP","I18": #LOCATION = "C2443" !CDS_LOCATION = "C2443" &SEC = "1" #&CDS_SEC = "1";
"A":   PN = "1"  !CDS_PN = "1";
"B":   PN = "2"  !CDS_PN = "2";
BODY = "Q_CAP","I19": #LOCATION = "C2444" !CDS_LOCATION = "C2444" &SEC = "1" #&CDS_SEC = "1";
"A":   PN = "1"  !CDS_PN = "1";
"B":   PN = "2"  !CDS_PN = "2";
BODY = "Q_RES","I24": #LOCATION = "R1735" !CDS_LOCATION = "R1735" &SEC = "1" #&CDS_SEC = "1";
"A":   PN = "1"  !CDS_PN = "1";
"B":   PN = "2"  !CDS_PN = "2";
BODY = "Q_RES","I36": #LOCATION = "PR371" !CDS_LOCATION = "PR371" &SEC = "1" #&CDS_SEC = "1";
"A":   PN = "1"  !CDS_PN = "1";
"B":   PN = "2"  !CDS_PN = "2";
BODY = "Q_CAP","I37": #LOCATION = "PC627" !CDS_LOCATION = "PC627" &SEC = "1" #&CDS_SEC = "1";
"A":   PN = "1"  !CDS_PN = "1";
"B":   PN = "2"  !CDS_PN = "2";
BODY = "Q_RES","I43": #LOCATION = "R2399" !CDS_LOCATION = "R2399" &SEC = "1" #&CDS_SEC = "1";
"A":   PN = "1"  !CDS_PN = "1";
"B":   PN = "2"  !CDS_PN = "2";
BODY = "Q_RES","I44": #LOCATION = "R362" !CDS_LOCATION = "R362" &SEC = "1" #&CDS_SEC = "1";
"A":   PN = "1"  !CDS_PN = "1";
"B":   PN = "2"  !CDS_PN = "2";
BODY = "Q_CAP","I51": #LOCATION = "PC813" !CDS_LOCATION = "PC813" &SEC = "1" #&CDS_SEC = "1";
"A":   PN = "1"  !CDS_PN = "1";
"B":   PN = "2"  !CDS_PN = "2";
BODY = "Q_CAP","I56": #LOCATION = "PC631" !CDS_LOCATION = "PC631" &SEC = "1" #&CDS_SEC = "1";
"A":   PN = "1"  !CDS_PN = "1";
"B":   PN = "2"  !CDS_PN = "2";
BODY = "Q_RES","I69": #LOCATION = "PR4231" !CDS_LOCATION = "PR4231" &SEC = "1" #&CDS_SEC = "1";
"A":   PN = "1"  !CDS_PN = "1";
"B":   PN = "2"  !CDS_PN = "2";
BODY = "Q_CAP","I70": #LOCATION = "PC630" !CDS_LOCATION = "PC630" &SEC = "1" #&CDS_SEC = "1";
"A":   PN = "1"  !CDS_PN = "1";
"B":   PN = "2"  !CDS_PN = "2";
BODY = "Q_CAP","I71": #LOCATION = "PC1196" !CDS_LOCATION = "PC1196" &SEC = "1" #&CDS_SEC = "1";
"A":   PN = "1"  !CDS_PN = "1";
"B":   PN = "2"  !CDS_PN = "2";
BODY = "Q_CAP","I73": #LOCATION = "PC632" !CDS_LOCATION = "PC632" &SEC = "1" #&CDS_SEC = "1";
"A":   PN = "1"  !CDS_PN = "1";
"B":   PN = "2"  !CDS_PN = "2";
BODY = "Q_RES","I74": #LOCATION = "PR4230" !CDS_LOCATION = "PR4230" &SEC = "1" #&CDS_SEC = "1";
"A":   PN = "1"  !CDS_PN = "1";
"B":   PN = "2"  !CDS_PN = "2";
BODY = "Q_RES","I80": #LOCATION = "PR375" !CDS_LOCATION = "PR375" &SEC = "1" #&CDS_SEC = "1";
"A":   PN = "1"  !CDS_PN = "1";
"B":   PN = "2"  !CDS_PN = "2";
BODY = "Q_RES","I95": #LOCATION = "PR358" !CDS_LOCATION = "PR358" &SEC = "1" #&CDS_SEC = "1";
"A":   PN = "1"  !CDS_PN = "1";
"B":   PN = "2"  !CDS_PN = "2";
BODY = "Q_CAP","I96": #LOCATION = "PC2365" !CDS_LOCATION = "PC2365" &SEC = "1" #&CDS_SEC = "1";
"A":   PN = "1"  !CDS_PN = "1";
"B":   PN = "2"  !CDS_PN = "2";
DRAWING = "@s9s_mb_2u_lib.s9s_mb_2u(sch_1):page267";
BODY = "Q_CAP","I12": #LOCATION = "C1300" !CDS_LOCATION = "C1300" &SEC = "1" #&CDS_SEC = "1";
"A":   PN = "1"  !CDS_PN = "1";
"B":   PN = "2"  !CDS_PN = "2";
BODY = "Q_CAP","I16": #LOCATION = "PC1248" !CDS_LOCATION = "PC1248" &SEC = "1" #&CDS_SEC = "1";
"A":   PN = "1"  !CDS_PN = "1";
"B":   PN = "2"  !CDS_PN = "2";
BODY = "Q_CAP","I17": #LOCATION = "PC1249" !CDS_LOCATION = "PC1249" &SEC = "1" #&CDS_SEC = "1";
"A":   PN = "1"  !CDS_PN = "1";
"B":   PN = "2"  !CDS_PN = "2";
BODY = "Q_RES","I18": #LOCATION = "PR3335" !CDS_LOCATION = "PR3335" &SEC = "1" #&CDS_SEC = "1";
"A":   PN = "1"  !CDS_PN = "1";
"B":   PN = "2"  !CDS_PN = "2";
BODY = "Q_CAP","I27": #LOCATION = "PC1252" !CDS_LOCATION = "PC1252" &SEC = "1" #&CDS_SEC = "1";
"A":   PN = "1"  !CDS_PN = "1";
"B":   PN = "2"  !CDS_PN = "2";
BODY = "Q_RES","I34": #LOCATION = "PR2336" !CDS_LOCATION = "PR2336" &SEC = "1" #&CDS_SEC = "1";
"A":   PN = "1"  !CDS_PN = "1";
"B":   PN = "2"  !CDS_PN = "2";
BODY = "Q_CAP","I38": #LOCATION = "PC1254" !CDS_LOCATION = "PC1254" &SEC = "1" #&CDS_SEC = "1";
"A":   PN = "1"  !CDS_PN = "1";
"B":   PN = "2"  !CDS_PN = "2";
BODY = "Q_CAP","I42": #LOCATION = "PC1255" !CDS_LOCATION = "PC1255" &SEC = "1" #&CDS_SEC = "1";
"A":   PN = "1"  !CDS_PN = "1";
"B":   PN = "2"  !CDS_PN = "2";
BODY = "Q_CAP","I4": #LOCATION = "PC2643" !CDS_LOCATION = "PC2643" #SEC = "1" !CDS_SEC = "1";
"A":   PN = "1"  !CDS_PN = "1";
"B":   PN = "2"  !CDS_PN = "2";
BODY = "Q_RES","I9": #LOCATION = "R2406" !CDS_LOCATION = "R2406" &SEC = "1" #&CDS_SEC = "1";
"A":   PN = "1"  !CDS_PN = "1";
"B":   PN = "2"  !CDS_PN = "2";
BODY = "Q_RES","I26": #LOCATION = "PR1310" !CDS_LOCATION = "PR1310" &SEC = "1" #&CDS_SEC = "1";
"A":   PN = "1"  !CDS_PN = "1";
"B":   PN = "2"  !CDS_PN = "2";
BODY = "Q_CAP","I30": #LOCATION = "C1301" !CDS_LOCATION = "C1301" &SEC = "1" #&CDS_SEC = "1";
"A":   PN = "1"  !CDS_PN = "1";
"B":   PN = "2"  !CDS_PN = "2";
BODY = "Q_INDUCTOR","I28": #LOCATION = "PL118" !CDS_LOCATION = "PL118" &SEC = "1" #&CDS_SEC = "1";
"1":   PN = "1"  !CDS_PN = "1";
"2":   PN = "2"  !CDS_PN = "2";
BODY = "Q_RES","I36": #LOCATION = "PR1337" !CDS_LOCATION = "PR1337" &SEC = "1" #&CDS_SEC = "1";
"A":   PN = "1"  !CDS_PN = "1";
"B":   PN = "2"  !CDS_PN = "2";
BODY = "Q_CAPP","I49": #LOCATION = "PC1258" !CDS_LOCATION = "PC1258" &SEC = "1" #&CDS_SEC = "1";
"A":   PN = "1"  !CDS_PN = "1";
"B":   PN = "2"  !CDS_PN = "2";
BODY = "Q_RES","I15": #LOCATION = "PR1336" !CDS_LOCATION = "PR1336" &SEC = "1" #&CDS_SEC = "1";
"A":   PN = "1"  !CDS_PN = "1";
"B":   PN = "2"  !CDS_PN = "2";
BODY = "Q_SHORT","I33": #LOCATION = "PJ65" !CDS_LOCATION = "PJ65" &SEC = "1" #&CDS_SEC = "1";
"1":   PN = "1"  !CDS_PN = "1";
"2":   PN = "2"  !CDS_PN = "2";
BODY = "Q_RES","I45": #LOCATION = "R2407" !CDS_LOCATION = "R2407" &SEC = "1" #&CDS_SEC = "1";
"A":   PN = "1"  !CDS_PN = "1";
"B":   PN = "2"  !CDS_PN = "2";
BODY = "Q_CAP","I7": #LOCATION = "PC831" !CDS_LOCATION = "PC831" &SEC = "1" #&CDS_SEC = "1";
"A":   PN = "1"  !CDS_PN = "1";
"B":   PN = "2"  !CDS_PN = "2";
BODY = "Q_CAP","I23": #LOCATION = "PC2001" !CDS_LOCATION = "PC2001" &SEC = "1" #&CDS_SEC = "1";
"A":   PN = "1"  !CDS_PN = "1";
"B":   PN = "2"  !CDS_PN = "2";
BODY = "MOSFET_N","I31": #LOCATION = "PU173" !CDS_LOCATION = "PU173" &SEC = "1" #&CDS_SEC = "1";
"DRAIN":   PN = "D"  !CDS_PN = "D";
"GATE":   PN = "G"  !CDS_PN = "G";
"SOURCE":   PN = "S"  !CDS_PN = "S";
BODY = "Q_CAP","I35": #LOCATION = "PC1253" !CDS_LOCATION = "PC1253" &SEC = "1" #&CDS_SEC = "1";
"A":   PN = "1"  !CDS_PN = "1";
"B":   PN = "2"  !CDS_PN = "2";
BODY = "Q_CAP","I43": #LOCATION = "PC1256" !CDS_LOCATION = "PC1256" &SEC = "1" #&CDS_SEC = "1";
"A":   PN = "1"  !CDS_PN = "1";
"B":   PN = "2"  !CDS_PN = "2";
BODY = "Q_RES","I5": #LOCATION = "PR1335" !CDS_LOCATION = "PR1335" &SEC = "1" #&CDS_SEC = "1";
"A":   PN = "1"  !CDS_PN = "1";
"B":   PN = "2"  !CDS_PN = "2";
BODY = "Q_CAP","I10": #LOCATION = "PC1247" !CDS_LOCATION = "PC1247" &SEC = "1" #&CDS_SEC = "1";
"A":   PN = "1"  !CDS_PN = "1";
"B":   PN = "2"  !CDS_PN = "2";
BODY = "Q_RES","I14": #LOCATION = "R2332" !CDS_LOCATION = "R2332" &SEC = "1" #&CDS_SEC = "1";
"A":   PN = "1"  !CDS_PN = "1";
"B":   PN = "2"  !CDS_PN = "2";
BODY = "RS53318LR","I19": #LOCATION = "PU79" !CDS_LOCATION = "PU79" #SEC = "1" !CDS_SEC = "1";
"AGND":   PN = "2"  !CDS_PN = "2";
"BST":   PN = "1"  !CDS_PN = "1";
"CS":   PN = "3"  !CDS_PN = "3";
"EN":   PN = "8"  !CDS_PN = "8";
"FB":   PN = "7"  !CDS_PN = "7";
"MODE":   PN = "4"  !CDS_PN = "4";
"PGND":   PN = "11_18"  !CDS_PN = "11_18";
"PGOOD":   PN = "9"  !CDS_PN = "9";
"REF":   PN = "5"  !CDS_PN = "5";
"RTN":   PN = "6"  !CDS_PN = "6";
"SW":   PN = "20"  !CDS_PN = "20";
"VCC":   PN = "19"  !CDS_PN = "19";
"VIN1":   PN = "10"  !CDS_PN = "10";
"VIN2":   PN = "21"  !CDS_PN = "21";
BODY = "Q_CAP","I25": #LOCATION = "PC1251" !CDS_LOCATION = "PC1251" &SEC = "1" #&CDS_SEC = "1";
"A":   PN = "1"  !CDS_PN = "1";
"B":   PN = "2"  !CDS_PN = "2";
BODY = "Q_RES","I29": #LOCATION = "R2408" !CDS_LOCATION = "R2408" &SEC = "1" #&CDS_SEC = "1";
"A":   PN = "1"  !CDS_PN = "1";
"B":   PN = "2"  !CDS_PN = "2";
BODY = "Q_CAP","I40": #LOCATION = "PC1421" !CDS_LOCATION = "PC1421" &SEC = "1" #&CDS_SEC = "1";
"A":   PN = "1"  !CDS_PN = "1";
"B":   PN = "2"  !CDS_PN = "2";
BODY = "Q_SHORT","I41": #LOCATION = "PJ64" !CDS_LOCATION = "PJ64" &SEC = "1" #&CDS_SEC = "1";
"1":   PN = "1"  !CDS_PN = "1";
"2":   PN = "2"  !CDS_PN = "2";
BODY = "Q_CAP","I44": #LOCATION = "PC1257" !CDS_LOCATION = "PC1257" &SEC = "1" #&CDS_SEC = "1";
"A":   PN = "1"  !CDS_PN = "1";
"B":   PN = "2"  !CDS_PN = "2";
DRAWING = "@s9s_mb_2u_lib.s9s_mb_2u(sch_1):page271";
BODY = "Q_CAP","I22": #LOCATION = "PC566_P1_2" !CDS_LOCATION = "PC566_P1_2" &SEC = "1" #&CDS_SEC = "1";
"A":   PN = "1"  !CDS_PN = "1";
"B":   PN = "2"  !CDS_PN = "2";
BODY = "Q_RES","I29": #LOCATION = "PR326" !CDS_LOCATION = "PR326" &SEC = "1" #&CDS_SEC = "1";
"A":   PN = "1"  !CDS_PN = "1";
"B":   PN = "2"  !CDS_PN = "2";
BODY = "Q_RES","I46": #LOCATION = "PR1767" !CDS_LOCATION = "PR1767" &SEC = "1" #&CDS_SEC = "1";
"A":   PN = "1"  !CDS_PN = "1";
"B":   PN = "2"  !CDS_PN = "2";
BODY = "Q_CAPP","I61": #LOCATION = "PC1990" !CDS_LOCATION = "PC1990" &SEC = "1" #&CDS_SEC = "1";
"A":   PN = "1"  !CDS_PN = "1";
"B":   PN = "2"  !CDS_PN = "2";
BODY = "Q_CAPP","I65": #LOCATION = "PC587" !CDS_LOCATION = "PC587" &SEC = "1" #&CDS_SEC = "1";
"A":   PN = "1"  !CDS_PN = "1";
"B":   PN = "2"  !CDS_PN = "2";
BODY = "Q_CAPP","I69": #LOCATION = "PC586" !CDS_LOCATION = "PC586" &SEC = "1" #&CDS_SEC = "1";
"A":   PN = "1"  !CDS_PN = "1";
"B":   PN = "2"  !CDS_PN = "2";
BODY = "Q_INDUCTOR4P_14","I74": #LOCATION = "PL31" !CDS_LOCATION = "PL31" #SEC = "1" !CDS_SEC = "1";
"1":   PN = "1"  !CDS_PN = "1";
"2":   PN = "2"  !CDS_PN = "2";
"3":   PN = "3"  !CDS_PN = "3";
"4":   PN = "4"  !CDS_PN = "4";
BODY = "Q_CAP","I79": #LOCATION = "PC1656" !CDS_LOCATION = "PC1656" &SEC = "1" #&CDS_SEC = "1";
"A":   PN = "1"  !CDS_PN = "1";
"B":   PN = "2"  !CDS_PN = "2";
BODY = "Q_INDUCTOR","I83": #LOCATION = "PL32" !CDS_LOCATION = "PL32" &SEC = "1" #&CDS_SEC = "1";
"1":   PN = "1"  !CDS_PN = "1";
"2":   PN = "2"  !CDS_PN = "2";
BODY = "Q_CAP","I84": #LOCATION = "PC572_P1_1" !CDS_LOCATION = "PC572_P1_1" &SEC = "1" #&CDS_SEC = "1";
"A":   PN = "1"  !CDS_PN = "1";
"B":   PN = "2"  !CDS_PN = "2";
BODY = "Q_RES","I3": #LOCATION = "PR325" !CDS_LOCATION = "PR325" &SEC = "1" #&CDS_SEC = "1";
"A":   PN = "1"  !CDS_PN = "1";
"B":   PN = "2"  !CDS_PN = "2";
BODY = "Q_CAP","I6": #LOCATION = "PC1338" !CDS_LOCATION = "PC1338" &SEC = "1" #&CDS_SEC = "1";
"A":   PN = "1"  !CDS_PN = "1";
"B":   PN = "2"  !CDS_PN = "2";
BODY = "Q_CAP","I11": #LOCATION = "PC556" !CDS_LOCATION = "PC556" &SEC = "1" #&CDS_SEC = "1";
"A":   PN = "1"  !CDS_PN = "1";
"B":   PN = "2"  !CDS_PN = "2";
BODY = "Q_CAP","I23": #LOCATION = "PC564" !CDS_LOCATION = "PC564" &SEC = "1" #&CDS_SEC = "1";
"A":   PN = "1"  !CDS_PN = "1";
"B":   PN = "2"  !CDS_PN = "2";
BODY = "Q_CAP","I24": #LOCATION = "PC568_P1_2" !CDS_LOCATION = "PC568_P1_2" &SEC = "1" #&CDS_SEC = "1";
"A":   PN = "1"  !CDS_PN = "1";
"B":   PN = "2"  !CDS_PN = "2";
BODY = "Q_CAP","I47": #LOCATION = "PC563_P1_1" !CDS_LOCATION = "PC563_P1_1" &SEC = "1" #&CDS_SEC = "1";
"A":   PN = "1"  !CDS_PN = "1";
"B":   PN = "2"  !CDS_PN = "2";
BODY = "Q_CAP","I48": #LOCATION = "PC567_P1_1" !CDS_LOCATION = "PC567_P1_1" &SEC = "1" #&CDS_SEC = "1";
"A":   PN = "1"  !CDS_PN = "1";
"B":   PN = "2"  !CDS_PN = "2";
BODY = "Q_CAP","I49": #LOCATION = "PC565" !CDS_LOCATION = "PC565" &SEC = "1" #&CDS_SEC = "1";
"A":   PN = "1"  !CDS_PN = "1";
"B":   PN = "2"  !CDS_PN = "2";
BODY = "Q_CAP","I50": #LOCATION = "PC569_P1_1" !CDS_LOCATION = "PC569_P1_1" &SEC = "1" #&CDS_SEC = "1";
"A":   PN = "1"  !CDS_PN = "1";
"B":   PN = "2"  !CDS_PN = "2";
BODY = "Q_CAP","I57": #LOCATION = "PC575_P1_2" !CDS_LOCATION = "PC575_P1_2" &SEC = "1" #&CDS_SEC = "1";
"A":   PN = "1"  !CDS_PN = "1";
"B":   PN = "2"  !CDS_PN = "2";
BODY = "Q_CAP","I58": #LOCATION = "PC577_P1_2" !CDS_LOCATION = "PC577_P1_2" &SEC = "1" #&CDS_SEC = "1";
"A":   PN = "1"  !CDS_PN = "1";
"B":   PN = "2"  !CDS_PN = "2";
BODY = "Q_RES","I59": #LOCATION = "PR4240" !CDS_LOCATION = "PR4240" &SEC = "1" #&CDS_SEC = "1";
"A":   PN = "1"  !CDS_PN = "1";
"B":   PN = "2"  !CDS_PN = "2";
BODY = "Q_CAPP","I63": #LOCATION = "PC580" !CDS_LOCATION = "PC580" &SEC = "1" #&CDS_SEC = "1";
"A":   PN = "1"  !CDS_PN = "1";
"B":   PN = "2"  !CDS_PN = "2";
BODY = "Q_CAPP","I72": #LOCATION = "PC589" !CDS_LOCATION = "PC589" &SEC = "1" #&CDS_SEC = "1";
"A":   PN = "1"  !CDS_PN = "1";
"B":   PN = "2"  !CDS_PN = "2";
BODY = "Q_RES","I82": #LOCATION = "PR2556" !CDS_LOCATION = "PR2556" &SEC = "1" #&CDS_SEC = "1";
"A":   PN = "1"  !CDS_PN = "1";
"B":   PN = "2"  !CDS_PN = "2";
BODY = "Q_CAP","I85": #LOCATION = "PC574_P1_1" !CDS_LOCATION = "PC574_P1_1" &SEC = "1" #&CDS_SEC = "1";
"A":   PN = "1"  !CDS_PN = "1";
"B":   PN = "2"  !CDS_PN = "2";
BODY = "Q_CAP","I15": #LOCATION = "PC558_P1_2" !CDS_LOCATION = "PC558_P1_2" &SEC = "1" #&CDS_SEC = "1";
"A":   PN = "1"  !CDS_PN = "1";
"B":   PN = "2"  !CDS_PN = "2";
BODY = "Q_CAP","I19": #LOCATION = "PC560_P1_2" !CDS_LOCATION = "PC560_P1_2" &SEC = "1" #&CDS_SEC = "1";
"A":   PN = "1"  !CDS_PN = "1";
"B":   PN = "2"  !CDS_PN = "2";
BODY = "Q_RES","I20": #LOCATION = "PR1766" !CDS_LOCATION = "PR1766" &SEC = "1" #&CDS_SEC = "1";
"A":   PN = "1"  !CDS_PN = "1";
"B":   PN = "2"  !CDS_PN = "2";
BODY = "Q_CAP","I21": #LOCATION = "PC562_P1_2" !CDS_LOCATION = "PC562_P1_2" &SEC = "1" #&CDS_SEC = "1";
"A":   PN = "1"  !CDS_PN = "1";
"B":   PN = "2"  !CDS_PN = "2";
BODY = "Q_RES","I37": #LOCATION = "PR328" !CDS_LOCATION = "PR328" &SEC = "1" #&CDS_SEC = "1";
"A":   PN = "1"  !CDS_PN = "1";
"B":   PN = "2"  !CDS_PN = "2";
BODY = "Q_CAP","I39": #LOCATION = "PC559_P1_1" !CDS_LOCATION = "PC559_P1_1" &SEC = "1" #&CDS_SEC = "1";
"A":   PN = "1"  !CDS_PN = "1";
"B":   PN = "2"  !CDS_PN = "2";
BODY = "ISL99390FRZTR5935","I40": #LOCATION = "PU31_P1_1" !CDS_LOCATION = "PU31_P1_1" &SEC = "1" #&CDS_SEC = "1";
"AGND":   PN = "2"  !CDS_PN = "2";
"BOOT":   PN = "33"  !CDS_PN = "33";
"DNC":   PN = "31"  !CDS_PN = "31";
"EN":   PN = "35"  !CDS_PN = "35";
"GL1":   PN = "6"  !CDS_PN = "6";
"GL2":   PN = "41"  !CDS_PN = "41";
"IOUT":   PN = "38"  !CDS_PN = "38";
"LSET":   PN = "37"  !CDS_PN = "37";
"PGND1":   PN = "5"  !CDS_PN = "5";
"PGND2":   PN = "7_9-20_24"  !CDS_PN = "7_9-20_24";
"PGND3":   PN = "40"  !CDS_PN = "40";
"PHASE":   PN = "32"  !CDS_PN = "32";
"PVCC":   PN = "4"  !CDS_PN = "4";
"PWM":   PN = "34"  !CDS_PN = "34";
"REFIN":   PN = "39"  !CDS_PN = "39";
"SW":   PN = "10_19"  !CDS_PN = "10_19";
"TOUT_FLT":   PN = "36"  !CDS_PN = "36";
"VCC":   PN = "3"  !CDS_PN = "3";
"VIN1":   PN = "25_29"  !CDS_PN = "25_29";
"VIN2":   PN = "30"  !CDS_PN = "30";
"VOS":   PN = "1"  !CDS_PN = "1";
BODY = "Q_CAPP","I56": #LOCATION = "PC83" !CDS_LOCATION = "PC83" &SEC = "1" #&CDS_SEC = "1";
"A":   PN = "1"  !CDS_PN = "1";
"B":   PN = "2"  !CDS_PN = "2";
BODY = "Q_CAPP","I62": #LOCATION = "PC189" !CDS_LOCATION = "PC189" &SEC = "1" #&CDS_SEC = "1";
"A":   PN = "1"  !CDS_PN = "1";
"B":   PN = "2"  !CDS_PN = "2";
BODY = "Q_RES","I73": #LOCATION = "PR330" !CDS_LOCATION = "PR330" &SEC = "1" #&CDS_SEC = "1";
"A":   PN = "1"  !CDS_PN = "1";
"B":   PN = "2"  !CDS_PN = "2";
BODY = "Q_CAPP","I87": #LOCATION = "PC582" !CDS_LOCATION = "PC582" &SEC = "1" #&CDS_SEC = "1";
"A":   PN = "1"  !CDS_PN = "1";
"B":   PN = "2"  !CDS_PN = "2";
BODY = "Q_CAP","I88": #LOCATION = "PC576_P1_1" !CDS_LOCATION = "PC576_P1_1" &SEC = "1" #&CDS_SEC = "1";
"A":   PN = "1"  !CDS_PN = "1";
"B":   PN = "2"  !CDS_PN = "2";
BODY = "Q_CAP","I91": #LOCATION = "PC578_P1_1" !CDS_LOCATION = "PC578_P1_1" &SEC = "1" #&CDS_SEC = "1";
"A":   PN = "1"  !CDS_PN = "1";
"B":   PN = "2"  !CDS_PN = "2";
BODY = "Q_CAPP","I96": #LOCATION = "PC2346" !CDS_LOCATION = "PC2346" &SEC = "1" #&CDS_SEC = "1";
"A":   PN = "1"  !CDS_PN = "1";
"B":   PN = "2"  !CDS_PN = "2";
BODY = "ISL99390FRZTR5935","I7": #LOCATION = "PU30_P1_2" !CDS_LOCATION = "PU30_P1_2" &SEC = "1" #&CDS_SEC = "1";
"AGND":   PN = "2"  !CDS_PN = "2";
"BOOT":   PN = "33"  !CDS_PN = "33";
"DNC":   PN = "31"  !CDS_PN = "31";
"EN":   PN = "35"  !CDS_PN = "35";
"GL1":   PN = "6"  !CDS_PN = "6";
"GL2":   PN = "41"  !CDS_PN = "41";
"IOUT":   PN = "38"  !CDS_PN = "38";
"LSET":   PN = "37"  !CDS_PN = "37";
"PGND1":   PN = "5"  !CDS_PN = "5";
"PGND2":   PN = "7_9-20_24"  !CDS_PN = "7_9-20_24";
"PGND3":   PN = "40"  !CDS_PN = "40";
"PHASE":   PN = "32"  !CDS_PN = "32";
"PVCC":   PN = "4"  !CDS_PN = "4";
"PWM":   PN = "34"  !CDS_PN = "34";
"REFIN":   PN = "39"  !CDS_PN = "39";
"SW":   PN = "10_19"  !CDS_PN = "10_19";
"TOUT_FLT":   PN = "36"  !CDS_PN = "36";
"VCC":   PN = "3"  !CDS_PN = "3";
"VIN1":   PN = "25_29"  !CDS_PN = "25_29";
"VIN2":   PN = "30"  !CDS_PN = "30";
"VOS":   PN = "1"  !CDS_PN = "1";
BODY = "Q_RES","I13": #LOCATION = "PR327" !CDS_LOCATION = "PR327" &SEC = "1" #&CDS_SEC = "1";
"A":   PN = "1"  !CDS_PN = "1";
"B":   PN = "2"  !CDS_PN = "2";
BODY = "Q_INDUCTOR4P_14","I18": #LOCATION = "PL30" !CDS_LOCATION = "PL30" #SEC = "1" !CDS_SEC = "1";
"1":   PN = "1"  !CDS_PN = "1";
"2":   PN = "2"  !CDS_PN = "2";
"3":   PN = "3"  !CDS_PN = "3";
"4":   PN = "4"  !CDS_PN = "4";
BODY = "Q_RES","I26": #LOCATION = "PR639" !CDS_LOCATION = "PR639" &SEC = "1" #&CDS_SEC = "1";
"A":   PN = "1"  !CDS_PN = "1";
"B":   PN = "2"  !CDS_PN = "2";
BODY = "Q_CAP","I34": #LOCATION = "PC1339" !CDS_LOCATION = "PC1339" &SEC = "1" #&CDS_SEC = "1";
"A":   PN = "1"  !CDS_PN = "1";
"B":   PN = "2"  !CDS_PN = "2";
BODY = "Q_CAP","I36": #LOCATION = "PC557" !CDS_LOCATION = "PC557" &SEC = "1" #&CDS_SEC = "1";
"A":   PN = "1"  !CDS_PN = "1";
"B":   PN = "2"  !CDS_PN = "2";
BODY = "Q_RES","I41": #LOCATION = "PR640" !CDS_LOCATION = "PR640" &SEC = "1" #&CDS_SEC = "1";
"A":   PN = "1"  !CDS_PN = "1";
"B":   PN = "2"  !CDS_PN = "2";
BODY = "Q_CAP","I44": #LOCATION = "PC561_P1_1" !CDS_LOCATION = "PC561_P1_1" &SEC = "1" #&CDS_SEC = "1";
"A":   PN = "1"  !CDS_PN = "1";
"B":   PN = "2"  !CDS_PN = "2";
BODY = "Q_RES","I51": #LOCATION = "PR329" !CDS_LOCATION = "PR329" &SEC = "1" #&CDS_SEC = "1";
"A":   PN = "1"  !CDS_PN = "1";
"B":   PN = "2"  !CDS_PN = "2";
BODY = "Q_CAP","I53": #LOCATION = "PC570_P1_2" !CDS_LOCATION = "PC570_P1_2" &SEC = "1" #&CDS_SEC = "1";
"A":   PN = "1"  !CDS_PN = "1";
"B":   PN = "2"  !CDS_PN = "2";
BODY = "Q_CAPP","I64": #LOCATION = "PC583" !CDS_LOCATION = "PC583" &SEC = "1" #&CDS_SEC = "1";
"A":   PN = "1"  !CDS_PN = "1";
"B":   PN = "2"  !CDS_PN = "2";
BODY = "Q_CAPP","I68": #LOCATION = "PC590" !CDS_LOCATION = "PC590" &SEC = "1" #&CDS_SEC = "1";
"A":   PN = "1"  !CDS_PN = "1";
"B":   PN = "2"  !CDS_PN = "2";
BODY = "Q_CAP","I76": #LOCATION = "PC571_P1_1" !CDS_LOCATION = "PC571_P1_1" &SEC = "1" #&CDS_SEC = "1";
"A":   PN = "1"  !CDS_PN = "1";
"B":   PN = "2"  !CDS_PN = "2";
BODY = "Q_CAPP","I86": #LOCATION = "PC579" !CDS_LOCATION = "PC579" &SEC = "1" #&CDS_SEC = "1";
"A":   PN = "1"  !CDS_PN = "1";
"B":   PN = "2"  !CDS_PN = "2";
BODY = "Q_CAPP","I92": #LOCATION = "PC585" !CDS_LOCATION = "PC585" &SEC = "1" #&CDS_SEC = "1";
"A":   PN = "1"  !CDS_PN = "1";
"B":   PN = "2"  !CDS_PN = "2";
BODY = "Q_CAPP","I94": #LOCATION = "PC588" !CDS_LOCATION = "PC588" &SEC = "1" #&CDS_SEC = "1";
"A":   PN = "1"  !CDS_PN = "1";
"B":   PN = "2"  !CDS_PN = "2";
DRAWING = "@s9s_mb_2u_lib.s9s_mb_2u(sch_1):page272";
BODY = "Q_CAP","I11": #LOCATION = "PC523" !CDS_LOCATION = "PC523" &SEC = "1" #&CDS_SEC = "1";
"A":   PN = "1"  !CDS_PN = "1";
"B":   PN = "2"  !CDS_PN = "2";
BODY = "Q_RES","I12": #LOCATION = "PR299" !CDS_LOCATION = "PR299" &SEC = "1" #&CDS_SEC = "1";
"A":   PN = "1"  !CDS_PN = "1";
"B":   PN = "2"  !CDS_PN = "2";
BODY = "Q_CAP","I27": #LOCATION = "PC1359" !CDS_LOCATION = "PC1359" &SEC = "1" #&CDS_SEC = "1";
"A":   PN = "1"  !CDS_PN = "1";
"B":   PN = "2"  !CDS_PN = "2";
BODY = "Q_RES","I34": #LOCATION = "PR1788" !CDS_LOCATION = "PR1788" &SEC = "1" #&CDS_SEC = "1";
"A":   PN = "1"  !CDS_PN = "1";
"B":   PN = "2"  !CDS_PN = "2";
BODY = "Q_CAP","I35": #LOCATION = "PC529_P1_4" !CDS_LOCATION = "PC529_P1_4" &SEC = "1" #&CDS_SEC = "1";
"A":   PN = "1"  !CDS_PN = "1";
"B":   PN = "2"  !CDS_PN = "2";
BODY = "Q_CAP","I36": #LOCATION = "PC533_P1_4" !CDS_LOCATION = "PC533_P1_4" &SEC = "1" #&CDS_SEC = "1";
"A":   PN = "1"  !CDS_PN = "1";
"B":   PN = "2"  !CDS_PN = "2";
BODY = "Q_CAP","I41": #LOCATION = "PC535_P1_4" !CDS_LOCATION = "PC535_P1_4" &SEC = "1" #&CDS_SEC = "1";
"A":   PN = "1"  !CDS_PN = "1";
"B":   PN = "2"  !CDS_PN = "2";
BODY = "Q_CAP","I42": #LOCATION = "PC537_P1_4" !CDS_LOCATION = "PC537_P1_4" &SEC = "1" #&CDS_SEC = "1";
"A":   PN = "1"  !CDS_PN = "1";
"B":   PN = "2"  !CDS_PN = "2";
BODY = "Q_RES","I46": #LOCATION = "PR1789" !CDS_LOCATION = "PR1789" &SEC = "1" #&CDS_SEC = "1";
"A":   PN = "1"  !CDS_PN = "1";
"B":   PN = "2"  !CDS_PN = "2";
BODY = "Q_CAP","I48": #LOCATION = "PC528_P1_3" !CDS_LOCATION = "PC528_P1_3" &SEC = "1" #&CDS_SEC = "1";
"A":   PN = "1"  !CDS_PN = "1";
"B":   PN = "2"  !CDS_PN = "2";
BODY = "Q_CAP","I49": #LOCATION = "PC530_P1_3" !CDS_LOCATION = "PC530_P1_3" &SEC = "1" #&CDS_SEC = "1";
"A":   PN = "1"  !CDS_PN = "1";
"B":   PN = "2"  !CDS_PN = "2";
BODY = "Q_CAP","I52": #LOCATION = "PC532" !CDS_LOCATION = "PC532" &SEC = "1" #&CDS_SEC = "1";
"A":   PN = "1"  !CDS_PN = "1";
"B":   PN = "2"  !CDS_PN = "2";
BODY = "Q_CAP","I54": #LOCATION = "PC536_P1_3" !CDS_LOCATION = "PC536_P1_3" &SEC = "1" #&CDS_SEC = "1";
"A":   PN = "1"  !CDS_PN = "1";
"B":   PN = "2"  !CDS_PN = "2";
BODY = "Q_RES","I3": #LOCATION = "PR297" !CDS_LOCATION = "PR297" &SEC = "1" #&CDS_SEC = "1";
"A":   PN = "1"  !CDS_PN = "1";
"B":   PN = "2"  !CDS_PN = "2";
BODY = "Q_CAP","I6": #LOCATION = "PC1358" !CDS_LOCATION = "PC1358" &SEC = "1" #&CDS_SEC = "1";
"A":   PN = "1"  !CDS_PN = "1";
"B":   PN = "2"  !CDS_PN = "2";
BODY = "ISL99390FRZTR5935","I10": #LOCATION = "PU27_P1_4" !CDS_LOCATION = "PU27_P1_4" #SEC = "1" !CDS_SEC = "1";
"AGND":   PN = "2"  !CDS_PN = "2";
"BOOT":   PN = "33"  !CDS_PN = "33";
"DNC":   PN = "31"  !CDS_PN = "31";
"EN":   PN = "35"  !CDS_PN = "35";
"GL1":   PN = "6"  !CDS_PN = "6";
"GL2":   PN = "41"  !CDS_PN = "41";
"IOUT":   PN = "38"  !CDS_PN = "38";
"LSET":   PN = "37"  !CDS_PN = "37";
"PGND1":   PN = "5"  !CDS_PN = "5";
"PGND2":   PN = "7_9-20_24"  !CDS_PN = "7_9-20_24";
"PGND3":   PN = "40"  !CDS_PN = "40";
"PHASE":   PN = "32"  !CDS_PN = "32";
"PVCC":   PN = "4"  !CDS_PN = "4";
"PWM":   PN = "34"  !CDS_PN = "34";
"REFIN":   PN = "39"  !CDS_PN = "39";
"SW":   PN = "10_19"  !CDS_PN = "10_19";
"TOUT_FLT":   PN = "36"  !CDS_PN = "36";
"VCC":   PN = "3"  !CDS_PN = "3";
"VIN1":   PN = "25_29"  !CDS_PN = "25_29";
"VIN2":   PN = "30"  !CDS_PN = "30";
"VOS":   PN = "1"  !CDS_PN = "1";
BODY = "Q_RES","I15": #LOCATION = "PR298" !CDS_LOCATION = "PR298" &SEC = "1" #&CDS_SEC = "1";
"A":   PN = "1"  !CDS_PN = "1";
"B":   PN = "2"  !CDS_PN = "2";
BODY = "Q_CAP","I19": #LOCATION = "PC525_P1_4" !CDS_LOCATION = "PC525_P1_4" &SEC = "1" #&CDS_SEC = "1";
"A":   PN = "1"  !CDS_PN = "1";
"B":   PN = "2"  !CDS_PN = "2";
BODY = "Q_CAP","I24": #LOCATION = "PC524" !CDS_LOCATION = "PC524" &SEC = "1" #&CDS_SEC = "1";
"A":   PN = "1"  !CDS_PN = "1";
"B":   PN = "2"  !CDS_PN = "2";
BODY = "Q_RES","I25": #LOCATION = "PR300" !CDS_LOCATION = "PR300" &SEC = "1" #&CDS_SEC = "1";
"A":   PN = "1"  !CDS_PN = "1";
"B":   PN = "2"  !CDS_PN = "2";
BODY = "Q_CAP","I29": #LOCATION = "PC526_P1_3" !CDS_LOCATION = "PC526_P1_3" &SEC = "1" #&CDS_SEC = "1";
"A":   PN = "1"  !CDS_PN = "1";
"B":   PN = "2"  !CDS_PN = "2";
BODY = "Q_CAP","I33": #LOCATION = "PC527_P1_4" !CDS_LOCATION = "PC527_P1_4" &SEC = "1" #&CDS_SEC = "1";
"A":   PN = "1"  !CDS_PN = "1";
"B":   PN = "2"  !CDS_PN = "2";
BODY = "Q_INDUCTOR4P_14","I37": #LOCATION = "PL28" !CDS_LOCATION = "PL28" #SEC = "1" !CDS_SEC = "1";
"1":   PN = "1"  !CDS_PN = "1";
"2":   PN = "2"  !CDS_PN = "2";
"3":   PN = "3"  !CDS_PN = "3";
"4":   PN = "4"  !CDS_PN = "4";
BODY = "Q_RES","I38": #LOCATION = "PR301" !CDS_LOCATION = "PR301" &SEC = "1" #&CDS_SEC = "1";
"A":   PN = "1"  !CDS_PN = "1";
"B":   PN = "2"  !CDS_PN = "2";
BODY = "Q_CAP","I39": #LOCATION = "PC531" !CDS_LOCATION = "PC531" &SEC = "1" #&CDS_SEC = "1";
"A":   PN = "1"  !CDS_PN = "1";
"B":   PN = "2"  !CDS_PN = "2";
BODY = "Q_RES","I45": #LOCATION = "PR302" !CDS_LOCATION = "PR302" &SEC = "1" #&CDS_SEC = "1";
"A":   PN = "1"  !CDS_PN = "1";
"B":   PN = "2"  !CDS_PN = "2";
BODY = "Q_CAP","I50": #LOCATION = "PC534_P1_3" !CDS_LOCATION = "PC534_P1_3" &SEC = "1" #&CDS_SEC = "1";
"A":   PN = "1"  !CDS_PN = "1";
"B":   PN = "2"  !CDS_PN = "2";
BODY = "Q_INDUCTOR4P_14","I51": #LOCATION = "PL29" !CDS_LOCATION = "PL29" #SEC = "1" !CDS_SEC = "1";
"1":   PN = "1"  !CDS_PN = "1";
"2":   PN = "2"  !CDS_PN = "2";
"3":   PN = "3"  !CDS_PN = "3";
"4":   PN = "4"  !CDS_PN = "4";
BODY = "Q_CAP","I55": #LOCATION = "PC538_P1_3" !CDS_LOCATION = "PC538_P1_3" &SEC = "1" #&CDS_SEC = "1";
"A":   PN = "1"  !CDS_PN = "1";
"B":   PN = "2"  !CDS_PN = "2";
BODY = "Q_CAP","I58": #LOCATION = "PC541_P1_4" !CDS_LOCATION = "PC541_P1_4" &SEC = "1" #&CDS_SEC = "1";
"A":   PN = "1"  !CDS_PN = "1";
"B":   PN = "2"  !CDS_PN = "2";
BODY = "Q_CAP","I59": #LOCATION = "PC543_P1_4" !CDS_LOCATION = "PC543_P1_4" &SEC = "1" #&CDS_SEC = "1";
"A":   PN = "1"  !CDS_PN = "1";
"B":   PN = "2"  !CDS_PN = "2";
BODY = "Q_CAP","I63": #LOCATION = "PC542_P1_3" !CDS_LOCATION = "PC542_P1_3" &SEC = "1" #&CDS_SEC = "1";
"A":   PN = "1"  !CDS_PN = "1";
"B":   PN = "2"  !CDS_PN = "2";
BODY = "Q_CAP","I64": #LOCATION = "PC544_P1_3" !CDS_LOCATION = "PC544_P1_3" &SEC = "1" #&CDS_SEC = "1";
"A":   PN = "1"  !CDS_PN = "1";
"B":   PN = "2"  !CDS_PN = "2";
BODY = "ISL99390FRZTR5935","I66": #LOCATION = "PU28_P1_3" !CDS_LOCATION = "PU28_P1_3" &SEC = "1" #&CDS_SEC = "1";
"AGND":   PN = "2"  !CDS_PN = "2";
"BOOT":   PN = "33"  !CDS_PN = "33";
"DNC":   PN = "31"  !CDS_PN = "31";
"EN":   PN = "35"  !CDS_PN = "35";
"GL1":   PN = "6"  !CDS_PN = "6";
"GL2":   PN = "41"  !CDS_PN = "41";
"IOUT":   PN = "38"  !CDS_PN = "38";
"LSET":   PN = "37"  !CDS_PN = "37";
"PGND1":   PN = "5"  !CDS_PN = "5";
"PGND2":   PN = "7_9-20_24"  !CDS_PN = "7_9-20_24";
"PGND3":   PN = "40"  !CDS_PN = "40";
"PHASE":   PN = "32"  !CDS_PN = "32";
"PVCC":   PN = "4"  !CDS_PN = "4";
"PWM":   PN = "34"  !CDS_PN = "34";
"REFIN":   PN = "39"  !CDS_PN = "39";
"SW":   PN = "10_19"  !CDS_PN = "10_19";
"TOUT_FLT":   PN = "36"  !CDS_PN = "36";
"VCC":   PN = "3"  !CDS_PN = "3";
"VIN1":   PN = "25_29"  !CDS_PN = "25_29";
"VIN2":   PN = "30"  !CDS_PN = "30";
"VOS":   PN = "1"  !CDS_PN = "1";
DRAWING = "@s9s_mb_2u_lib.s9s_mb_2u(sch_1):page273";
BODY = "Q_RES","I2": #LOCATION = "PR291" !CDS_LOCATION = "PR291" &SEC = "1" #&CDS_SEC = "1";
"A":   PN = "1"  !CDS_PN = "1";
"B":   PN = "2"  !CDS_PN = "2";
BODY = "Q_CAP","I21": #LOCATION = "PC503_P1_6" !CDS_LOCATION = "PC503_P1_6" &SEC = "1" #&CDS_SEC = "1";
"A":   PN = "1"  !CDS_PN = "1";
"B":   PN = "2"  !CDS_PN = "2";
BODY = "ISL99390FRZTR5935","I23": #LOCATION = "PU26_P1_5" !CDS_LOCATION = "PU26_P1_5" &SEC = "1" #&CDS_SEC = "1";
"AGND":   PN = "2"  !CDS_PN = "2";
"BOOT":   PN = "33"  !CDS_PN = "33";
"DNC":   PN = "31"  !CDS_PN = "31";
"EN":   PN = "35"  !CDS_PN = "35";
"GL1":   PN = "6"  !CDS_PN = "6";
"GL2":   PN = "41"  !CDS_PN = "41";
"IOUT":   PN = "38"  !CDS_PN = "38";
"LSET":   PN = "37"  !CDS_PN = "37";
"PGND1":   PN = "5"  !CDS_PN = "5";
"PGND2":   PN = "7_9-20_24"  !CDS_PN = "7_9-20_24";
"PGND3":   PN = "40"  !CDS_PN = "40";
"PHASE":   PN = "32"  !CDS_PN = "32";
"PVCC":   PN = "4"  !CDS_PN = "4";
"PWM":   PN = "34"  !CDS_PN = "34";
"REFIN":   PN = "39"  !CDS_PN = "39";
"SW":   PN = "10_19"  !CDS_PN = "10_19";
"TOUT_FLT":   PN = "36"  !CDS_PN = "36";
"VCC":   PN = "3"  !CDS_PN = "3";
"VIN1":   PN = "25_29"  !CDS_PN = "25_29";
"VIN2":   PN = "30"  !CDS_PN = "30";
"VOS":   PN = "1"  !CDS_PN = "1";
BODY = "Q_INDUCTOR4P_14","I28": #LOCATION = "PL26" !CDS_LOCATION = "PL26" #SEC = "1" !CDS_SEC = "1";
"1":   PN = "1"  !CDS_PN = "1";
"2":   PN = "2"  !CDS_PN = "2";
"3":   PN = "3"  !CDS_PN = "3";
"4":   PN = "4"  !CDS_PN = "4";
BODY = "Q_CAP","I29": #LOCATION = "PC505_P1_6" !CDS_LOCATION = "PC505_P1_6" &SEC = "1" #&CDS_SEC = "1";
"A":   PN = "1"  !CDS_PN = "1";
"B":   PN = "2"  !CDS_PN = "2";
BODY = "Q_CAP","I31": #LOCATION = "PC507_P1_6" !CDS_LOCATION = "PC507_P1_6" &SEC = "1" #&CDS_SEC = "1";
"A":   PN = "1"  !CDS_PN = "1";
"B":   PN = "2"  !CDS_PN = "2";
BODY = "Q_CAP","I34": #LOCATION = "PC513_P1_6" !CDS_LOCATION = "PC513_P1_6" &SEC = "1" #&CDS_SEC = "1";
"A":   PN = "1"  !CDS_PN = "1";
"B":   PN = "2"  !CDS_PN = "2";
BODY = "Q_CAP","I36": #LOCATION = "PC1361" !CDS_LOCATION = "PC1361" &SEC = "1" #&CDS_SEC = "1";
"A":   PN = "1"  !CDS_PN = "1";
"B":   PN = "2"  !CDS_PN = "2";
BODY = "Q_CAP","I37": #LOCATION = "PC502" !CDS_LOCATION = "PC502" &SEC = "1" #&CDS_SEC = "1";
"A":   PN = "1"  !CDS_PN = "1";
"B":   PN = "2"  !CDS_PN = "2";
BODY = "Q_RES","I39": #LOCATION = "PR294" !CDS_LOCATION = "PR294" &SEC = "1" #&CDS_SEC = "1";
"A":   PN = "1"  !CDS_PN = "1";
"B":   PN = "2"  !CDS_PN = "2";
BODY = "Q_CAP","I41": #LOCATION = "PC504_P1_5" !CDS_LOCATION = "PC504_P1_5" &SEC = "1" #&CDS_SEC = "1";
"A":   PN = "1"  !CDS_PN = "1";
"B":   PN = "2"  !CDS_PN = "2";
BODY = "Q_RES","I44": #LOCATION = "PR1791" !CDS_LOCATION = "PR1791" &SEC = "1" #&CDS_SEC = "1";
"A":   PN = "1"  !CDS_PN = "1";
"B":   PN = "2"  !CDS_PN = "2";
BODY = "Q_CAP","I45": #LOCATION = "PC506_P1_5" !CDS_LOCATION = "PC506_P1_5" &SEC = "1" #&CDS_SEC = "1";
"A":   PN = "1"  !CDS_PN = "1";
"B":   PN = "2"  !CDS_PN = "2";
BODY = "Q_CAP","I47": #LOCATION = "PC510" !CDS_LOCATION = "PC510" &SEC = "1" #&CDS_SEC = "1";
"A":   PN = "1"  !CDS_PN = "1";
"B":   PN = "2"  !CDS_PN = "2";
BODY = "Q_INDUCTOR4P_14","I48": #LOCATION = "PL27" !CDS_LOCATION = "PL27" #SEC = "1" !CDS_SEC = "1";
"1":   PN = "1"  !CDS_PN = "1";
"2":   PN = "2"  !CDS_PN = "2";
"3":   PN = "3"  !CDS_PN = "3";
"4":   PN = "4"  !CDS_PN = "4";
BODY = "Q_RES","I49": #LOCATION = "PR296" !CDS_LOCATION = "PR296" &SEC = "1" #&CDS_SEC = "1";
"A":   PN = "1"  !CDS_PN = "1";
"B":   PN = "2"  !CDS_PN = "2";
BODY = "Q_CAP","I50": #LOCATION = "PC512_P1_5" !CDS_LOCATION = "PC512_P1_5" &SEC = "1" #&CDS_SEC = "1";
"A":   PN = "1"  !CDS_PN = "1";
"B":   PN = "2"  !CDS_PN = "2";
BODY = "Q_CAP","I54": #LOCATION = "PC519_P1_6" !CDS_LOCATION = "PC519_P1_6" &SEC = "1" #&CDS_SEC = "1";
"A":   PN = "1"  !CDS_PN = "1";
"B":   PN = "2"  !CDS_PN = "2";
BODY = "Q_RES","I7": #LOCATION = "PR292" !CDS_LOCATION = "PR292" &SEC = "1" #&CDS_SEC = "1";
"A":   PN = "1"  !CDS_PN = "1";
"B":   PN = "2"  !CDS_PN = "2";
BODY = "Q_CAP","I15": #LOCATION = "PC1360" !CDS_LOCATION = "PC1360" &SEC = "1" #&CDS_SEC = "1";
"A":   PN = "1"  !CDS_PN = "1";
"B":   PN = "2"  !CDS_PN = "2";
BODY = "ISL99390FRZTR5935","I16": #LOCATION = "PU25_P1_6" !CDS_LOCATION = "PU25_P1_6" &SEC = "1" #&CDS_SEC = "1";
"AGND":   PN = "2"  !CDS_PN = "2";
"BOOT":   PN = "33"  !CDS_PN = "33";
"DNC":   PN = "31"  !CDS_PN = "31";
"EN":   PN = "35"  !CDS_PN = "35";
"GL1":   PN = "6"  !CDS_PN = "6";
"GL2":   PN = "41"  !CDS_PN = "41";
"IOUT":   PN = "38"  !CDS_PN = "38";
"LSET":   PN = "37"  !CDS_PN = "37";
"PGND1":   PN = "5"  !CDS_PN = "5";
"PGND2":   PN = "7_9-20_24"  !CDS_PN = "7_9-20_24";
"PGND3":   PN = "40"  !CDS_PN = "40";
"PHASE":   PN = "32"  !CDS_PN = "32";
"PVCC":   PN = "4"  !CDS_PN = "4";
"PWM":   PN = "34"  !CDS_PN = "34";
"REFIN":   PN = "39"  !CDS_PN = "39";
"SW":   PN = "10_19"  !CDS_PN = "10_19";
"TOUT_FLT":   PN = "36"  !CDS_PN = "36";
"VCC":   PN = "3"  !CDS_PN = "3";
"VIN1":   PN = "25_29"  !CDS_PN = "25_29";
"VIN2":   PN = "30"  !CDS_PN = "30";
"VOS":   PN = "1"  !CDS_PN = "1";
BODY = "Q_CAP","I17": #LOCATION = "PC501" !CDS_LOCATION = "PC501" &SEC = "1" #&CDS_SEC = "1";
"A":   PN = "1"  !CDS_PN = "1";
"B":   PN = "2"  !CDS_PN = "2";
BODY = "Q_RES","I19": #LOCATION = "PR293" !CDS_LOCATION = "PR293" &SEC = "1" #&CDS_SEC = "1";
"A":   PN = "1"  !CDS_PN = "1";
"B":   PN = "2"  !CDS_PN = "2";
BODY = "Q_CAP","I26": #LOCATION = "PC509" !CDS_LOCATION = "PC509" &SEC = "1" #&CDS_SEC = "1";
"A":   PN = "1"  !CDS_PN = "1";
"B":   PN = "2"  !CDS_PN = "2";
BODY = "Q_RES","I27": #LOCATION = "PR295" !CDS_LOCATION = "PR295" &SEC = "1" #&CDS_SEC = "1";
"A":   PN = "1"  !CDS_PN = "1";
"B":   PN = "2"  !CDS_PN = "2";
BODY = "Q_RES","I30": #LOCATION = "PR1790" !CDS_LOCATION = "PR1790" &SEC = "1" #&CDS_SEC = "1";
"A":   PN = "1"  !CDS_PN = "1";
"B":   PN = "2"  !CDS_PN = "2";
BODY = "Q_CAP","I33": #LOCATION = "PC511_P1_6" !CDS_LOCATION = "PC511_P1_6" &SEC = "1" #&CDS_SEC = "1";
"A":   PN = "1"  !CDS_PN = "1";
"B":   PN = "2"  !CDS_PN = "2";
BODY = "Q_CAP","I35": #LOCATION = "PC515_P1_6" !CDS_LOCATION = "PC515_P1_6" &SEC = "1" #&CDS_SEC = "1";
"A":   PN = "1"  !CDS_PN = "1";
"B":   PN = "2"  !CDS_PN = "2";
BODY = "Q_CAP","I46": #LOCATION = "PC508_P1_5" !CDS_LOCATION = "PC508_P1_5" &SEC = "1" #&CDS_SEC = "1";
"A":   PN = "1"  !CDS_PN = "1";
"B":   PN = "2"  !CDS_PN = "2";
BODY = "Q_CAP","I51": #LOCATION = "PC514_P1_5" !CDS_LOCATION = "PC514_P1_5" &SEC = "1" #&CDS_SEC = "1";
"A":   PN = "1"  !CDS_PN = "1";
"B":   PN = "2"  !CDS_PN = "2";
BODY = "Q_CAP","I52": #LOCATION = "PC516_P1_5" !CDS_LOCATION = "PC516_P1_5" &SEC = "1" #&CDS_SEC = "1";
"A":   PN = "1"  !CDS_PN = "1";
"B":   PN = "2"  !CDS_PN = "2";
BODY = "Q_CAP","I57": #LOCATION = "PC521_P1_6" !CDS_LOCATION = "PC521_P1_6" &SEC = "1" #&CDS_SEC = "1";
"A":   PN = "1"  !CDS_PN = "1";
"B":   PN = "2"  !CDS_PN = "2";
BODY = "Q_CAP","I64": #LOCATION = "PC520_P1_5" !CDS_LOCATION = "PC520_P1_5" &SEC = "1" #&CDS_SEC = "1";
"A":   PN = "1"  !CDS_PN = "1";
"B":   PN = "2"  !CDS_PN = "2";
BODY = "Q_CAP","I65": #LOCATION = "PC522_P1_5" !CDS_LOCATION = "PC522_P1_5" &SEC = "1" #&CDS_SEC = "1";
"A":   PN = "1"  !CDS_PN = "1";
"B":   PN = "2"  !CDS_PN = "2";
DRAWING = "@s9s_mb_2u_lib.s9s_mb_2u(sch_1):page274";
BODY = "Q_CAP","I9": #LOCATION = "PC479" !CDS_LOCATION = "PC479" &SEC = "1" #&CDS_SEC = "1";
"A":   PN = "1"  !CDS_PN = "1";
"B":   PN = "2"  !CDS_PN = "2";
BODY = "Q_CAP","I18": #LOCATION = "PC481_P1_8" !CDS_LOCATION = "PC481_P1_8" &SEC = "1" #&CDS_SEC = "1";
"A":   PN = "1"  !CDS_PN = "1";
"B":   PN = "2"  !CDS_PN = "2";
BODY = "Q_RES","I26": #LOCATION = "PR1792" !CDS_LOCATION = "PR1792" &SEC = "1" #&CDS_SEC = "1";
"A":   PN = "1"  !CDS_PN = "1";
"B":   PN = "2"  !CDS_PN = "2";
BODY = "Q_CAP","I28": #LOCATION = "PC489_P1_8" !CDS_LOCATION = "PC489_P1_8" &SEC = "1" #&CDS_SEC = "1";
"A":   PN = "1"  !CDS_PN = "1";
"B":   PN = "2"  !CDS_PN = "2";
BODY = "Q_CAP","I32": #LOCATION = "PC1363" !CDS_LOCATION = "PC1363" &SEC = "1" #&CDS_SEC = "1";
"A":   PN = "1"  !CDS_PN = "1";
"B":   PN = "2"  !CDS_PN = "2";
BODY = "Q_CAP","I34": #LOCATION = "PC480" !CDS_LOCATION = "PC480" &SEC = "1" #&CDS_SEC = "1";
"A":   PN = "1"  !CDS_PN = "1";
"B":   PN = "2"  !CDS_PN = "2";
BODY = "Q_CAP","I37": #LOCATION = "PC484_P1_7" !CDS_LOCATION = "PC484_P1_7" &SEC = "1" #&CDS_SEC = "1";
"A":   PN = "1"  !CDS_PN = "1";
"B":   PN = "2"  !CDS_PN = "2";
BODY = "Q_RES","I39": #LOCATION = "PR1793" !CDS_LOCATION = "PR1793" &SEC = "1" #&CDS_SEC = "1";
"A":   PN = "1"  !CDS_PN = "1";
"B":   PN = "2"  !CDS_PN = "2";
BODY = "Q_CAP","I40": #LOCATION = "PC486_P1_7" !CDS_LOCATION = "PC486_P1_7" &SEC = "1" #&CDS_SEC = "1";
"A":   PN = "1"  !CDS_PN = "1";
"B":   PN = "2"  !CDS_PN = "2";
BODY = "Q_CAP","I41": #LOCATION = "PC490_P1_7" !CDS_LOCATION = "PC490_P1_7" &SEC = "1" #&CDS_SEC = "1";
"A":   PN = "1"  !CDS_PN = "1";
"B":   PN = "2"  !CDS_PN = "2";
BODY = "Q_CAP","I42": #LOCATION = "PC487" !CDS_LOCATION = "PC487" &SEC = "1" #&CDS_SEC = "1";
"A":   PN = "1"  !CDS_PN = "1";
"B":   PN = "2"  !CDS_PN = "2";
BODY = "Q_INDUCTOR4P_14","I43": #LOCATION = "PL24" !CDS_LOCATION = "PL24" #SEC = "1" !CDS_SEC = "1";
"1":   PN = "1"  !CDS_PN = "1";
"2":   PN = "2"  !CDS_PN = "2";
"3":   PN = "3"  !CDS_PN = "3";
"4":   PN = "4"  !CDS_PN = "4";
BODY = "Q_RES","I44": #LOCATION = "PR289" !CDS_LOCATION = "PR289" &SEC = "1" #&CDS_SEC = "1";
"A":   PN = "1"  !CDS_PN = "1";
"B":   PN = "2"  !CDS_PN = "2";
BODY = "Q_CAP","I46": #LOCATION = "PC491_P1_8" !CDS_LOCATION = "PC491_P1_8" &SEC = "1" #&CDS_SEC = "1";
"A":   PN = "1"  !CDS_PN = "1";
"B":   PN = "2"  !CDS_PN = "2";
BODY = "Q_CAP","I47": #LOCATION = "PC493_P1_8" !CDS_LOCATION = "PC493_P1_8" &SEC = "1" #&CDS_SEC = "1";
"A":   PN = "1"  !CDS_PN = "1";
"B":   PN = "2"  !CDS_PN = "2";
BODY = "Q_CAP","I52": #LOCATION = "PC495_P1_8" !CDS_LOCATION = "PC495_P1_8" &SEC = "1" #&CDS_SEC = "1";
"A":   PN = "1"  !CDS_PN = "1";
"B":   PN = "2"  !CDS_PN = "2";
BODY = "Q_CAP","I53": #LOCATION = "PC497_P1_8" !CDS_LOCATION = "PC497_P1_8" &SEC = "1" #&CDS_SEC = "1";
"A":   PN = "1"  !CDS_PN = "1";
"B":   PN = "2"  !CDS_PN = "2";
BODY = "Q_CAP","I54": #LOCATION = "PC499_P1_8" !CDS_LOCATION = "PC499_P1_8" &SEC = "1" #&CDS_SEC = "1";
"A":   PN = "1"  !CDS_PN = "1";
"B":   PN = "2"  !CDS_PN = "2";
BODY = "Q_RES","I3": #LOCATION = "PR285" !CDS_LOCATION = "PR285" &SEC = "1" #&CDS_SEC = "1";
"A":   PN = "1"  !CDS_PN = "1";
"B":   PN = "2"  !CDS_PN = "2";
BODY = "Q_CAP","I7": #LOCATION = "PC1362" !CDS_LOCATION = "PC1362" &SEC = "1" #&CDS_SEC = "1";
"A":   PN = "1"  !CDS_PN = "1";
"B":   PN = "2"  !CDS_PN = "2";
BODY = "ISL99390FRZTR5935","I11": #LOCATION = "PU23_P1_8" !CDS_LOCATION = "PU23_P1_8" &SEC = "1" #&CDS_SEC = "1";
"AGND":   PN = "2"  !CDS_PN = "2";
"BOOT":   PN = "33"  !CDS_PN = "33";
"DNC":   PN = "31"  !CDS_PN = "31";
"EN":   PN = "35"  !CDS_PN = "35";
"GL1":   PN = "6"  !CDS_PN = "6";
"GL2":   PN = "41"  !CDS_PN = "41";
"IOUT":   PN = "38"  !CDS_PN = "38";
"LSET":   PN = "37"  !CDS_PN = "37";
"PGND1":   PN = "5"  !CDS_PN = "5";
"PGND2":   PN = "7_9-20_24"  !CDS_PN = "7_9-20_24";
"PGND3":   PN = "40"  !CDS_PN = "40";
"PHASE":   PN = "32"  !CDS_PN = "32";
"PVCC":   PN = "4"  !CDS_PN = "4";
"PWM":   PN = "34"  !CDS_PN = "34";
"REFIN":   PN = "39"  !CDS_PN = "39";
"SW":   PN = "10_19"  !CDS_PN = "10_19";
"TOUT_FLT":   PN = "36"  !CDS_PN = "36";
"VCC":   PN = "3"  !CDS_PN = "3";
"VIN1":   PN = "25_29"  !CDS_PN = "25_29";
"VIN2":   PN = "30"  !CDS_PN = "30";
"VOS":   PN = "1"  !CDS_PN = "1";
BODY = "Q_RES","I12": #LOCATION = "PR287" !CDS_LOCATION = "PR287" &SEC = "1" #&CDS_SEC = "1";
"A":   PN = "1"  !CDS_PN = "1";
"B":   PN = "2"  !CDS_PN = "2";
BODY = "Q_RES","I15": #LOCATION = "PR286" !CDS_LOCATION = "PR286" &SEC = "1" #&CDS_SEC = "1";
"A":   PN = "1"  !CDS_PN = "1";
"B":   PN = "2"  !CDS_PN = "2";
BODY = "ISL99390FRZTR5935","I20": #LOCATION = "PU24_P1_7" !CDS_LOCATION = "PU24_P1_7" &SEC = "1" #&CDS_SEC = "1";
"AGND":   PN = "2"  !CDS_PN = "2";
"BOOT":   PN = "33"  !CDS_PN = "33";
"DNC":   PN = "31"  !CDS_PN = "31";
"EN":   PN = "35"  !CDS_PN = "35";
"GL1":   PN = "6"  !CDS_PN = "6";
"GL2":   PN = "41"  !CDS_PN = "41";
"IOUT":   PN = "38"  !CDS_PN = "38";
"LSET":   PN = "37"  !CDS_PN = "37";
"PGND1":   PN = "5"  !CDS_PN = "5";
"PGND2":   PN = "7_9-20_24"  !CDS_PN = "7_9-20_24";
"PGND3":   PN = "40"  !CDS_PN = "40";
"PHASE":   PN = "32"  !CDS_PN = "32";
"PVCC":   PN = "4"  !CDS_PN = "4";
"PWM":   PN = "34"  !CDS_PN = "34";
"REFIN":   PN = "39"  !CDS_PN = "39";
"SW":   PN = "10_19"  !CDS_PN = "10_19";
"TOUT_FLT":   PN = "36"  !CDS_PN = "36";
"VCC":   PN = "3"  !CDS_PN = "3";
"VIN1":   PN = "25_29"  !CDS_PN = "25_29";
"VIN2":   PN = "30"  !CDS_PN = "30";
"VOS":   PN = "1"  !CDS_PN = "1";
BODY = "Q_INDUCTOR","I23": #LOCATION = "PL106" !CDS_LOCATION = "PL106" &SEC = "1" #&CDS_SEC = "1";
"1":   PN = "1"  !CDS_PN = "1";
"2":   PN = "2"  !CDS_PN = "2";
BODY = "Q_CAP","I24": #LOCATION = "PC483_P1_8" !CDS_LOCATION = "PC483_P1_8" &SEC = "1" #&CDS_SEC = "1";
"A":   PN = "1"  !CDS_PN = "1";
"B":   PN = "2"  !CDS_PN = "2";
BODY = "Q_CAP","I27": #LOCATION = "PC485_P1_8" !CDS_LOCATION = "PC485_P1_8" &SEC = "1" #&CDS_SEC = "1";
"A":   PN = "1"  !CDS_PN = "1";
"B":   PN = "2"  !CDS_PN = "2";
BODY = "Q_RES","I50": #LOCATION = "PR290" !CDS_LOCATION = "PR290" &SEC = "1" #&CDS_SEC = "1";
"A":   PN = "1"  !CDS_PN = "1";
"B":   PN = "2"  !CDS_PN = "2";
BODY = "Q_INDUCTOR4P_14","I58": #LOCATION = "PL25" !CDS_LOCATION = "PL25" #SEC = "1" !CDS_SEC = "1";
"1":   PN = "1"  !CDS_PN = "1";
"2":   PN = "2"  !CDS_PN = "2";
"3":   PN = "3"  !CDS_PN = "3";
"4":   PN = "4"  !CDS_PN = "4";
BODY = "Q_CAP","I59": #LOCATION = "PC488" !CDS_LOCATION = "PC488" &SEC = "1" #&CDS_SEC = "1";
"A":   PN = "1"  !CDS_PN = "1";
"B":   PN = "2"  !CDS_PN = "2";
BODY = "Q_CAP","I61": #LOCATION = "PC492_P1_7" !CDS_LOCATION = "PC492_P1_7" &SEC = "1" #&CDS_SEC = "1";
"A":   PN = "1"  !CDS_PN = "1";
"B":   PN = "2"  !CDS_PN = "2";
BODY = "Q_CAP","I62": #LOCATION = "PC494_P1_7" !CDS_LOCATION = "PC494_P1_7" &SEC = "1" #&CDS_SEC = "1";
"A":   PN = "1"  !CDS_PN = "1";
"B":   PN = "2"  !CDS_PN = "2";
BODY = "Q_CAP","I64": #LOCATION = "PC496_P1_7" !CDS_LOCATION = "PC496_P1_7" &SEC = "1" #&CDS_SEC = "1";
"A":   PN = "1"  !CDS_PN = "1";
"B":   PN = "2"  !CDS_PN = "2";
BODY = "Q_CAP","I65": #LOCATION = "PC498_P1_7" !CDS_LOCATION = "PC498_P1_7" &SEC = "1" #&CDS_SEC = "1";
"A":   PN = "1"  !CDS_PN = "1";
"B":   PN = "2"  !CDS_PN = "2";
BODY = "Q_CAP","I66": #LOCATION = "PC500_P1_7" !CDS_LOCATION = "PC500_P1_7" &SEC = "1" #&CDS_SEC = "1";
"A":   PN = "1"  !CDS_PN = "1";
"B":   PN = "2"  !CDS_PN = "2";
BODY = "Q_RES","I68": #LOCATION = "PR288" !CDS_LOCATION = "PR288" &SEC = "1" #&CDS_SEC = "1";
"A":   PN = "1"  !CDS_PN = "1";
"B":   PN = "2"  !CDS_PN = "2";
BODY = "Q_CAP","I69": #LOCATION = "PC482_P1_7" !CDS_LOCATION = "PC482_P1_7" &SEC = "1" #&CDS_SEC = "1";
"A":   PN = "1"  !CDS_PN = "1";
"B":   PN = "2"  !CDS_PN = "2";
DRAWING = "@s9s_mb_2u_lib.s9s_mb_2u(sch_1):page276";
BODY = "Q_RES","I2": #LOCATION = "PR1304" !CDS_LOCATION = "PR1304" &SEC = "1" #&CDS_SEC = "1";
"A":   PN = "1"  !CDS_PN = "1";
"B":   PN = "2"  !CDS_PN = "2";
BODY = "Q_CAP","I33": #LOCATION = "PC1194_P1_4" !CDS_LOCATION = "PC1194_P1_4" &SEC = "1" #&CDS_SEC = "1";
"A":   PN = "1"  !CDS_PN = "1";
"B":   PN = "2"  !CDS_PN = "2";
BODY = "Q_CAP","I36": #LOCATION = "PC1200_P1_4" !CDS_LOCATION = "PC1200_P1_4" &SEC = "1" #&CDS_SEC = "1";
"A":   PN = "1"  !CDS_PN = "1";
"B":   PN = "2"  !CDS_PN = "2";
BODY = "Q_RES","I40": #LOCATION = "PR1802" !CDS_LOCATION = "PR1802" &SEC = "1" #&CDS_SEC = "1";
"A":   PN = "1"  !CDS_PN = "1";
"B":   PN = "2"  !CDS_PN = "2";
BODY = "Q_INDUCTOR","I44": #LOCATION = "PL113" !CDS_LOCATION = "PL113" &SEC = "1" #&CDS_SEC = "1";
"1":   PN = "1"  !CDS_PN = "1";
"2":   PN = "2"  !CDS_PN = "2";
BODY = "Q_CAP","I45": #LOCATION = "PC1198" !CDS_LOCATION = "PC1198" &SEC = "1" #&CDS_SEC = "1";
"A":   PN = "1"  !CDS_PN = "1";
"B":   PN = "2"  !CDS_PN = "2";
BODY = "Q_CAPP","I55": #LOCATION = "PC1201" !CDS_LOCATION = "PC1201" &SEC = "1" #&CDS_SEC = "1";
"A":   PN = "1"  !CDS_PN = "1";
"B":   PN = "2"  !CDS_PN = "2";
BODY = "Q_CAP","I56": #LOCATION = "PC1204_P1_3" !CDS_LOCATION = "PC1204_P1_3" &SEC = "1" #&CDS_SEC = "1";
"A":   PN = "1"  !CDS_PN = "1";
"B":   PN = "2"  !CDS_PN = "2";
BODY = "Q_CAPP","I67": #LOCATION = "PC1203" !CDS_LOCATION = "PC1203" &SEC = "1" #&CDS_SEC = "1";
"A":   PN = "1"  !CDS_PN = "1";
"B":   PN = "2"  !CDS_PN = "2";
BODY = "Q_CAP","I68": #LOCATION = "PC1208_P1_3" !CDS_LOCATION = "PC1208_P1_3" &SEC = "1" #&CDS_SEC = "1";
"A":   PN = "1"  !CDS_PN = "1";
"B":   PN = "2"  !CDS_PN = "2";
BODY = "Q_CAP","I77": #LOCATION = "PC1682" !CDS_LOCATION = "PC1682" &SEC = "1" #&CDS_SEC = "1";
"A":   PN = "1"  !CDS_PN = "1";
"B":   PN = "2"  !CDS_PN = "2";
BODY = "Q_CAP","I38": #LOCATION = "PC1193_P1_3" !CDS_LOCATION = "PC1193_P1_3" &SEC = "1" #&CDS_SEC = "1";
"A":   PN = "1"  !CDS_PN = "1";
"B":   PN = "2"  !CDS_PN = "2";
BODY = "Q_CAP","I41": #LOCATION = "PC1199_P1_3" !CDS_LOCATION = "PC1199_P1_3" &SEC = "1" #&CDS_SEC = "1";
"A":   PN = "1"  !CDS_PN = "1";
"B":   PN = "2"  !CDS_PN = "2";
BODY = "Q_INDUCTOR","I57": #LOCATION = "PL12" !CDS_LOCATION = "PL12" &SEC = "1" #&CDS_SEC = "1";
"1":   PN = "1"  !CDS_PN = "1";
"2":   PN = "2"  !CDS_PN = "2";
BODY = "ISL99390FRZTR5935","I15": #LOCATION = "PU78_P1_4" !CDS_LOCATION = "PU78_P1_4" &SEC = "1" #&CDS_SEC = "1";
"AGND":   PN = "2"  !CDS_PN = "2";
"BOOT":   PN = "33"  !CDS_PN = "33";
"DNC":   PN = "31"  !CDS_PN = "31";
"EN":   PN = "35"  !CDS_PN = "35";
"GL1":   PN = "6"  !CDS_PN = "6";
"GL2":   PN = "41"  !CDS_PN = "41";
"IOUT":   PN = "38"  !CDS_PN = "38";
"LSET":   PN = "37"  !CDS_PN = "37";
"PGND1":   PN = "5"  !CDS_PN = "5";
"PGND2":   PN = "7_9-20_24"  !CDS_PN = "7_9-20_24";
"PGND3":   PN = "40"  !CDS_PN = "40";
"PHASE":   PN = "32"  !CDS_PN = "32";
"PVCC":   PN = "4"  !CDS_PN = "4";
"PWM":   PN = "34"  !CDS_PN = "34";
"REFIN":   PN = "39"  !CDS_PN = "39";
"SW":   PN = "10_19"  !CDS_PN = "10_19";
"TOUT_FLT":   PN = "36"  !CDS_PN = "36";
"VCC":   PN = "3"  !CDS_PN = "3";
"VIN1":   PN = "25_29"  !CDS_PN = "25_29";
"VIN2":   PN = "30"  !CDS_PN = "30";
"VOS":   PN = "1"  !CDS_PN = "1";
BODY = "Q_RES","I18": #LOCATION = "PR1307" !CDS_LOCATION = "PR1307" &SEC = "1" #&CDS_SEC = "1";
"A":   PN = "1"  !CDS_PN = "1";
"B":   PN = "2"  !CDS_PN = "2";
BODY = "Q_CAP","I27": #LOCATION = "PC1191" !CDS_LOCATION = "PC1191" &SEC = "1" #&CDS_SEC = "1";
"A":   PN = "1"  !CDS_PN = "1";
"B":   PN = "2"  !CDS_PN = "2";
BODY = "Q_CAP","I37": #LOCATION = "PC1202_P1_4" !CDS_LOCATION = "PC1202_P1_4" &SEC = "1" #&CDS_SEC = "1";
"A":   PN = "1"  !CDS_PN = "1";
"B":   PN = "2"  !CDS_PN = "2";
BODY = "Q_CAP","I39": #LOCATION = "PC1195_P1_3" !CDS_LOCATION = "PC1195_P1_3" &SEC = "1" #&CDS_SEC = "1";
"A":   PN = "1"  !CDS_PN = "1";
"B":   PN = "2"  !CDS_PN = "2";
BODY = "Q_CAP","I42": #LOCATION = "PC1201_P1_3" !CDS_LOCATION = "PC1201_P1_3" &SEC = "1" #&CDS_SEC = "1";
"A":   PN = "1"  !CDS_PN = "1";
"B":   PN = "2"  !CDS_PN = "2";
BODY = "Q_INDUCTOR","I64": #LOCATION = "PL14" !CDS_LOCATION = "PL14" &SEC = "1" #&CDS_SEC = "1";
"1":   PN = "1"  !CDS_PN = "1";
"2":   PN = "2"  !CDS_PN = "2";
BODY = "Q_CAP","I66": #LOCATION = "PC1206_P1_3" !CDS_LOCATION = "PC1206_P1_3" &SEC = "1" #&CDS_SEC = "1";
"A":   PN = "1"  !CDS_PN = "1";
"B":   PN = "2"  !CDS_PN = "2";
BODY = "Q_CAP","I80": #LOCATION = "PC1684" !CDS_LOCATION = "PC1684" &SEC = "1" #&CDS_SEC = "1";
"A":   PN = "1"  !CDS_PN = "1";
"B":   PN = "2"  !CDS_PN = "2";
BODY = "Q_CAP","I23": #LOCATION = "PC1369" !CDS_LOCATION = "PC1369" &SEC = "1" #&CDS_SEC = "1";
"A":   PN = "1"  !CDS_PN = "1";
"B":   PN = "2"  !CDS_PN = "2";
BODY = "ISL99390FRZTR5935","I24": #LOCATION = "PU77_P1_3" !CDS_LOCATION = "PU77_P1_3" &SEC = "1" #&CDS_SEC = "1";
"AGND":   PN = "2"  !CDS_PN = "2";
"BOOT":   PN = "33"  !CDS_PN = "33";
"DNC":   PN = "31"  !CDS_PN = "31";
"EN":   PN = "35"  !CDS_PN = "35";
"GL1":   PN = "6"  !CDS_PN = "6";
"GL2":   PN = "41"  !CDS_PN = "41";
"IOUT":   PN = "38"  !CDS_PN = "38";
"LSET":   PN = "37"  !CDS_PN = "37";
"PGND1":   PN = "5"  !CDS_PN = "5";
"PGND2":   PN = "7_9-20_24"  !CDS_PN = "7_9-20_24";
"PGND3":   PN = "40"  !CDS_PN = "40";
"PHASE":   PN = "32"  !CDS_PN = "32";
"PVCC":   PN = "4"  !CDS_PN = "4";
"PWM":   PN = "34"  !CDS_PN = "34";
"REFIN":   PN = "39"  !CDS_PN = "39";
"SW":   PN = "10_19"  !CDS_PN = "10_19";
"TOUT_FLT":   PN = "36"  !CDS_PN = "36";
"VCC":   PN = "3"  !CDS_PN = "3";
"VIN1":   PN = "25_29"  !CDS_PN = "25_29";
"VIN2":   PN = "30"  !CDS_PN = "30";
"VOS":   PN = "1"  !CDS_PN = "1";
BODY = "Q_CAP","I31": #LOCATION = "PC1244_P1_3" !CDS_LOCATION = "PC1244_P1_3" &SEC = "1" #&CDS_SEC = "1";
"A":   PN = "1"  !CDS_PN = "1";
"B":   PN = "2"  !CDS_PN = "2";
BODY = "Q_CAP","I35": #LOCATION = "PC1196_P1_4" !CDS_LOCATION = "PC1196_P1_4" &SEC = "1" #&CDS_SEC = "1";
"A":   PN = "1"  !CDS_PN = "1";
"B":   PN = "2"  !CDS_PN = "2";
BODY = "Q_CAP","I50": #LOCATION = "PC1209_P1_4" !CDS_LOCATION = "PC1209_P1_4" &SEC = "1" #&CDS_SEC = "1";
"A":   PN = "1"  !CDS_PN = "1";
"B":   PN = "2"  !CDS_PN = "2";
BODY = "Q_CAP","I52": #LOCATION = "PC727_P1_4" !CDS_LOCATION = "PC727_P1_4" &SEC = "1" #&CDS_SEC = "1";
"A":   PN = "1"  !CDS_PN = "1";
"B":   PN = "2"  !CDS_PN = "2";
BODY = "Q_RES","I54": #LOCATION = "PR1333" !CDS_LOCATION = "PR1333" &SEC = "1" #&CDS_SEC = "1";
"A":   PN = "1"  !CDS_PN = "1";
"B":   PN = "2"  !CDS_PN = "2";
BODY = "Q_CAPP","I70": #LOCATION = "PC1204" !CDS_LOCATION = "PC1204" &SEC = "1" #&CDS_SEC = "1";
"A":   PN = "1"  !CDS_PN = "1";
"B":   PN = "2"  !CDS_PN = "2";
BODY = "Q_CAPP","I72": #LOCATION = "PC1205" !CDS_LOCATION = "PC1205" &SEC = "1" #&CDS_SEC = "1";
"A":   PN = "1"  !CDS_PN = "1";
"B":   PN = "2"  !CDS_PN = "2";
BODY = "Q_RES","I5": #LOCATION = "PR1305" !CDS_LOCATION = "PR1305" &SEC = "1" #&CDS_SEC = "1";
"A":   PN = "1"  !CDS_PN = "1";
"B":   PN = "2"  !CDS_PN = "2";
BODY = "Q_CAP","I12": #LOCATION = "PC1192" !CDS_LOCATION = "PC1192" &SEC = "1" #&CDS_SEC = "1";
"A":   PN = "1"  !CDS_PN = "1";
"B":   PN = "2"  !CDS_PN = "2";
BODY = "Q_CAP","I13": #LOCATION = "PC1370" !CDS_LOCATION = "PC1370" &SEC = "1" #&CDS_SEC = "1";
"A":   PN = "1"  !CDS_PN = "1";
"B":   PN = "2"  !CDS_PN = "2";
BODY = "Q_RES","I17": #LOCATION = "PR1803" !CDS_LOCATION = "PR1803" &SEC = "1" #&CDS_SEC = "1";
"A":   PN = "1"  !CDS_PN = "1";
"B":   PN = "2"  !CDS_PN = "2";
BODY = "Q_CAP","I20": #LOCATION = "PC1245_P1_4" !CDS_LOCATION = "PC1245_P1_4" &SEC = "1" #&CDS_SEC = "1";
"A":   PN = "1"  !CDS_PN = "1";
"B":   PN = "2"  !CDS_PN = "2";
BODY = "Q_RES","I29": #LOCATION = "PR1306" !CDS_LOCATION = "PR1306" &SEC = "1" #&CDS_SEC = "1";
"A":   PN = "1"  !CDS_PN = "1";
"B":   PN = "2"  !CDS_PN = "2";
BODY = "Q_RES","I43": #LOCATION = "PR1334" !CDS_LOCATION = "PR1334" &SEC = "1" #&CDS_SEC = "1";
"A":   PN = "1"  !CDS_PN = "1";
"B":   PN = "2"  !CDS_PN = "2";
BODY = "Q_CAP","I47": #LOCATION = "PC1203_P1_4" !CDS_LOCATION = "PC1203_P1_4" &SEC = "1" #&CDS_SEC = "1";
"A":   PN = "1"  !CDS_PN = "1";
"B":   PN = "2"  !CDS_PN = "2";
BODY = "Q_CAP","I48": #LOCATION = "PC1207_P1_4" !CDS_LOCATION = "PC1207_P1_4" &SEC = "1" #&CDS_SEC = "1";
"A":   PN = "1"  !CDS_PN = "1";
"B":   PN = "2"  !CDS_PN = "2";
BODY = "Q_CAP","I58": #LOCATION = "PC1197" !CDS_LOCATION = "PC1197" &SEC = "1" #&CDS_SEC = "1";
"A":   PN = "1"  !CDS_PN = "1";
"B":   PN = "2"  !CDS_PN = "2";
BODY = "Q_CAP","I60": #LOCATION = "PC726_P1_3" !CDS_LOCATION = "PC726_P1_3" &SEC = "1" #&CDS_SEC = "1";
"A":   PN = "1"  !CDS_PN = "1";
"B":   PN = "2"  !CDS_PN = "2";
BODY = "Q_CAP","I62": #LOCATION = "PC1658" !CDS_LOCATION = "PC1658" &SEC = "1" #&CDS_SEC = "1";
"A":   PN = "1"  !CDS_PN = "1";
"B":   PN = "2"  !CDS_PN = "2";
BODY = "Q_CAPP","I73": #LOCATION = "PC2171" !CDS_LOCATION = "PC2171" &SEC = "1" #&CDS_SEC = "1";
"A":   PN = "1"  !CDS_PN = "1";
"B":   PN = "2"  !CDS_PN = "2";
BODY = "Q_CAP","I75": #LOCATION = "PC1681" !CDS_LOCATION = "PC1681" &SEC = "1" #&CDS_SEC = "1";
"A":   PN = "1"  !CDS_PN = "1";
"B":   PN = "2"  !CDS_PN = "2";
BODY = "Q_CAP","I78": #LOCATION = "PC1683" !CDS_LOCATION = "PC1683" &SEC = "1" #&CDS_SEC = "1";
"A":   PN = "1"  !CDS_PN = "1";
"B":   PN = "2"  !CDS_PN = "2";
BODY = "Q_CAPP","I81": #LOCATION = "PC1210" !CDS_LOCATION = "PC1210" &SEC = "1" #&CDS_SEC = "1";
"A":   PN = "1"  !CDS_PN = "1";
"B":   PN = "2"  !CDS_PN = "2";
DRAWING = "@s9s_mb_2u_lib.s9s_mb_2u(sch_1):page278";
BODY = "Q_RES","I22": #LOCATION = "PR260" !CDS_LOCATION = "PR260" &SEC = "1" #&CDS_SEC = "1";
"A":   PN = "1"  !CDS_PN = "1";
"B":   PN = "2"  !CDS_PN = "2";
BODY = "Q_RES","I26": #LOCATION = "PR275" !CDS_LOCATION = "PR275" &SEC = "1" #&CDS_SEC = "1";
"A":   PN = "1"  !CDS_PN = "1";
"B":   PN = "2"  !CDS_PN = "2";
BODY = "Q_CAP","I51": #LOCATION = "PC469" !CDS_LOCATION = "PC469" &SEC = "1" #&CDS_SEC = "1";
"A":   PN = "1"  !CDS_PN = "1";
"B":   PN = "2"  !CDS_PN = "2";
BODY = "Q_RES","I52": #LOCATION = "PR274" !CDS_LOCATION = "PR274" &SEC = "1" #&CDS_SEC = "1";
"A":   PN = "1"  !CDS_PN = "1";
"B":   PN = "2"  !CDS_PN = "2";
BODY = "Q_SHORT","I54": #LOCATION = "PJ50" !CDS_LOCATION = "PJ50" &SEC = "1" #&CDS_SEC = "1";
"1":   PN = "1"  !CDS_PN = "1";
"2":   PN = "2"  !CDS_PN = "2";
BODY = "Q_RES","I57": #LOCATION = "R2563" !CDS_LOCATION = "R2563" &SEC = "1" #&CDS_SEC = "1";
"A":   PN = "1"  !CDS_PN = "1";
"B":   PN = "2"  !CDS_PN = "2";
BODY = "Q_RES","I59": #LOCATION = "R2561" !CDS_LOCATION = "R2561" &SEC = "1" #&CDS_SEC = "1";
"A":   PN = "1"  !CDS_PN = "1";
"B":   PN = "2"  !CDS_PN = "2";
BODY = "Q_RES","I61": #LOCATION = "R2559" !CDS_LOCATION = "R2559" &SEC = "1" #&CDS_SEC = "1";
"A":   PN = "1"  !CDS_PN = "1";
"B":   PN = "2"  !CDS_PN = "2";
BODY = "Q_RES","I15": #LOCATION = "R2345" !CDS_LOCATION = "R2345" &SEC = "1" #&CDS_SEC = "1";
"A":   PN = "1"  !CDS_PN = "1";
"B":   PN = "2"  !CDS_PN = "2";
BODY = "Q_RES","I31": #LOCATION = "R2570" !CDS_LOCATION = "R2570" &SEC = "1" #&CDS_SEC = "1";
"A":   PN = "1"  !CDS_PN = "1";
"B":   PN = "2"  !CDS_PN = "2";
BODY = "Q_CAP","I53": #LOCATION = "PC468" !CDS_LOCATION = "PC468" &SEC = "1" #&CDS_SEC = "1";
"A":   PN = "1"  !CDS_PN = "1";
"B":   PN = "2"  !CDS_PN = "2";
BODY = "Q_RES","I55": #LOCATION = "PR568" !CDS_LOCATION = "PR568" &SEC = "1" #&CDS_SEC = "1";
"A":   PN = "1"  !CDS_PN = "1";
"B":   PN = "2"  !CDS_PN = "2";
BODY = "Q_RES","I60": #LOCATION = "R2560" !CDS_LOCATION = "R2560" &SEC = "1" #&CDS_SEC = "1";
"A":   PN = "1"  !CDS_PN = "1";
"B":   PN = "2"  !CDS_PN = "2";
BODY = "Q_RES","I62": #LOCATION = "PR273" !CDS_LOCATION = "PR273" &SEC = "1" #&CDS_SEC = "1";
"A":   PN = "1"  !CDS_PN = "1";
"B":   PN = "2"  !CDS_PN = "2";
BODY = "Q_CAP","I66": #LOCATION = "PC475" !CDS_LOCATION = "PC475" &SEC = "1" #&CDS_SEC = "1";
"A":   PN = "1"  !CDS_PN = "1";
"B":   PN = "2"  !CDS_PN = "2";
BODY = "Q_RES","I73": #LOCATION = "R2573" !CDS_LOCATION = "R2573" &SEC = "1" #&CDS_SEC = "1";
"A":   PN = "1"  !CDS_PN = "1";
"B":   PN = "2"  !CDS_PN = "2";
BODY = "Q_CAP","I32": #LOCATION = "C2453" !CDS_LOCATION = "C2453" &SEC = "1" #&CDS_SEC = "1";
"A":   PN = "1"  !CDS_PN = "1";
"B":   PN = "2"  !CDS_PN = "2";
BODY = "Q_CAP","I33": #LOCATION = "C2452" !CDS_LOCATION = "C2452" &SEC = "1" #&CDS_SEC = "1";
"A":   PN = "1"  !CDS_PN = "1";
"B":   PN = "2"  !CDS_PN = "2";
BODY = "Q_RES","I14": #LOCATION = "R2354" !CDS_LOCATION = "R2354" &SEC = "1" #&CDS_SEC = "1";
"A":   PN = "1"  !CDS_PN = "1";
"B":   PN = "2"  !CDS_PN = "2";
BODY = "Q_RES","I21": #LOCATION = "PR261" !CDS_LOCATION = "PR261" &SEC = "1" #&CDS_SEC = "1";
"A":   PN = "1"  !CDS_PN = "1";
"B":   PN = "2"  !CDS_PN = "2";
BODY = "Q_RES","I23": #LOCATION = "PR258" !CDS_LOCATION = "PR258" &SEC = "1" #&CDS_SEC = "1";
"A":   PN = "1"  !CDS_PN = "1";
"B":   PN = "2"  !CDS_PN = "2";
BODY = "Q_CAP","I28": #LOCATION = "PC467" !CDS_LOCATION = "PC467" &SEC = "1" #&CDS_SEC = "1";
"A":   PN = "1"  !CDS_PN = "1";
"B":   PN = "2"  !CDS_PN = "2";
BODY = "Q_SHORT","I44": #LOCATION = "PJ51" !CDS_LOCATION = "PJ51" &SEC = "1" #&CDS_SEC = "1";
"1":   PN = "1"  !CDS_PN = "1";
"2":   PN = "2"  !CDS_PN = "2";
BODY = "Q_CAP","I69": #LOCATION = "PC1292" !CDS_LOCATION = "PC1292" &SEC = "1" #&CDS_SEC = "1";
"A":   PN = "1"  !CDS_PN = "1";
"B":   PN = "2"  !CDS_PN = "2";
BODY = "Q_RES","I78": #LOCATION = "PR4246" !CDS_LOCATION = "PR4246" &SEC = "1" #&CDS_SEC = "1";
"A":   PN = "1"  !CDS_PN = "1";
"B":   PN = "2"  !CDS_PN = "2";
BODY = "Q_RES","I79": #LOCATION = "PR4245" !CDS_LOCATION = "PR4245" &SEC = "1" #&CDS_SEC = "1";
"A":   PN = "1"  !CDS_PN = "1";
"B":   PN = "2"  !CDS_PN = "2";
BODY = "Q_RES","I80": #LOCATION = "PR4244" !CDS_LOCATION = "PR4244" &SEC = "1" #&CDS_SEC = "1";
"A":   PN = "1"  !CDS_PN = "1";
"B":   PN = "2"  !CDS_PN = "2";
BODY = "Q_RES","I81": #LOCATION = "PR4243" !CDS_LOCATION = "PR4243" &SEC = "1" #&CDS_SEC = "1";
"A":   PN = "1"  !CDS_PN = "1";
"B":   PN = "2"  !CDS_PN = "2";
BODY = "Q_CAP","I93": #LOCATION = "PC476" !CDS_LOCATION = "PC476" &SEC = "1" #&CDS_SEC = "1";
"A":   PN = "1"  !CDS_PN = "1";
"B":   PN = "2"  !CDS_PN = "2";
BODY = "Q_CAP","I97": #LOCATION = "PC478" !CDS_LOCATION = "PC478" &SEC = "1" #&CDS_SEC = "1";
"A":   PN = "1"  !CDS_PN = "1";
"B":   PN = "2"  !CDS_PN = "2";
BODY = "Q_RES","I103": #LOCATION = "R4781" !CDS_LOCATION = "R4781" &SEC = "1" #&CDS_SEC = "1";
"A":   PN = "1"  !CDS_PN = "1";
"B":   PN = "2"  !CDS_PN = "2";
BODY = "Q_RES","I29": #LOCATION = "R2572" !CDS_LOCATION = "R2572" &SEC = "1" #&CDS_SEC = "1";
"A":   PN = "1"  !CDS_PN = "1";
"B":   PN = "2"  !CDS_PN = "2";
BODY = "Q_RES","I30": #LOCATION = "R2571" !CDS_LOCATION = "R2571" &SEC = "1" #&CDS_SEC = "1";
"A":   PN = "1"  !CDS_PN = "1";
"B":   PN = "2"  !CDS_PN = "2";
BODY = "Q_RES","I35": #LOCATION = "PR276" !CDS_LOCATION = "PR276" &SEC = "1" #&CDS_SEC = "1";
"A":   PN = "1"  !CDS_PN = "1";
"B":   PN = "2"  !CDS_PN = "2";
BODY = "Q_CAP","I36": #LOCATION = "PC474" !CDS_LOCATION = "PC474" &SEC = "1" #&CDS_SEC = "1";
"A":   PN = "1"  !CDS_PN = "1";
"B":   PN = "2"  !CDS_PN = "2";
BODY = "ISL69260IRAZT","I38": #LOCATION = "PU22" !CDS_LOCATION = "PU22" &SEC = "1" #&CDS_SEC = "1";
"ADDR_CFG":   PN = "34"  !CDS_PN = "34";
"CFP":   PN = "33"  !CDS_PN = "33";
"CS0":   PN = "30"  !CDS_PN = "30";
"CS1":   PN = "29"  !CDS_PN = "29";
"CS2":   PN = "28"  !CDS_PN = "28";
"CS3":   PN = "27"  !CDS_PN = "27";
"CS4":   PN = "26"  !CDS_PN = "26";
"CS5":   PN = "25"  !CDS_PN = "25";
"CS6":   PN = "24"  !CDS_PN = "24";
"CS7":   PN = "23"  !CDS_PN = "23";
"EN0":   PN = "13"  !CDS_PN = "13";
"EN1":   PN = "20"  !CDS_PN = "20";
"PG0":   PN = "12"  !CDS_PN = "12";
"PG1":   PN = "16"  !CDS_PN = "16";
"PMSCL":   PN = "10"  !CDS_PN = "10";
"PMSDA":   PN = "9"  !CDS_PN = "9";
"PWM0":   PN = "1"  !CDS_PN = "1";
"PWM1":   PN = "2"  !CDS_PN = "2";
"PWM2":   PN = "3"  !CDS_PN = "3";
"PWM3":   PN = "4"  !CDS_PN = "4";
"PWM4":   PN = "5"  !CDS_PN = "5";
"PWM5":   PN = "6"  !CDS_PN = "6";
"PWM6":   PN = "7"  !CDS_PN = "7";
"PWM7":   PN = "8"  !CDS_PN = "8";
"RGND0":   PN = "22"  !CDS_PN = "22";
"RGND1":   PN = "31"  !CDS_PN = "31";
"SVCLK":   PN = "17"  !CDS_PN = "17";
"SVDATA":   PN = "18"  !CDS_PN = "18";
"TEMP0":   PN = "35"  !CDS_PN = "35";
"TEMP1||ISYS":   PN = "36"  !CDS_PN = "36";
"TH_GND":   PN = "TH"  !CDS_PN = "TH";
"VCC":   PN = "39"  !CDS_PN = "39";
"VCCS":   PN = "40"  !CDS_PN = "40";
"VSEN0":   PN = "21"  !CDS_PN = "21";
"VSEN1":   PN = "32"  !CDS_PN = "32";
"NPINALERT#||NPSYSCRIT#":   PN = "15"  !CDS_PN = "15";
"NPMALERT#":   PN = "11"  !CDS_PN = "11";
"NSVALERT#":   PN = "19"  !CDS_PN = "19";
"NVRHOT#":   PN = "14"  !CDS_PN = "14";
"VINSEN||VSYS":   PN = "38"  !CDS_PN = "38";
"VMON||IINSEN||VSYS||ISYS":   PN = "37"  !CDS_PN = "37";
BODY = "Q_RES","I41": #LOCATION = "PR567" !CDS_LOCATION = "PR567" &SEC = "1" #&CDS_SEC = "1";
"A":   PN = "1"  !CDS_PN = "1";
"B":   PN = "2"  !CDS_PN = "2";
BODY = "Q_RES","I45": #LOCATION = "PR569" !CDS_LOCATION = "PR569" &SEC = "1" #&CDS_SEC = "1";
"A":   PN = "1"  !CDS_PN = "1";
"B":   PN = "2"  !CDS_PN = "2";
BODY = "Q_RES","I46": #LOCATION = "PR566" !CDS_LOCATION = "PR566" &SEC = "1" #&CDS_SEC = "1";
"A":   PN = "1"  !CDS_PN = "1";
"B":   PN = "2"  !CDS_PN = "2";
BODY = "Q_RES","I49": #LOCATION = "R2569" !CDS_LOCATION = "R2569" &SEC = "1" #&CDS_SEC = "1";
"A":   PN = "1"  !CDS_PN = "1";
"B":   PN = "2"  !CDS_PN = "2";
BODY = "Q_RES","I50": #LOCATION = "R2568" !CDS_LOCATION = "R2568" &SEC = "1" #&CDS_SEC = "1";
"A":   PN = "1"  !CDS_PN = "1";
"B":   PN = "2"  !CDS_PN = "2";
BODY = "Q_RES","I58": #LOCATION = "R4594" !CDS_LOCATION = "R4594" #SEC = "1" !CDS_SEC = "1";
"A":   PN = "1"  !CDS_PN = "1";
"B":   PN = "2"  !CDS_PN = "2";
BODY = "Q_CAP","I63": #LOCATION = "C2451" !CDS_LOCATION = "C2451" &SEC = "1" #&CDS_SEC = "1";
"A":   PN = "1"  !CDS_PN = "1";
"B":   PN = "2"  !CDS_PN = "2";
BODY = "Q_RES","I67": #LOCATION = "PR665" !CDS_LOCATION = "PR665" &SEC = "1" #&CDS_SEC = "1";
"A":   PN = "1"  !CDS_PN = "1";
"B":   PN = "2"  !CDS_PN = "2";
BODY = "Q_RES","I70": #LOCATION = "R2574" !CDS_LOCATION = "R2574" &SEC = "1" #&CDS_SEC = "1";
"A":   PN = "1"  !CDS_PN = "1";
"B":   PN = "2"  !CDS_PN = "2";
BODY = "Q_RES","I75": #LOCATION = "PR667" !CDS_LOCATION = "PR667" &SEC = "1" #&CDS_SEC = "1";
"A":   PN = "1"  !CDS_PN = "1";
"B":   PN = "2"  !CDS_PN = "2";
BODY = "Q_RES","I89": #LOCATION = "PR4242" !CDS_LOCATION = "PR4242" &SEC = "1" #&CDS_SEC = "1";
"A":   PN = "1"  !CDS_PN = "1";
"B":   PN = "2"  !CDS_PN = "2";
BODY = "Q_CAP","I92": #LOCATION = "PC477" !CDS_LOCATION = "PC477" &SEC = "1" #&CDS_SEC = "1";
"A":   PN = "1"  !CDS_PN = "1";
"B":   PN = "2"  !CDS_PN = "2";
BODY = "Q_CAP","I96": #LOCATION = "PC1193" !CDS_LOCATION = "PC1193" &SEC = "1" #&CDS_SEC = "1";
"A":   PN = "1"  !CDS_PN = "1";
"B":   PN = "2"  !CDS_PN = "2";
BODY = "Q_RES","I104": #LOCATION = "R2558" !CDS_LOCATION = "R2558" #SEC = "1" !CDS_SEC = "1";
"A":   PN = "1"  !CDS_PN = "1";
"B":   PN = "2"  !CDS_PN = "2";
BODY = "Q_RES","I105": #LOCATION = "R2556" !CDS_LOCATION = "R2556" &SEC = "1" #&CDS_SEC = "1";
"A":   PN = "1"  !CDS_PN = "1";
"B":   PN = "2"  !CDS_PN = "2";
BODY = "Q_CAP","I106": #LOCATION = "C2450" !CDS_LOCATION = "C2450" &SEC = "1" #&CDS_SEC = "1";
"A":   PN = "1"  !CDS_PN = "1";
"B":   PN = "2"  !CDS_PN = "2";
BODY = "Q_RES","I108": #LOCATION = "PR283" !CDS_LOCATION = "PR283" &SEC = "1" #&CDS_SEC = "1";
"A":   PN = "1"  !CDS_PN = "1";
"B":   PN = "2"  !CDS_PN = "2";
BODY = "Q_RES","I110": #LOCATION = "PR259" !CDS_LOCATION = "PR259" &SEC = "1" #&CDS_SEC = "1";
"A":   PN = "1"  !CDS_PN = "1";
"B":   PN = "2"  !CDS_PN = "2";
BODY = "Q_CAP","I111": #LOCATION = "PC2367" !CDS_LOCATION = "PC2367" &SEC = "1" #&CDS_SEC = "1";
"A":   PN = "1"  !CDS_PN = "1";
"B":   PN = "2"  !CDS_PN = "2";
DRAWING = "@s9s_mb_2u_lib.s9s_mb_2u(sch_1):page279";
BODY = "Q_RES","I11": #LOCATION = "PR255" !CDS_LOCATION = "PR255" &SEC = "1" #&CDS_SEC = "1";
"A":   PN = "1"  !CDS_PN = "1";
"B":   PN = "2"  !CDS_PN = "2";
BODY = "Q_CAP","I33": #LOCATION = "PC458_P1_2" !CDS_LOCATION = "PC458_P1_2" &SEC = "1" #&CDS_SEC = "1";
"A":   PN = "1"  !CDS_PN = "1";
"B":   PN = "2"  !CDS_PN = "2";
BODY = "Q_RES","I34": #LOCATION = "PR4247" !CDS_LOCATION = "PR4247" &SEC = "1" #&CDS_SEC = "1";
"A":   PN = "1"  !CDS_PN = "1";
"B":   PN = "2"  !CDS_PN = "2";
BODY = "Q_CAP","I36": #LOCATION = "PC443_P1_2" !CDS_LOCATION = "PC443_P1_2" &SEC = "1" #&CDS_SEC = "1";
"A":   PN = "1"  !CDS_PN = "1";
"B":   PN = "2"  !CDS_PN = "2";
BODY = "ISL99390FRZTR5935","I38": #LOCATION = "PU50_P1_1" !CDS_LOCATION = "PU50_P1_1" #SEC = "1" !CDS_SEC = "1";
"AGND":   PN = "2"  !CDS_PN = "2";
"BOOT":   PN = "33"  !CDS_PN = "33";
"DNC":   PN = "31"  !CDS_PN = "31";
"EN":   PN = "35"  !CDS_PN = "35";
"GL1":   PN = "6"  !CDS_PN = "6";
"GL2":   PN = "41"  !CDS_PN = "41";
"IOUT":   PN = "38"  !CDS_PN = "38";
"LSET":   PN = "37"  !CDS_PN = "37";
"PGND1":   PN = "5"  !CDS_PN = "5";
"PGND2":   PN = "7_9-20_24"  !CDS_PN = "7_9-20_24";
"PGND3":   PN = "40"  !CDS_PN = "40";
"PHASE":   PN = "32"  !CDS_PN = "32";
"PVCC":   PN = "4"  !CDS_PN = "4";
"PWM":   PN = "34"  !CDS_PN = "34";
"REFIN":   PN = "39"  !CDS_PN = "39";
"SW":   PN = "10_19"  !CDS_PN = "10_19";
"TOUT_FLT":   PN = "36"  !CDS_PN = "36";
"VCC":   PN = "3"  !CDS_PN = "3";
"VIN1":   PN = "25_29"  !CDS_PN = "25_29";
"VIN2":   PN = "30"  !CDS_PN = "30";
"VOS":   PN = "1"  !CDS_PN = "1";
BODY = "Q_CAP","I41": #LOCATION = "PC444_P1_1" !CDS_LOCATION = "PC444_P1_1" &SEC = "1" #&CDS_SEC = "1";
"A":   PN = "1"  !CDS_PN = "1";
"B":   PN = "2"  !CDS_PN = "2";
BODY = "Q_CAP","I43": #LOCATION = "PC449_P1_2" !CDS_LOCATION = "PC449_P1_2" &SEC = "1" #&CDS_SEC = "1";
"A":   PN = "1"  !CDS_PN = "1";
"B":   PN = "2"  !CDS_PN = "2";
BODY = "Q_CAP","I51": #LOCATION = "PC448_P1_1" !CDS_LOCATION = "PC448_P1_1" &SEC = "1" #&CDS_SEC = "1";
"A":   PN = "1"  !CDS_PN = "1";
"B":   PN = "2"  !CDS_PN = "2";
BODY = "Q_CAP","I52": #LOCATION = "PC446" !CDS_LOCATION = "PC446" &SEC = "1" #&CDS_SEC = "1";
"A":   PN = "1"  !CDS_PN = "1";
"B":   PN = "2"  !CDS_PN = "2";
BODY = "Q_CAPP","I59": #LOCATION = "PC1593" !CDS_LOCATION = "PC1593" &SEC = "1" #&CDS_SEC = "1";
"A":   PN = "1"  !CDS_PN = "1";
"B":   PN = "2"  !CDS_PN = "2";
BODY = "Q_CAPP","I62": #LOCATION = "PC1594" !CDS_LOCATION = "PC1594" &SEC = "1" #&CDS_SEC = "1";
"A":   PN = "1"  !CDS_PN = "1";
"B":   PN = "2"  !CDS_PN = "2";
BODY = "Q_CAP","I68": #LOCATION = "PC1659" !CDS_LOCATION = "PC1659" &SEC = "1" #&CDS_SEC = "1";
"A":   PN = "1"  !CDS_PN = "1";
"B":   PN = "2"  !CDS_PN = "2";
BODY = "Q_CAPP","I69": #LOCATION = "PC460" !CDS_LOCATION = "PC460" &SEC = "1" #&CDS_SEC = "1";
"A":   PN = "1"  !CDS_PN = "1";
"B":   PN = "2"  !CDS_PN = "2";
BODY = "Q_RES","I16": #LOCATION = "PR1726" !CDS_LOCATION = "PR1726" &SEC = "1" #&CDS_SEC = "1";
"A":   PN = "1"  !CDS_PN = "1";
"B":   PN = "2"  !CDS_PN = "2";
BODY = "Q_RES","I25": #LOCATION = "PR254" !CDS_LOCATION = "PR254" &SEC = "1" #&CDS_SEC = "1";
"A":   PN = "1"  !CDS_PN = "1";
"B":   PN = "2"  !CDS_PN = "2";
BODY = "ISL99390FRZTR5935","I29": #LOCATION = "PU51_P1_2" !CDS_LOCATION = "PU51_P1_2" &SEC = "1" #&CDS_SEC = "1";
"AGND":   PN = "2"  !CDS_PN = "2";
"BOOT":   PN = "33"  !CDS_PN = "33";
"DNC":   PN = "31"  !CDS_PN = "31";
"EN":   PN = "35"  !CDS_PN = "35";
"GL1":   PN = "6"  !CDS_PN = "6";
"GL2":   PN = "41"  !CDS_PN = "41";
"IOUT":   PN = "38"  !CDS_PN = "38";
"LSET":   PN = "37"  !CDS_PN = "37";
"PGND1":   PN = "5"  !CDS_PN = "5";
"PGND2":   PN = "7_9-20_24"  !CDS_PN = "7_9-20_24";
"PGND3":   PN = "40"  !CDS_PN = "40";
"PHASE":   PN = "32"  !CDS_PN = "32";
"PVCC":   PN = "4"  !CDS_PN = "4";
"PWM":   PN = "34"  !CDS_PN = "34";
"REFIN":   PN = "39"  !CDS_PN = "39";
"SW":   PN = "10_19"  !CDS_PN = "10_19";
"TOUT_FLT":   PN = "36"  !CDS_PN = "36";
"VCC":   PN = "3"  !CDS_PN = "3";
"VIN1":   PN = "25_29"  !CDS_PN = "25_29";
"VIN2":   PN = "30"  !CDS_PN = "30";
"VOS":   PN = "1"  !CDS_PN = "1";
BODY = "Q_CAP","I32": #LOCATION = "PC456_P1_2" !CDS_LOCATION = "PC456_P1_2" &SEC = "1" #&CDS_SEC = "1";
"A":   PN = "1"  !CDS_PN = "1";
"B":   PN = "2"  !CDS_PN = "2";
BODY = "Q_CAP","I37": #LOCATION = "PC445_P1_2" !CDS_LOCATION = "PC445_P1_2" &SEC = "1" #&CDS_SEC = "1";
"A":   PN = "1"  !CDS_PN = "1";
"B":   PN = "2"  !CDS_PN = "2";
BODY = "Q_RES","I42": #LOCATION = "PR1795" !CDS_LOCATION = "PR1795" &SEC = "1" #&CDS_SEC = "1";
"A":   PN = "1"  !CDS_PN = "1";
"B":   PN = "2"  !CDS_PN = "2";
BODY = "Q_CAP","I44": #LOCATION = "PC447" !CDS_LOCATION = "PC447" &SEC = "1" #&CDS_SEC = "1";
"A":   PN = "1"  !CDS_PN = "1";
"B":   PN = "2"  !CDS_PN = "2";
BODY = "Q_CAP","I45": #LOCATION = "PC451_P1_2" !CDS_LOCATION = "PC451_P1_2" &SEC = "1" #&CDS_SEC = "1";
"A":   PN = "1"  !CDS_PN = "1";
"B":   PN = "2"  !CDS_PN = "2";
BODY = "Q_INDUCTOR","I46": #LOCATION = "PL22" !CDS_LOCATION = "PL22" &SEC = "1" #&CDS_SEC = "1";
"1":   PN = "1"  !CDS_PN = "1";
"2":   PN = "2"  !CDS_PN = "2";
BODY = "Q_CAP","I53": #LOCATION = "PC450_P1_1" !CDS_LOCATION = "PC450_P1_1" &SEC = "1" #&CDS_SEC = "1";
"A":   PN = "1"  !CDS_PN = "1";
"B":   PN = "2"  !CDS_PN = "2";
BODY = "Q_CAPP","I60": #LOCATION = "PC1595" !CDS_LOCATION = "PC1595" &SEC = "1" #&CDS_SEC = "1";
"A":   PN = "1"  !CDS_PN = "1";
"B":   PN = "2"  !CDS_PN = "2";
BODY = "Q_CAPP","I61": #LOCATION = "PC1588" !CDS_LOCATION = "PC1588" &SEC = "1" #&CDS_SEC = "1";
"A":   PN = "1"  !CDS_PN = "1";
"B":   PN = "2"  !CDS_PN = "2";
BODY = "Q_CAP","I63": #LOCATION = "PC455_P1_1" !CDS_LOCATION = "PC455_P1_1" &SEC = "1" #&CDS_SEC = "1";
"A":   PN = "1"  !CDS_PN = "1";
"B":   PN = "2"  !CDS_PN = "2";
BODY = "Q_CAPP","I70": #LOCATION = "PC461" !CDS_LOCATION = "PC461" &SEC = "1" #&CDS_SEC = "1";
"A":   PN = "1"  !CDS_PN = "1";
"B":   PN = "2"  !CDS_PN = "2";
BODY = "Q_CAP","I10": #LOCATION = "PC441" !CDS_LOCATION = "PC441" &SEC = "1" #&CDS_SEC = "1";
"A":   PN = "1"  !CDS_PN = "1";
"B":   PN = "2"  !CDS_PN = "2";
BODY = "Q_CAP","I24": #LOCATION = "PC440" !CDS_LOCATION = "PC440" &SEC = "1" #&CDS_SEC = "1";
"A":   PN = "1"  !CDS_PN = "1";
"B":   PN = "2"  !CDS_PN = "2";
BODY = "Q_RES","I31": #LOCATION = "PR1797" !CDS_LOCATION = "PR1797" &SEC = "1" #&CDS_SEC = "1";
"A":   PN = "1"  !CDS_PN = "1";
"B":   PN = "2"  !CDS_PN = "2";
BODY = "Q_CAP","I40": #LOCATION = "PC442_P1_1" !CDS_LOCATION = "PC442_P1_1" &SEC = "1" #&CDS_SEC = "1";
"A":   PN = "1"  !CDS_PN = "1";
"B":   PN = "2"  !CDS_PN = "2";
BODY = "Q_RES","I49": #LOCATION = "PR1796" !CDS_LOCATION = "PR1796" &SEC = "1" #&CDS_SEC = "1";
"A":   PN = "1"  !CDS_PN = "1";
"B":   PN = "2"  !CDS_PN = "2";
BODY = "Q_RES","I50": #LOCATION = "PR1794" !CDS_LOCATION = "PR1794" &SEC = "1" #&CDS_SEC = "1";
"A":   PN = "1"  !CDS_PN = "1";
"B":   PN = "2"  !CDS_PN = "2";
BODY = "Q_INDUCTOR","I54": #LOCATION = "PL21" !CDS_LOCATION = "PL21" &SEC = "1" #&CDS_SEC = "1";
"1":   PN = "1"  !CDS_PN = "1";
"2":   PN = "2"  !CDS_PN = "2";
BODY = "Q_RES","I3": #LOCATION = "PR1727" !CDS_LOCATION = "PR1727" &SEC = "1" #&CDS_SEC = "1";
"A":   PN = "1"  !CDS_PN = "1";
"B":   PN = "2"  !CDS_PN = "2";
BODY = "Q_CAP","I6": #LOCATION = "PC1365" !CDS_LOCATION = "PC1365" &SEC = "1" #&CDS_SEC = "1";
"A":   PN = "1"  !CDS_PN = "1";
"B":   PN = "2"  !CDS_PN = "2";
BODY = "Q_CAP","I13": #LOCATION = "PC2949" !CDS_LOCATION = "PC2949" &SEC = "1" #&CDS_SEC = "1";
"A":   PN = "1"  !CDS_PN = "1";
"B":   PN = "2"  !CDS_PN = "2";
BODY = "Q_CAP","I20": #LOCATION = "PC1364" !CDS_LOCATION = "PC1364" &SEC = "1" #&CDS_SEC = "1";
"A":   PN = "1"  !CDS_PN = "1";
"B":   PN = "2"  !CDS_PN = "2";
BODY = "Q_CAP","I26": #LOCATION = "PC2950" !CDS_LOCATION = "PC2950" &SEC = "1" #&CDS_SEC = "1";
"A":   PN = "1"  !CDS_PN = "1";
"B":   PN = "2"  !CDS_PN = "2";
BODY = "Q_CAP","I55": #LOCATION = "PC452_P1_1" !CDS_LOCATION = "PC452_P1_1" &SEC = "1" #&CDS_SEC = "1";
"A":   PN = "1"  !CDS_PN = "1";
"B":   PN = "2"  !CDS_PN = "2";
BODY = "Q_CAP","I65": #LOCATION = "PC457_P1_1" !CDS_LOCATION = "PC457_P1_1" &SEC = "1" #&CDS_SEC = "1";
"A":   PN = "1"  !CDS_PN = "1";
"B":   PN = "2"  !CDS_PN = "2";
BODY = "Q_CAPP","I71": #LOCATION = "PC1596" !CDS_LOCATION = "PC1596" &SEC = "1" #&CDS_SEC = "1";
"A":   PN = "1"  !CDS_PN = "1";
"B":   PN = "2"  !CDS_PN = "2";
BODY = "Q_INDUCTOR","I78": #LOCATION = "PL23" !CDS_LOCATION = "PL23" &SEC = "1" #&CDS_SEC = "1";
"1":   PN = "1"  !CDS_PN = "1";
"2":   PN = "2"  !CDS_PN = "2";
DRAWING = "@s9s_mb_2u_lib.s9s_mb_2u(sch_1):page280";
BODY = "RAA2213404GNPHB0","I14": #LOCATION = "PU49" !CDS_LOCATION = "PU49" &SEC = "1" #&CDS_SEC = "1";
"BOOT":   PN = "20"  !CDS_PN = "20";
"FAULT#":   PN = "2"  !CDS_PN = "2";
"GL1":   PN = "5"  !CDS_PN = "5";
"GL2":   PN = "27"  !CDS_PN = "27";
"GND1":   PN = "6_7-13_15-29"  !CDS_PN = "6_7-13_15-29";
"GND2":   PN = "23"  !CDS_PN = "23";
"GND3":   PN = "26"  !CDS_PN = "26";
"IMON":   PN = "25"  !CDS_PN = "25";
"LGCTRL":   PN = "3"  !CDS_PN = "3";
"NC1":   PN = "22"  !CDS_PN = "22";
"PHASE":   PN = "19"  !CDS_PN = "19";
"PWM":   PN = "21"  !CDS_PN = "21";
"REFIN":   PN = "24"  !CDS_PN = "24";
"SW":   PN = "8_12"  !CDS_PN = "8_12";
"TMON":   PN = "1"  !CDS_PN = "1";
"VCC":   PN = "4"  !CDS_PN = "4";
"VIN":   PN = "16_18-28"  !CDS_PN = "16_18-28";
BODY = "Q_CAP","I22": #LOCATION = "PC431" !CDS_LOCATION = "PC431" &SEC = "1" #&CDS_SEC = "1";
"A":   PN = "1"  !CDS_PN = "1";
"B":   PN = "2"  !CDS_PN = "2";
BODY = "Q_INDUCTOR","I23": #LOCATION = "PL20" !CDS_LOCATION = "PL20" &SEC = "1" #&CDS_SEC = "1";
"1":   PN = "1"  !CDS_PN = "1";
"2":   PN = "2"  !CDS_PN = "2";
BODY = "Q_CAP","I24": #LOCATION = "PC429" !CDS_LOCATION = "PC429" &SEC = "1" #&CDS_SEC = "1";
"A":   PN = "1"  !CDS_PN = "1";
"B":   PN = "2"  !CDS_PN = "2";
BODY = "Q_RES","I25": #LOCATION = "PR1798" !CDS_LOCATION = "PR1798" &SEC = "1" #&CDS_SEC = "1";
"A":   PN = "1"  !CDS_PN = "1";
"B":   PN = "2"  !CDS_PN = "2";
BODY = "Q_CAP","I27": #LOCATION = "PC432" !CDS_LOCATION = "PC432" &SEC = "1" #&CDS_SEC = "1";
"A":   PN = "1"  !CDS_PN = "1";
"B":   PN = "2"  !CDS_PN = "2";
BODY = "Q_CAP","I30": #LOCATION = "PC435" !CDS_LOCATION = "PC435" &SEC = "1" #&CDS_SEC = "1";
"A":   PN = "1"  !CDS_PN = "1";
"B":   PN = "2"  !CDS_PN = "2";
BODY = "Q_CAP","I31": #LOCATION = "PC437" !CDS_LOCATION = "PC437" &SEC = "1" #&CDS_SEC = "1";
"A":   PN = "1"  !CDS_PN = "1";
"B":   PN = "2"  !CDS_PN = "2";
BODY = "Q_RES","I4": #LOCATION = "PR678" !CDS_LOCATION = "PR678" &SEC = "1" #&CDS_SEC = "1";
"A":   PN = "1"  !CDS_PN = "1";
"B":   PN = "2"  !CDS_PN = "2";
BODY = "Q_RES","I15": #LOCATION = "PR250" !CDS_LOCATION = "PR250" &SEC = "1" #&CDS_SEC = "1";
"A":   PN = "1"  !CDS_PN = "1";
"B":   PN = "2"  !CDS_PN = "2";
BODY = "Q_CAP","I26": #LOCATION = "PC430" !CDS_LOCATION = "PC430" &SEC = "1" #&CDS_SEC = "1";
"A":   PN = "1"  !CDS_PN = "1";
"B":   PN = "2"  !CDS_PN = "2";
BODY = "Q_CAP","I28": #LOCATION = "PC433" !CDS_LOCATION = "PC433" &SEC = "1" #&CDS_SEC = "1";
"A":   PN = "1"  !CDS_PN = "1";
"B":   PN = "2"  !CDS_PN = "2";
BODY = "Q_CAP","I29": #LOCATION = "PC434" !CDS_LOCATION = "PC434" &SEC = "1" #&CDS_SEC = "1";
"A":   PN = "1"  !CDS_PN = "1";
"B":   PN = "2"  !CDS_PN = "2";
BODY = "Q_CAP","I9": #LOCATION = "PC1366" !CDS_LOCATION = "PC1366" &SEC = "1" #&CDS_SEC = "1";
"A":   PN = "1"  !CDS_PN = "1";
"B":   PN = "2"  !CDS_PN = "2";
BODY = "Q_CAPP","I32": #LOCATION = "PC2199" !CDS_LOCATION = "PC2199" &SEC = "1" #&CDS_SEC = "1";
"A":   PN = "1"  !CDS_PN = "1";
"B":   PN = "2"  !CDS_PN = "2";
BODY = "Q_RES","I1": #LOCATION = "PR1728" !CDS_LOCATION = "PR1728" &SEC = "1" #&CDS_SEC = "1";
"A":   PN = "1"  !CDS_PN = "1";
"B":   PN = "2"  !CDS_PN = "2";
BODY = "Q_CAP","I11": #LOCATION = "PC428" !CDS_LOCATION = "PC428" &SEC = "1" #&CDS_SEC = "1";
"A":   PN = "1"  !CDS_PN = "1";
"B":   PN = "2"  !CDS_PN = "2";
BODY = "Q_RES","I13": #LOCATION = "PR4248" !CDS_LOCATION = "PR4248" &SEC = "1" #&CDS_SEC = "1";
"A":   PN = "1"  !CDS_PN = "1";
"B":   PN = "2"  !CDS_PN = "2";
BODY = "Q_RES","I16": #LOCATION = "PR699" !CDS_LOCATION = "PR699" &SEC = "1" #&CDS_SEC = "1";
"A":   PN = "1"  !CDS_PN = "1";
"B":   PN = "2"  !CDS_PN = "2";
BODY = "Q_RES","I18": #LOCATION = "PR4249" !CDS_LOCATION = "PR4249" &SEC = "1" #&CDS_SEC = "1";
"A":   PN = "1"  !CDS_PN = "1";
"B":   PN = "2"  !CDS_PN = "2";
BODY = "Q_RES","I20": #LOCATION = "PR1799" !CDS_LOCATION = "PR1799" &SEC = "1" #&CDS_SEC = "1";
"A":   PN = "1"  !CDS_PN = "1";
"B":   PN = "2"  !CDS_PN = "2";
BODY = "Q_CAPP","I33": #LOCATION = "PC1930" !CDS_LOCATION = "PC1930" &SEC = "1" #&CDS_SEC = "1";
"A":   PN = "1"  !CDS_PN = "1";
"B":   PN = "2"  !CDS_PN = "2";
BODY = "Q_RES","I37": #LOCATION = "PR4250" !CDS_LOCATION = "PR4250" &SEC = "1" #&CDS_SEC = "1";
"A":   PN = "1"  !CDS_PN = "1";
"B":   PN = "2"  !CDS_PN = "2";
DRAWING = "@s9s_mb_2u_lib.s9s_mb_2u(sch_1):page283";
BODY = "Q_CAP","I8": #LOCATION = "PC1371" !CDS_LOCATION = "PC1371" &SEC = "1" #&CDS_SEC = "1";
"A":   PN = "1"  !CDS_PN = "1";
"B":   PN = "2"  !CDS_PN = "2";
BODY = "Q_CAP","I18": #LOCATION = "PC2951" !CDS_LOCATION = "PC2951" &SEC = "1" #&CDS_SEC = "1";
"A":   PN = "1"  !CDS_PN = "1";
"B":   PN = "2"  !CDS_PN = "2";
BODY = "Q_CAP","I20": #LOCATION = "PC374" !CDS_LOCATION = "PC374" &SEC = "1" #&CDS_SEC = "1";
"A":   PN = "1"  !CDS_PN = "1";
"B":   PN = "2"  !CDS_PN = "2";
BODY = "Q_RES","I21": #LOCATION = "PR1804" !CDS_LOCATION = "PR1804" &SEC = "1" #&CDS_SEC = "1";
"A":   PN = "1"  !CDS_PN = "1";
"B":   PN = "2"  !CDS_PN = "2";
BODY = "Q_CAP","I23": #LOCATION = "PC377" !CDS_LOCATION = "PC377" &SEC = "1" #&CDS_SEC = "1";
"A":   PN = "1"  !CDS_PN = "1";
"B":   PN = "2"  !CDS_PN = "2";
BODY = "Q_CAP","I27": #LOCATION = "PC379" !CDS_LOCATION = "PC379" &SEC = "1" #&CDS_SEC = "1";
"A":   PN = "1"  !CDS_PN = "1";
"B":   PN = "2"  !CDS_PN = "2";
BODY = "Q_CAP","I28": #LOCATION = "PC381" !CDS_LOCATION = "PC381" &SEC = "1" #&CDS_SEC = "1";
"A":   PN = "1"  !CDS_PN = "1";
"B":   PN = "2"  !CDS_PN = "2";
BODY = "Q_RES","I12": #LOCATION = "PR1805" !CDS_LOCATION = "PR1805" &SEC = "1" #&CDS_SEC = "1";
"A":   PN = "1"  !CDS_PN = "1";
"B":   PN = "2"  !CDS_PN = "2";
BODY = "Q_CAP","I22": #LOCATION = "PC375" !CDS_LOCATION = "PC375" &SEC = "1" #&CDS_SEC = "1";
"A":   PN = "1"  !CDS_PN = "1";
"B":   PN = "2"  !CDS_PN = "2";
BODY = "Q_INDUCTOR","I14": #LOCATION = "PL17" !CDS_LOCATION = "PL17" &SEC = "1" #&CDS_SEC = "1";
"1":   PN = "1"  !CDS_PN = "1";
"2":   PN = "2"  !CDS_PN = "2";
BODY = "Q_CAP","I15": #LOCATION = "PC373" !CDS_LOCATION = "PC373" &SEC = "1" #&CDS_SEC = "1";
"A":   PN = "1"  !CDS_PN = "1";
"B":   PN = "2"  !CDS_PN = "2";
BODY = "Q_CAP","I29": #LOCATION = "PC382" !CDS_LOCATION = "PC382" &SEC = "1" #&CDS_SEC = "1";
"A":   PN = "1"  !CDS_PN = "1";
"B":   PN = "2"  !CDS_PN = "2";
BODY = "Q_RES","I3": #LOCATION = "PR1746" !CDS_LOCATION = "PR1746" &SEC = "1" #&CDS_SEC = "1";
"A":   PN = "1"  !CDS_PN = "1";
"B":   PN = "2"  !CDS_PN = "2";
BODY = "ISL99390FRZTR5935","I10": #LOCATION = "PU17" !CDS_LOCATION = "PU17" #SEC = "1" !CDS_SEC = "1";
"AGND":   PN = "2"  !CDS_PN = "2";
"BOOT":   PN = "33"  !CDS_PN = "33";
"DNC":   PN = "31"  !CDS_PN = "31";
"EN":   PN = "35"  !CDS_PN = "35";
"GL1":   PN = "6"  !CDS_PN = "6";
"GL2":   PN = "41"  !CDS_PN = "41";
"IOUT":   PN = "38"  !CDS_PN = "38";
"LSET":   PN = "37"  !CDS_PN = "37";
"PGND1":   PN = "5"  !CDS_PN = "5";
"PGND2":   PN = "7_9-20_24"  !CDS_PN = "7_9-20_24";
"PGND3":   PN = "40"  !CDS_PN = "40";
"PHASE":   PN = "32"  !CDS_PN = "32";
"PVCC":   PN = "4"  !CDS_PN = "4";
"PWM":   PN = "34"  !CDS_PN = "34";
"REFIN":   PN = "39"  !CDS_PN = "39";
"SW":   PN = "10_19"  !CDS_PN = "10_19";
"TOUT_FLT":   PN = "36"  !CDS_PN = "36";
"VCC":   PN = "3"  !CDS_PN = "3";
"VIN1":   PN = "25_29"  !CDS_PN = "25_29";
"VIN2":   PN = "30"  !CDS_PN = "30";
"VOS":   PN = "1"  !CDS_PN = "1";
BODY = "Q_RES","I16": #LOCATION = "PR200" !CDS_LOCATION = "PR200" &SEC = "1" #&CDS_SEC = "1";
"A":   PN = "1"  !CDS_PN = "1";
"B":   PN = "2"  !CDS_PN = "2";
BODY = "Q_CAP","I30": #LOCATION = "PC2" !CDS_LOCATION = "PC2" &SEC = "1" #&CDS_SEC = "1";
"A":   PN = "1"  !CDS_PN = "1";
"B":   PN = "2"  !CDS_PN = "2";
BODY = "Q_CAPP","I32": #LOCATION = "PC385" !CDS_LOCATION = "PC385" &SEC = "1" #&CDS_SEC = "1";
"A":   PN = "1"  !CDS_PN = "1";
"B":   PN = "2"  !CDS_PN = "2";
BODY = "Q_CAP","I13": #LOCATION = "PC376" !CDS_LOCATION = "PC376" &SEC = "1" #&CDS_SEC = "1";
"A":   PN = "1"  !CDS_PN = "1";
"B":   PN = "2"  !CDS_PN = "2";
BODY = "Q_CAP","I24": #LOCATION = "PC378" !CDS_LOCATION = "PC378" &SEC = "1" #&CDS_SEC = "1";
"A":   PN = "1"  !CDS_PN = "1";
"B":   PN = "2"  !CDS_PN = "2";
BODY = "Q_CAPP","I25": #LOCATION = "PC1940" !CDS_LOCATION = "PC1940" &SEC = "1" #&CDS_SEC = "1";
"A":   PN = "1"  !CDS_PN = "1";
"B":   PN = "2"  !CDS_PN = "2";
BODY = "Q_CAPP","I26": #LOCATION = "PC384" !CDS_LOCATION = "PC384" &SEC = "1" #&CDS_SEC = "1";
"A":   PN = "1"  !CDS_PN = "1";
"B":   PN = "2"  !CDS_PN = "2";
BODY = "Q_RES","I35": #LOCATION = "PR4258" !CDS_LOCATION = "PR4258" &SEC = "1" #&CDS_SEC = "1";
"A":   PN = "1"  !CDS_PN = "1";
"B":   PN = "2"  !CDS_PN = "2";
DRAWING = "@s9s_mb_2u_lib.s9s_mb_2u(sch_1):page285";
BODY = "Q_CAP","I15": #LOCATION = "PC1260" !CDS_LOCATION = "PC1260" &SEC = "1" #&CDS_SEC = "1";
"A":   PN = "1"  !CDS_PN = "1";
"B":   PN = "2"  !CDS_PN = "2";
BODY = "Q_RES","I18": #LOCATION = "PR3336" !CDS_LOCATION = "PR3336" &SEC = "1" #&CDS_SEC = "1";
"A":   PN = "1"  !CDS_PN = "1";
"B":   PN = "2"  !CDS_PN = "2";
BODY = "Q_RES","I30": #LOCATION = "PR2381" !CDS_LOCATION = "PR2381" &SEC = "1" #&CDS_SEC = "1";
"A":   PN = "1"  !CDS_PN = "1";
"B":   PN = "2"  !CDS_PN = "2";
BODY = "Q_CAP","I32": #LOCATION = "PC2282" !CDS_LOCATION = "PC2282" &SEC = "1" #&CDS_SEC = "1";
"A":   PN = "1"  !CDS_PN = "1";
"B":   PN = "2"  !CDS_PN = "2";
BODY = "Q_CAP","I36": #LOCATION = "C2460" !CDS_LOCATION = "C2460" &SEC = "1" #&CDS_SEC = "1";
"A":   PN = "1"  !CDS_PN = "1";
"B":   PN = "2"  !CDS_PN = "2";
BODY = "Q_CAP","I17": #LOCATION = "PC1262" !CDS_LOCATION = "PC1262" &SEC = "1" #&CDS_SEC = "1";
"A":   PN = "1"  !CDS_PN = "1";
"B":   PN = "2"  !CDS_PN = "2";
BODY = "Q_RES","I27": #LOCATION = "R2583" !CDS_LOCATION = "R2583" &SEC = "1" #&CDS_SEC = "1";
"A":   PN = "1"  !CDS_PN = "1";
"B":   PN = "2"  !CDS_PN = "2";
BODY = "Q_RES","I28": #LOCATION = "PR1314" !CDS_LOCATION = "PR1314" &SEC = "1" #&CDS_SEC = "1";
"A":   PN = "1"  !CDS_PN = "1";
"B":   PN = "2"  !CDS_PN = "2";
BODY = "Q_INDUCTOR","I33": #LOCATION = "PL119" !CDS_LOCATION = "PL119" &SEC = "1" #&CDS_SEC = "1";
"1":   PN = "1"  !CDS_PN = "1";
"2":   PN = "2"  !CDS_PN = "2";
BODY = "Q_RES","I34": #LOCATION = "PR1340" !CDS_LOCATION = "PR1340" &SEC = "1" #&CDS_SEC = "1";
"A":   PN = "1"  !CDS_PN = "1";
"B":   PN = "2"  !CDS_PN = "2";
BODY = "Q_SHORT","I44": #LOCATION = "PJ67" !CDS_LOCATION = "PJ67" &SEC = "1" #&CDS_SEC = "1";
"1":   PN = "1"  !CDS_PN = "1";
"2":   PN = "2"  !CDS_PN = "2";
BODY = "Q_CAP","I11": #LOCATION = "C2445" !CDS_LOCATION = "C2445" #SEC = "1" !CDS_SEC = "1";
"A":   PN = "1"  !CDS_PN = "1";
"B":   PN = "2"  !CDS_PN = "2";
BODY = "Q_RES","I13": #LOCATION = "R2374" !CDS_LOCATION = "R2374" &SEC = "1" #&CDS_SEC = "1";
"A":   PN = "1"  !CDS_PN = "1";
"B":   PN = "2"  !CDS_PN = "2";
BODY = "RS53318LR","I25": #LOCATION = "PU80" !CDS_LOCATION = "PU80" #SEC = "1" !CDS_SEC = "1";
"AGND":   PN = "2"  !CDS_PN = "2";
"BST":   PN = "1"  !CDS_PN = "1";
"CS":   PN = "3"  !CDS_PN = "3";
"EN":   PN = "8"  !CDS_PN = "8";
"FB":   PN = "7"  !CDS_PN = "7";
"MODE":   PN = "4"  !CDS_PN = "4";
"PGND":   PN = "11_18"  !CDS_PN = "11_18";
"PGOOD":   PN = "9"  !CDS_PN = "9";
"REF":   PN = "5"  !CDS_PN = "5";
"RTN":   PN = "6"  !CDS_PN = "6";
"SW":   PN = "20"  !CDS_PN = "20";
"VCC":   PN = "19"  !CDS_PN = "19";
"VIN1":   PN = "10"  !CDS_PN = "10";
"VIN2":   PN = "21"  !CDS_PN = "21";
BODY = "Q_RES","I37": #LOCATION = "R2380" !CDS_LOCATION = "R2380" &SEC = "1" #&CDS_SEC = "1";
"A":   PN = "1"  !CDS_PN = "1";
"B":   PN = "2"  !CDS_PN = "2";
BODY = "Q_RES","I3": #LOCATION = "PR1338" !CDS_LOCATION = "PR1338" &SEC = "1" #&CDS_SEC = "1";
"A":   PN = "1"  !CDS_PN = "1";
"B":   PN = "2"  !CDS_PN = "2";
BODY = "Q_RES","I10": #LOCATION = "PR1339" !CDS_LOCATION = "PR1339" &SEC = "1" #&CDS_SEC = "1";
"A":   PN = "1"  !CDS_PN = "1";
"B":   PN = "2"  !CDS_PN = "2";
BODY = "Q_CAP","I16": #LOCATION = "PC1261" !CDS_LOCATION = "PC1261" &SEC = "1" #&CDS_SEC = "1";
"A":   PN = "1"  !CDS_PN = "1";
"B":   PN = "2"  !CDS_PN = "2";
BODY = "Q_CAP","I24": #LOCATION = "PC1264" !CDS_LOCATION = "PC1264" &SEC = "1" #&CDS_SEC = "1";
"A":   PN = "1"  !CDS_PN = "1";
"B":   PN = "2"  !CDS_PN = "2";
BODY = "Q_CAP","I41": #LOCATION = "PC1269" !CDS_LOCATION = "PC1269" &SEC = "1" #&CDS_SEC = "1";
"A":   PN = "1"  !CDS_PN = "1";
"B":   PN = "2"  !CDS_PN = "2";
BODY = "Q_SHORT","I46": #LOCATION = "PJ66" !CDS_LOCATION = "PJ66" &SEC = "1" #&CDS_SEC = "1";
"1":   PN = "1"  !CDS_PN = "1";
"2":   PN = "2"  !CDS_PN = "2";
BODY = "Q_CAP","I1": #LOCATION = "PC644" !CDS_LOCATION = "PC644" #SEC = "1" !CDS_SEC = "1";
"A":   PN = "1"  !CDS_PN = "1";
"B":   PN = "2"  !CDS_PN = "2";
BODY = "Q_CAP","I8": #LOCATION = "PC1259" !CDS_LOCATION = "PC1259" &SEC = "1" #&CDS_SEC = "1";
"A":   PN = "1"  !CDS_PN = "1";
"B":   PN = "2"  !CDS_PN = "2";
BODY = "Q_RES","I14": #LOCATION = "R2367" !CDS_LOCATION = "R2367" &SEC = "1" #&CDS_SEC = "1";
"A":   PN = "1"  !CDS_PN = "1";
"B":   PN = "2"  !CDS_PN = "2";
BODY = "Q_CAP","I23": #LOCATION = "PC2002" !CDS_LOCATION = "PC2002" &SEC = "1" #&CDS_SEC = "1";
"A":   PN = "1"  !CDS_PN = "1";
"B":   PN = "2"  !CDS_PN = "2";
BODY = "Q_CAP","I26": #LOCATION = "PC1265" !CDS_LOCATION = "PC1265" &SEC = "1" #&CDS_SEC = "1";
"A":   PN = "1"  !CDS_PN = "1";
"B":   PN = "2"  !CDS_PN = "2";
BODY = "MOSFET_N","I29": #LOCATION = "PU174" !CDS_LOCATION = "PU174" &SEC = "1" #&CDS_SEC = "1";
"DRAIN":   PN = "D"  !CDS_PN = "D";
"GATE":   PN = "G"  !CDS_PN = "G";
"SOURCE":   PN = "S"  !CDS_PN = "S";
BODY = "Q_CAP","I35": #LOCATION = "PC1266" !CDS_LOCATION = "PC1266" &SEC = "1" #&CDS_SEC = "1";
"A":   PN = "1"  !CDS_PN = "1";
"B":   PN = "2"  !CDS_PN = "2";
BODY = "Q_CAP","I39": #LOCATION = "PC1267" !CDS_LOCATION = "PC1267" &SEC = "1" #&CDS_SEC = "1";
"A":   PN = "1"  !CDS_PN = "1";
"B":   PN = "2"  !CDS_PN = "2";
BODY = "Q_CAP","I40": #LOCATION = "PC1268" !CDS_LOCATION = "PC1268" &SEC = "1" #&CDS_SEC = "1";
"A":   PN = "1"  !CDS_PN = "1";
"B":   PN = "2"  !CDS_PN = "2";
BODY = "Q_CAP","I47": #LOCATION = "PC1270" !CDS_LOCATION = "PC1270" &SEC = "1" #&CDS_SEC = "1";
"A":   PN = "1"  !CDS_PN = "1";
"B":   PN = "2"  !CDS_PN = "2";
BODY = "Q_CAPP","I49": #LOCATION = "PC1771" !CDS_LOCATION = "PC1771" &SEC = "1" #&CDS_SEC = "1";
"A":   PN = "1"  !CDS_PN = "1";
"B":   PN = "2"  !CDS_PN = "2";
DRAWING = "@s9s_mb_2u_lib.s9s_mb_2u(sch_1):page287";
BODY = "PICOPROBE_BXA","I8": #LOCATION = "J68" !CDS_LOCATION = "J68" &SEC = "1" #&CDS_SEC = "1";
"1_P":   PN = "1"  !CDS_PN = "1";
"2_N":   PN = "2"  !CDS_PN = "2";
"3_G":   PN = "3"  !CDS_PN = "3";
BODY = "PICOPROBE_BXA","I11": #LOCATION = "J67" !CDS_LOCATION = "J67" &SEC = "1" #&CDS_SEC = "1";
"1_P":   PN = "1"  !CDS_PN = "1";
"2_N":   PN = "2"  !CDS_PN = "2";
"3_G":   PN = "3"  !CDS_PN = "3";
BODY = "PICOPROBE_BXA","I12": #LOCATION = "J66" !CDS_LOCATION = "J66" &SEC = "1" #&CDS_SEC = "1";
"1_P":   PN = "1"  !CDS_PN = "1";
"2_N":   PN = "2"  !CDS_PN = "2";
"3_G":   PN = "3"  !CDS_PN = "3";
BODY = "PICOPROBE_BXA","I19": #LOCATION = "J74" !CDS_LOCATION = "J74" &SEC = "1" #&CDS_SEC = "1";
"1_P":   PN = "1"  !CDS_PN = "1";
"2_N":   PN = "2"  !CDS_PN = "2";
"3_G":   PN = "3"  !CDS_PN = "3";
BODY = "PICOPROBE_BXA","I21": #LOCATION = "J72" !CDS_LOCATION = "J72" &SEC = "1" #&CDS_SEC = "1";
"1_P":   PN = "1"  !CDS_PN = "1";
"2_N":   PN = "2"  !CDS_PN = "2";
"3_G":   PN = "3"  !CDS_PN = "3";
BODY = "PICOPROBE_BXA","I23": #LOCATION = "J70" !CDS_LOCATION = "J70" &SEC = "1" #&CDS_SEC = "1";
"1_P":   PN = "1"  !CDS_PN = "1";
"2_N":   PN = "2"  !CDS_PN = "2";
"3_G":   PN = "3"  !CDS_PN = "3";
BODY = "PICOPROBE_BXA","I30": #LOCATION = "J118" !CDS_LOCATION = "J118" &SEC = "1" #&CDS_SEC = "1";
"1_P":   PN = "1"  !CDS_PN = "1";
"2_N":   PN = "2"  !CDS_PN = "2";
"3_G":   PN = "3"  !CDS_PN = "3";
BODY = "PICOPROBE_BXA","I31": #LOCATION = "J121" !CDS_LOCATION = "J121" &SEC = "1" #&CDS_SEC = "1";
"1_P":   PN = "1"  !CDS_PN = "1";
"2_N":   PN = "2"  !CDS_PN = "2";
"3_G":   PN = "3"  !CDS_PN = "3";
BODY = "PICOPROBE_BXA","I32": #LOCATION = "J120" !CDS_LOCATION = "J120" &SEC = "1" #&CDS_SEC = "1";
"1_P":   PN = "1"  !CDS_PN = "1";
"2_N":   PN = "2"  !CDS_PN = "2";
"3_G":   PN = "3"  !CDS_PN = "3";
BODY = "PICOPROBE_BXA","I39": #LOCATION = "J80" !CDS_LOCATION = "J80" &SEC = "1" #&CDS_SEC = "1";
"1_P":   PN = "1"  !CDS_PN = "1";
"2_N":   PN = "2"  !CDS_PN = "2";
"3_G":   PN = "3"  !CDS_PN = "3";
BODY = "PICOPROBE_BXA","I43": #LOCATION = "J78" !CDS_LOCATION = "J78" &SEC = "1" #&CDS_SEC = "1";
"1_P":   PN = "1"  !CDS_PN = "1";
"2_N":   PN = "2"  !CDS_PN = "2";
"3_G":   PN = "3"  !CDS_PN = "3";
BODY = "PICOPROBE_BXA","I52": #LOCATION = "J75" !CDS_LOCATION = "J75" &SEC = "1" #&CDS_SEC = "1";
"1_P":   PN = "1"  !CDS_PN = "1";
"2_N":   PN = "2"  !CDS_PN = "2";
"3_G":   PN = "3"  !CDS_PN = "3";
BODY = "PICOPROBE_BXA","I53": #LOCATION = "J86" !CDS_LOCATION = "J86" &SEC = "1" #&CDS_SEC = "1";
"1_P":   PN = "1"  !CDS_PN = "1";
"2_N":   PN = "2"  !CDS_PN = "2";
"3_G":   PN = "3"  !CDS_PN = "3";
BODY = "PICOPROBE_BXA","I55": #LOCATION = "J84" !CDS_LOCATION = "J84" &SEC = "1" #&CDS_SEC = "1";
"1_P":   PN = "1"  !CDS_PN = "1";
"2_N":   PN = "2"  !CDS_PN = "2";
"3_G":   PN = "3"  !CDS_PN = "3";
BODY = "PICOPROBE_BXA","I57": #LOCATION = "J82" !CDS_LOCATION = "J82" &SEC = "1" #&CDS_SEC = "1";
"1_P":   PN = "1"  !CDS_PN = "1";
"2_N":   PN = "2"  !CDS_PN = "2";
"3_G":   PN = "3"  !CDS_PN = "3";
BODY = "PICOPROBE_BXA","I3": #LOCATION = "J115" !CDS_LOCATION = "J115" &SEC = "1" #&CDS_SEC = "1";
"1_P":   PN = "1"  !CDS_PN = "1";
"2_N":   PN = "2"  !CDS_PN = "2";
"3_G":   PN = "3"  !CDS_PN = "3";
BODY = "PICOPROBE_BXA","I4": #LOCATION = "J114" !CDS_LOCATION = "J114" &SEC = "1" #&CDS_SEC = "1";
"1_P":   PN = "1"  !CDS_PN = "1";
"2_N":   PN = "2"  !CDS_PN = "2";
"3_G":   PN = "3"  !CDS_PN = "3";
BODY = "PICOPROBE_BXA","I5": #LOCATION = "J117" !CDS_LOCATION = "J117" &SEC = "1" #&CDS_SEC = "1";
"1_P":   PN = "1"  !CDS_PN = "1";
"2_N":   PN = "2"  !CDS_PN = "2";
"3_G":   PN = "3"  !CDS_PN = "3";
BODY = "PICOPROBE_BXA","I6": #LOCATION = "J116" !CDS_LOCATION = "J116" &SEC = "1" #&CDS_SEC = "1";
"1_P":   PN = "1"  !CDS_PN = "1";
"2_N":   PN = "2"  !CDS_PN = "2";
"3_G":   PN = "3"  !CDS_PN = "3";
BODY = "PICOPROBE_BXA","I14": #LOCATION = "J65" !CDS_LOCATION = "J65" &SEC = "1" #&CDS_SEC = "1";
"1_P":   PN = "1"  !CDS_PN = "1";
"2_N":   PN = "2"  !CDS_PN = "2";
"3_G":   PN = "3"  !CDS_PN = "3";
BODY = "PICOPROBE_BXA","I17": #LOCATION = "J64" !CDS_LOCATION = "J64" &SEC = "1" #&CDS_SEC = "1";
"1_P":   PN = "1"  !CDS_PN = "1";
"2_N":   PN = "2"  !CDS_PN = "2";
"3_G":   PN = "3"  !CDS_PN = "3";
BODY = "PICOPROBE_BXA","I18": #LOCATION = "J63" !CDS_LOCATION = "J63" &SEC = "1" #&CDS_SEC = "1";
"1_P":   PN = "1"  !CDS_PN = "1";
"2_N":   PN = "2"  !CDS_PN = "2";
"3_G":   PN = "3"  !CDS_PN = "3";
BODY = "PICOPROBE_BXA","I20": #LOCATION = "J73" !CDS_LOCATION = "J73" &SEC = "1" #&CDS_SEC = "1";
"1_P":   PN = "1"  !CDS_PN = "1";
"2_N":   PN = "2"  !CDS_PN = "2";
"3_G":   PN = "3"  !CDS_PN = "3";
BODY = "PICOPROBE_BXA","I22": #LOCATION = "J71" !CDS_LOCATION = "J71" &SEC = "1" #&CDS_SEC = "1";
"1_P":   PN = "1"  !CDS_PN = "1";
"2_N":   PN = "2"  !CDS_PN = "2";
"3_G":   PN = "3"  !CDS_PN = "3";
BODY = "PICOPROBE_BXA","I24": #LOCATION = "J69" !CDS_LOCATION = "J69" &SEC = "1" #&CDS_SEC = "1";
"1_P":   PN = "1"  !CDS_PN = "1";
"2_N":   PN = "2"  !CDS_PN = "2";
"3_G":   PN = "3"  !CDS_PN = "3";
BODY = "PICOPROBE_BXA","I28": #LOCATION = "J119" !CDS_LOCATION = "J119" &SEC = "1" #&CDS_SEC = "1";
"1_P":   PN = "1"  !CDS_PN = "1";
"2_N":   PN = "2"  !CDS_PN = "2";
"3_G":   PN = "3"  !CDS_PN = "3";
BODY = "PICOPROBE_BXA","I42": #LOCATION = "J79" !CDS_LOCATION = "J79" &SEC = "1" #&CDS_SEC = "1";
"1_P":   PN = "1"  !CDS_PN = "1";
"2_N":   PN = "2"  !CDS_PN = "2";
"3_G":   PN = "3"  !CDS_PN = "3";
BODY = "PICOPROBE_BXA","I48": #LOCATION = "J77" !CDS_LOCATION = "J77" &SEC = "1" #&CDS_SEC = "1";
"1_P":   PN = "1"  !CDS_PN = "1";
"2_N":   PN = "2"  !CDS_PN = "2";
"3_G":   PN = "3"  !CDS_PN = "3";
BODY = "PICOPROBE_BXA","I51": #LOCATION = "J76" !CDS_LOCATION = "J76" &SEC = "1" #&CDS_SEC = "1";
"1_P":   PN = "1"  !CDS_PN = "1";
"2_N":   PN = "2"  !CDS_PN = "2";
"3_G":   PN = "3"  !CDS_PN = "3";
BODY = "PICOPROBE_BXA","I54": #LOCATION = "J85" !CDS_LOCATION = "J85" &SEC = "1" #&CDS_SEC = "1";
"1_P":   PN = "1"  !CDS_PN = "1";
"2_N":   PN = "2"  !CDS_PN = "2";
"3_G":   PN = "3"  !CDS_PN = "3";
BODY = "PICOPROBE_BXA","I56": #LOCATION = "J83" !CDS_LOCATION = "J83" &SEC = "1" #&CDS_SEC = "1";
"1_P":   PN = "1"  !CDS_PN = "1";
"2_N":   PN = "2"  !CDS_PN = "2";
"3_G":   PN = "3"  !CDS_PN = "3";
BODY = "PICOPROBE_BXA","I58": #LOCATION = "J81" !CDS_LOCATION = "J81" &SEC = "1" #&CDS_SEC = "1";
"1_P":   PN = "1"  !CDS_PN = "1";
"2_N":   PN = "2"  !CDS_PN = "2";
"3_G":   PN = "3"  !CDS_PN = "3";
DRAWING = "@s9s_mb_2u_lib.s9s_mb_2u(sch_1):page288";
BODY = "TP_TDR_4P_FTS","I3": LOCATION = "X19" #&CDS_LOCATION = "X19" &SEC = "1" #&CDS_SEC = "1";
"P1":   PN = "2"  !CDS_PN = "2";
"P2":   PN = "3"  !CDS_PN = "3";
"S1":   PN = "1"  !CDS_PN = "1";
"S2":   PN = "4"  !CDS_PN = "4";
BODY = "TP_TDR_4P_FTS","I4": LOCATION = "X20" #&CDS_LOCATION = "X20" &SEC = "1" #&CDS_SEC = "1";
"P1":   PN = "2"  !CDS_PN = "2";
"P2":   PN = "3"  !CDS_PN = "3";
"S1":   PN = "1"  !CDS_PN = "1";
"S2":   PN = "4"  !CDS_PN = "4";
BODY = "TP_TDR_4P_FTS","I8": LOCATION = "X22" #&CDS_LOCATION = "X22" &SEC = "1" #&CDS_SEC = "1";
"P1":   PN = "2"  !CDS_PN = "2";
"P2":   PN = "3"  !CDS_PN = "3";
"S1":   PN = "1"  !CDS_PN = "1";
"S2":   PN = "4"  !CDS_PN = "4";
BODY = "TP_TDR_4P_FTS","I9": LOCATION = "X21" #&CDS_LOCATION = "X21" &SEC = "1" #&CDS_SEC = "1";
"P1":   PN = "2"  !CDS_PN = "2";
"P2":   PN = "3"  !CDS_PN = "3";
"S1":   PN = "1"  !CDS_PN = "1";
"S2":   PN = "4"  !CDS_PN = "4";
BODY = "TP_TDR_4P_FTS","I10": LOCATION = "X23" #&CDS_LOCATION = "X23" &SEC = "1" #&CDS_SEC = "1";
"P1":   PN = "2"  !CDS_PN = "2";
"P2":   PN = "3"  !CDS_PN = "3";
"S1":   PN = "1"  !CDS_PN = "1";
"S2":   PN = "4"  !CDS_PN = "4";
BODY = "TP_TDR_4P_FTS","I11": LOCATION = "X13" #&CDS_LOCATION = "X13" &SEC = "1" #&CDS_SEC = "1";
"P1":   PN = "2"  !CDS_PN = "2";
"P2":   PN = "3"  !CDS_PN = "3";
"S1":   PN = "1"  !CDS_PN = "1";
"S2":   PN = "4"  !CDS_PN = "4";
BODY = "TP_TDR_4P_FTS","I12": LOCATION = "X14" #&CDS_LOCATION = "X14" &SEC = "1" #&CDS_SEC = "1";
"P1":   PN = "2"  !CDS_PN = "2";
"P2":   PN = "3"  !CDS_PN = "3";
"S1":   PN = "1"  !CDS_PN = "1";
"S2":   PN = "4"  !CDS_PN = "4";
BODY = "TP_TDR_4P_FTS","I17": LOCATION = "X15" #&CDS_LOCATION = "X15" &SEC = "1" #&CDS_SEC = "1";
"P1":   PN = "2"  !CDS_PN = "2";
"P2":   PN = "3"  !CDS_PN = "3";
"S1":   PN = "1"  !CDS_PN = "1";
"S2":   PN = "4"  !CDS_PN = "4";
BODY = "TP_TDR_4P_FTS","I18": LOCATION = "X16" #&CDS_LOCATION = "X16" &SEC = "1" #&CDS_SEC = "1";
"P1":   PN = "2"  !CDS_PN = "2";
"P2":   PN = "3"  !CDS_PN = "3";
"S1":   PN = "1"  !CDS_PN = "1";
"S2":   PN = "4"  !CDS_PN = "4";
BODY = "TP_TDR_4P_FTS","I19": LOCATION = "X17" #&CDS_LOCATION = "X17" &SEC = "1" #&CDS_SEC = "1";
"P1":   PN = "2"  !CDS_PN = "2";
"P2":   PN = "3"  !CDS_PN = "3";
"S1":   PN = "1"  !CDS_PN = "1";
"S2":   PN = "4"  !CDS_PN = "4";
BODY = "TP_TDR_4P_FTS","I26": LOCATION = "X7" #&CDS_LOCATION = "X7" &SEC = "1" #&CDS_SEC = "1";
"P1":   PN = "2"  !CDS_PN = "2";
"P2":   PN = "3"  !CDS_PN = "3";
"S1":   PN = "1"  !CDS_PN = "1";
"S2":   PN = "4"  !CDS_PN = "4";
BODY = "TP_TDR_4P_FTS","I27": LOCATION = "X8" #&CDS_LOCATION = "X8" &SEC = "1" #&CDS_SEC = "1";
"P1":   PN = "2"  !CDS_PN = "2";
"P2":   PN = "3"  !CDS_PN = "3";
"S1":   PN = "1"  !CDS_PN = "1";
"S2":   PN = "4"  !CDS_PN = "4";
BODY = "TP_TDR_4P_FTS","I28": LOCATION = "X1" #&CDS_LOCATION = "X1" &SEC = "1" #&CDS_SEC = "1";
"P1":   PN = "2"  !CDS_PN = "2";
"P2":   PN = "3"  !CDS_PN = "3";
"S1":   PN = "1"  !CDS_PN = "1";
"S2":   PN = "4"  !CDS_PN = "4";
BODY = "TP_TDR_4P_FTS","I30": LOCATION = "X2" #&CDS_LOCATION = "X2" &SEC = "1" #&CDS_SEC = "1";
"P1":   PN = "2"  !CDS_PN = "2";
"P2":   PN = "3"  !CDS_PN = "3";
"S1":   PN = "1"  !CDS_PN = "1";
"S2":   PN = "4"  !CDS_PN = "4";
BODY = "TP_TDR_4P_FTS","I32": LOCATION = "X9" #&CDS_LOCATION = "X9" &SEC = "1" #&CDS_SEC = "1";
"P1":   PN = "2"  !CDS_PN = "2";
"P2":   PN = "3"  !CDS_PN = "3";
"S1":   PN = "1"  !CDS_PN = "1";
"S2":   PN = "4"  !CDS_PN = "4";
BODY = "TP_TDR_4P_FTS","I33": LOCATION = "X10" #&CDS_LOCATION = "X10" &SEC = "1" #&CDS_SEC = "1";
"P1":   PN = "2"  !CDS_PN = "2";
"P2":   PN = "3"  !CDS_PN = "3";
"S1":   PN = "1"  !CDS_PN = "1";
"S2":   PN = "4"  !CDS_PN = "4";
BODY = "TP_TDR_4P_FTS","I34": LOCATION = "X11" #&CDS_LOCATION = "X11" &SEC = "1" #&CDS_SEC = "1";
"P1":   PN = "2"  !CDS_PN = "2";
"P2":   PN = "3"  !CDS_PN = "3";
"S1":   PN = "1"  !CDS_PN = "1";
"S2":   PN = "4"  !CDS_PN = "4";
BODY = "TP_TDR_4P_FTS","I35": LOCATION = "X3" #&CDS_LOCATION = "X3" &SEC = "1" #&CDS_SEC = "1";
"P1":   PN = "2"  !CDS_PN = "2";
"P2":   PN = "3"  !CDS_PN = "3";
"S1":   PN = "1"  !CDS_PN = "1";
"S2":   PN = "4"  !CDS_PN = "4";
BODY = "TP_TDR_4P_FTS","I37": LOCATION = "X4" #&CDS_LOCATION = "X4" &SEC = "1" #&CDS_SEC = "1";
"P1":   PN = "2"  !CDS_PN = "2";
"P2":   PN = "3"  !CDS_PN = "3";
"S1":   PN = "1"  !CDS_PN = "1";
"S2":   PN = "4"  !CDS_PN = "4";
BODY = "TP_TDR_4P_FTS","I39": LOCATION = "X5" #&CDS_LOCATION = "X5" &SEC = "1" #&CDS_SEC = "1";
"P1":   PN = "2"  !CDS_PN = "2";
"P2":   PN = "3"  !CDS_PN = "3";
"S1":   PN = "1"  !CDS_PN = "1";
"S2":   PN = "4"  !CDS_PN = "4";
BODY = "TP_TDR_4P_FTS","I42": LOCATION = "X24" #&CDS_LOCATION = "X24" &SEC = "1" #&CDS_SEC = "1";
"P1":   PN = "2"  !CDS_PN = "2";
"P2":   PN = "3"  !CDS_PN = "3";
"S1":   PN = "1"  !CDS_PN = "1";
"S2":   PN = "4"  !CDS_PN = "4";
BODY = "TP_TDR_4P_FTS","I43": LOCATION = "X18" #&CDS_LOCATION = "X18" &SEC = "1" #&CDS_SEC = "1";
"P1":   PN = "2"  !CDS_PN = "2";
"P2":   PN = "3"  !CDS_PN = "3";
"S1":   PN = "1"  !CDS_PN = "1";
"S2":   PN = "4"  !CDS_PN = "4";
BODY = "TP_TDR_4P_FTS","I46": LOCATION = "X12" #&CDS_LOCATION = "X12" &SEC = "1" #&CDS_SEC = "1";
"P1":   PN = "2"  !CDS_PN = "2";
"P2":   PN = "3"  !CDS_PN = "3";
"S1":   PN = "1"  !CDS_PN = "1";
"S2":   PN = "4"  !CDS_PN = "4";
BODY = "TP_TDR_4P_FTS","I47": LOCATION = "X6" #&CDS_LOCATION = "X6" &SEC = "1" #&CDS_SEC = "1";
"P1":   PN = "2"  !CDS_PN = "2";
"P2":   PN = "3"  !CDS_PN = "3";
"S1":   PN = "1"  !CDS_PN = "1";
"S2":   PN = "4"  !CDS_PN = "4";
BODY = "TDR_3P","I49": LOCATION = "DB7" #&CDS_LOCATION = "DB7" &SEC = "1" #&CDS_SEC = "1";
"GND":   PN = "1"  !CDS_PN = "1";
"IO1":   PN = "2"  !CDS_PN = "2";
"IO2":   PN = "3"  !CDS_PN = "3";
BODY = "TDR_3P","I51": LOCATION = "DB8" #&CDS_LOCATION = "DB8" &SEC = "1" #&CDS_SEC = "1";
"GND":   PN = "1"  !CDS_PN = "1";
"IO1":   PN = "2"  !CDS_PN = "2";
"IO2":   PN = "3"  !CDS_PN = "3";
BODY = "TDR_3P","I53": LOCATION = "DB9" #&CDS_LOCATION = "DB9" &SEC = "1" #&CDS_SEC = "1";
"GND":   PN = "1"  !CDS_PN = "1";
"IO1":   PN = "2"  !CDS_PN = "2";
"IO2":   PN = "3"  !CDS_PN = "3";
BODY = "TDR_3P","I55": LOCATION = "DB10" #&CDS_LOCATION = "DB10" &SEC = "1" #&CDS_SEC = "1";
"GND":   PN = "1"  !CDS_PN = "1";
"IO1":   PN = "2"  !CDS_PN = "2";
"IO2":   PN = "3"  !CDS_PN = "3";
BODY = "TDR_3P","I57": LOCATION = "DB11" #&CDS_LOCATION = "DB11" &SEC = "1" #&CDS_SEC = "1";
"GND":   PN = "1"  !CDS_PN = "1";
"IO1":   PN = "2"  !CDS_PN = "2";
"IO2":   PN = "3"  !CDS_PN = "3";
BODY = "TDR_3P","I60": LOCATION = "DB12" #&CDS_LOCATION = "DB12" &SEC = "1" #&CDS_SEC = "1";
"GND":   PN = "1"  !CDS_PN = "1";
"IO1":   PN = "2"  !CDS_PN = "2";
"IO2":   PN = "3"  !CDS_PN = "3";
BODY = "TDR_3P","I61": LOCATION = "DB1" #&CDS_LOCATION = "DB1" &SEC = "1" #&CDS_SEC = "1";
"GND":   PN = "1"  !CDS_PN = "1";
"IO1":   PN = "2"  !CDS_PN = "2";
"IO2":   PN = "3"  !CDS_PN = "3";
BODY = "TDR_3P","I62": LOCATION = "DB2" #&CDS_LOCATION = "DB2" &SEC = "1" #&CDS_SEC = "1";
"GND":   PN = "1"  !CDS_PN = "1";
"IO1":   PN = "2"  !CDS_PN = "2";
"IO2":   PN = "3"  !CDS_PN = "3";
BODY = "TDR_3P","I63": LOCATION = "DB3" #&CDS_LOCATION = "DB3" &SEC = "1" #&CDS_SEC = "1";
"GND":   PN = "1"  !CDS_PN = "1";
"IO1":   PN = "2"  !CDS_PN = "2";
"IO2":   PN = "3"  !CDS_PN = "3";
BODY = "TDR_3P","I67": LOCATION = "DB4" #&CDS_LOCATION = "DB4" &SEC = "1" #&CDS_SEC = "1";
"GND":   PN = "1"  !CDS_PN = "1";
"IO1":   PN = "2"  !CDS_PN = "2";
"IO2":   PN = "3"  !CDS_PN = "3";
BODY = "TDR_3P","I68": LOCATION = "DB5" #&CDS_LOCATION = "DB5" &SEC = "1" #&CDS_SEC = "1";
"GND":   PN = "1"  !CDS_PN = "1";
"IO1":   PN = "2"  !CDS_PN = "2";
"IO2":   PN = "3"  !CDS_PN = "3";
BODY = "TDR_3P","I69": LOCATION = "DB6" #&CDS_LOCATION = "DB6" &SEC = "1" #&CDS_SEC = "1";
"GND":   PN = "1"  !CDS_PN = "1";
"IO1":   PN = "2"  !CDS_PN = "2";
"IO2":   PN = "3"  !CDS_PN = "3";
BODY = "TDR_3P","I96": LOCATION = "DB14" #&CDS_LOCATION = "DB14" &SEC = "1" #&CDS_SEC = "1";
"GND":   PN = "1"  !CDS_PN = "1";
"IO1":   PN = "2"  !CDS_PN = "2";
"IO2":   PN = "3"  !CDS_PN = "3";
BODY = "TDR_3P","I97": LOCATION = "DB15" #&CDS_LOCATION = "DB15" &SEC = "1" #&CDS_SEC = "1";
"GND":   PN = "1"  !CDS_PN = "1";
"IO1":   PN = "2"  !CDS_PN = "2";
"IO2":   PN = "3"  !CDS_PN = "3";
BODY = "TDR_3P","I99": LOCATION = "DB16" #&CDS_LOCATION = "DB16" &SEC = "1" #&CDS_SEC = "1";
"GND":   PN = "1"  !CDS_PN = "1";
"IO1":   PN = "2"  !CDS_PN = "2";
"IO2":   PN = "3"  !CDS_PN = "3";
BODY = "TDR_3P","I101": LOCATION = "DB13" #&CDS_LOCATION = "DB13" &SEC = "1" #&CDS_SEC = "1";
"GND":   PN = "1"  !CDS_PN = "1";
"IO1":   PN = "2"  !CDS_PN = "2";
"IO2":   PN = "3"  !CDS_PN = "3";
BODY = "TP_TDR_4P_FTS","I106": LOCATION = "X27" #&CDS_LOCATION = "X27" &SEC = "1" #&CDS_SEC = "1";
"P1":   PN = "2"  !CDS_PN = "2";
"P2":   PN = "3"  !CDS_PN = "3";
"S1":   PN = "1"  !CDS_PN = "1";
"S2":   PN = "4"  !CDS_PN = "4";
BODY = "TP_TDR_4P_FTS","I107": LOCATION = "X28" #&CDS_LOCATION = "X28" &SEC = "1" #&CDS_SEC = "1";
"P1":   PN = "2"  !CDS_PN = "2";
"P2":   PN = "3"  !CDS_PN = "3";
"S1":   PN = "1"  !CDS_PN = "1";
"S2":   PN = "4"  !CDS_PN = "4";
BODY = "TP_TDR_4P_FTS","I108": LOCATION = "X25" #&CDS_LOCATION = "X25" &SEC = "1" #&CDS_SEC = "1";
"P1":   PN = "2"  !CDS_PN = "2";
"P2":   PN = "3"  !CDS_PN = "3";
"S1":   PN = "1"  !CDS_PN = "1";
"S2":   PN = "4"  !CDS_PN = "4";
BODY = "TP_TDR_4P_FTS","I110": LOCATION = "X26" #&CDS_LOCATION = "X26" &SEC = "1" #&CDS_SEC = "1";
"P1":   PN = "2"  !CDS_PN = "2";
"P2":   PN = "3"  !CDS_PN = "3";
"S1":   PN = "1"  !CDS_PN = "1";
"S2":   PN = "4"  !CDS_PN = "4";
BODY = "TP_TDR_4P_FTS","I112": LOCATION = "X31" #&CDS_LOCATION = "X31" &SEC = "1" #&CDS_SEC = "1";
"P1":   PN = "2"  !CDS_PN = "2";
"P2":   PN = "3"  !CDS_PN = "3";
"S1":   PN = "1"  !CDS_PN = "1";
"S2":   PN = "4"  !CDS_PN = "4";
BODY = "TP_TDR_4P_FTS","I115": LOCATION = "X32" #&CDS_LOCATION = "X32" &SEC = "1" #&CDS_SEC = "1";
"P1":   PN = "2"  !CDS_PN = "2";
"P2":   PN = "3"  !CDS_PN = "3";
"S1":   PN = "1"  !CDS_PN = "1";
"S2":   PN = "4"  !CDS_PN = "4";
BODY = "TP_TDR_4P_FTS","I116": LOCATION = "X29" #&CDS_LOCATION = "X29" &SEC = "1" #&CDS_SEC = "1";
"P1":   PN = "2"  !CDS_PN = "2";
"P2":   PN = "3"  !CDS_PN = "3";
"S1":   PN = "1"  !CDS_PN = "1";
"S2":   PN = "4"  !CDS_PN = "4";
BODY = "TP_TDR_4P_FTS","I117": LOCATION = "X30" #&CDS_LOCATION = "X30" &SEC = "1" #&CDS_SEC = "1";
"P1":   PN = "2"  !CDS_PN = "2";
"P2":   PN = "3"  !CDS_PN = "3";
"S1":   PN = "1"  !CDS_PN = "1";
"S2":   PN = "4"  !CDS_PN = "4";
DRAWING = "@s9s_mb_2u_lib.s9s_mb_2u(sch_1):page289";
BODY = "HOLE","I7": LOCATION = "H30" #&CDS_LOCATION = "H30" &SEC = "1" #&CDS_SEC = "1";
"1":   PN = "1"  !CDS_PN = "1";
BODY = "HOLE","I8": LOCATION = "H29" #&CDS_LOCATION = "H29" &SEC = "1" #&CDS_SEC = "1";
"1":   PN = "1"  !CDS_PN = "1";
BODY = "HOLE","I9": LOCATION = "H38" #&CDS_LOCATION = "H38" &SEC = "1" #&CDS_SEC = "1";
"1":   PN = "1"  !CDS_PN = "1";
BODY = "HOLE","I10": LOCATION = "H36" #&CDS_LOCATION = "H36" &SEC = "1" #&CDS_SEC = "1";
"1":   PN = "1"  !CDS_PN = "1";
BODY = "HOLE","I11": LOCATION = "H28" #&CDS_LOCATION = "H28" &SEC = "1" #&CDS_SEC = "1";
"1":   PN = "1"  !CDS_PN = "1";
BODY = "HOLE","I12": LOCATION = "H27" #&CDS_LOCATION = "H27" &SEC = "1" #&CDS_SEC = "1";
"1":   PN = "1"  !CDS_PN = "1";
BODY = "HOLE","I18": LOCATION = "H76" #&CDS_LOCATION = "H76" &SEC = "1" #&CDS_SEC = "1";
"1":   PN = "1"  !CDS_PN = "1";
BODY = "HOLE","I19": LOCATION = "H26" #&CDS_LOCATION = "H26" &SEC = "1" #&CDS_SEC = "1";
"1":   PN = "1"  !CDS_PN = "1";
BODY = "HOLE","I20": LOCATION = "H24" #&CDS_LOCATION = "H24" &SEC = "1" #&CDS_SEC = "1";
"1":   PN = "1"  !CDS_PN = "1";
BODY = "HOLE","I21": LOCATION = "H22" #&CDS_LOCATION = "H22" &SEC = "1" #&CDS_SEC = "1";
"1":   PN = "1"  !CDS_PN = "1";
BODY = "HOLE","I54": LOCATION = "H32" #&CDS_LOCATION = "H32" &SEC = "1" #&CDS_SEC = "1";
"1":   PN = "1"  !CDS_PN = "1";
BODY = "HOLE","I56": LOCATION = "H31" #&CDS_LOCATION = "H31" &SEC = "1" #&CDS_SEC = "1";
"1":   PN = "1"  !CDS_PN = "1";
BODY = "HOLE","I57": LOCATION = "H75" #&CDS_LOCATION = "H75" &SEC = "1" #&CDS_SEC = "1";
"1":   PN = "1"  !CDS_PN = "1";
BODY = "HOLE","I58": LOCATION = "H74" #&CDS_LOCATION = "H74" &SEC = "1" #&CDS_SEC = "1";
"1":   PN = "1"  !CDS_PN = "1";
BODY = "HOLE","I60": LOCATION = "H20" #&CDS_LOCATION = "H20" &SEC = "1" #&CDS_SEC = "1";
"1":   PN = "1"  !CDS_PN = "1";
BODY = "HOLE","I61": LOCATION = "H18" #&CDS_LOCATION = "H18" &SEC = "1" #&CDS_SEC = "1";
"1":   PN = "1"  !CDS_PN = "1";
BODY = "HOLE","I63": LOCATION = "H16" #&CDS_LOCATION = "H16" &SEC = "1" #&CDS_SEC = "1";
"1":   PN = "1"  !CDS_PN = "1";
BODY = "HOLE","I64": LOCATION = "H25" #&CDS_LOCATION = "H25" &SEC = "1" #&CDS_SEC = "1";
"1":   PN = "1"  !CDS_PN = "1";
BODY = "HOLE","I72": LOCATION = "H23" #&CDS_LOCATION = "H23" &SEC = "1" #&CDS_SEC = "1";
"1":   PN = "1"  !CDS_PN = "1";
BODY = "HOLE","I73": LOCATION = "H21" #&CDS_LOCATION = "H21" &SEC = "1" #&CDS_SEC = "1";
"1":   PN = "1"  !CDS_PN = "1";
BODY = "HOLE","I74": LOCATION = "H19" #&CDS_LOCATION = "H19" &SEC = "1" #&CDS_SEC = "1";
"1":   PN = "1"  !CDS_PN = "1";
BODY = "HOLE","I75": LOCATION = "H17" #&CDS_LOCATION = "H17" &SEC = "1" #&CDS_SEC = "1";
"1":   PN = "1"  !CDS_PN = "1";
BODY = "HOLE","I83": LOCATION = "H15" #&CDS_LOCATION = "H15" &SEC = "1" #&CDS_SEC = "1";
"1":   PN = "1"  !CDS_PN = "1";
BODY = "HOLE","I87": LOCATION = "H77" #&CDS_LOCATION = "H77" &SEC = "1" #&CDS_SEC = "1";
"1":   PN = "1"  !CDS_PN = "1";
BODY = "HOLE","I147": LOCATION = "H91" #&CDS_LOCATION = "H91" &SEC = "1" #&CDS_SEC = "1";
"1":   PN = "1"  !CDS_PN = "1";
BODY = "HOLE","I149": LOCATION = "H97" #&CDS_LOCATION = "H97" &SEC = "1" #&CDS_SEC = "1";
"1":   PN = "1"  !CDS_PN = "1";
BODY = "HOLE","I155": LOCATION = "H99" #&CDS_LOCATION = "H99" &SEC = "1" #&CDS_SEC = "1";
"1":   PN = "1"  !CDS_PN = "1";
BODY = "HOLE","I158": LOCATION = "H102" #&CDS_LOCATION = "H102" &SEC = "1" #&CDS_SEC = "1";
"1":   PN = "1"  !CDS_PN = "1";
BODY = "HOLE","I160": LOCATION = "H98" #&CDS_LOCATION = "H98" &SEC = "1" #&CDS_SEC = "1";
"1":   PN = "1"  !CDS_PN = "1";
BODY = "HOLE","I166": LOCATION = "H92" #&CDS_LOCATION = "H92" &SEC = "1" #&CDS_SEC = "1";
"1":   PN = "1"  !CDS_PN = "1";
BODY = "HOLE","I168": LOCATION = "H87" #&CDS_LOCATION = "H87" &SEC = "1" #&CDS_SEC = "1";
"1":   PN = "1"  !CDS_PN = "1";
BODY = "HOLE","I175": LOCATION = "H104" #&CDS_LOCATION = "H104" &SEC = "1" #&CDS_SEC = "1";
"1":   PN = "1"  !CDS_PN = "1";
BODY = "HOLE","I140": LOCATION = "H86" #&CDS_LOCATION = "H86" &SEC = "1" #&CDS_SEC = "1";
"1":   PN = "1"  !CDS_PN = "1";
BODY = "HOLE","I144": LOCATION = "H88" #&CDS_LOCATION = "H88" &SEC = "1" #&CDS_SEC = "1";
"1":   PN = "1"  !CDS_PN = "1";
BODY = "HOLE","I148": LOCATION = "H93" #&CDS_LOCATION = "H93" &SEC = "1" #&CDS_SEC = "1";
"1":   PN = "1"  !CDS_PN = "1";
BODY = "HOLE","I150": LOCATION = "H95" #&CDS_LOCATION = "H95" &SEC = "1" #&CDS_SEC = "1";
"1":   PN = "1"  !CDS_PN = "1";
BODY = "HOLE","I154": LOCATION = "H101" #&CDS_LOCATION = "H101" &SEC = "1" #&CDS_SEC = "1";
"1":   PN = "1"  !CDS_PN = "1";
BODY = "HOLE","I159": LOCATION = "H100" #&CDS_LOCATION = "H100" &SEC = "1" #&CDS_SEC = "1";
"1":   PN = "1"  !CDS_PN = "1";
BODY = "HOLE","I161": LOCATION = "H96" #&CDS_LOCATION = "H96" &SEC = "1" #&CDS_SEC = "1";
"1":   PN = "1"  !CDS_PN = "1";
BODY = "HOLE","I165": LOCATION = "H94" #&CDS_LOCATION = "H94" &SEC = "1" #&CDS_SEC = "1";
"1":   PN = "1"  !CDS_PN = "1";
BODY = "HOLE","I167": LOCATION = "H89" #&CDS_LOCATION = "H89" &SEC = "1" #&CDS_SEC = "1";
"1":   PN = "1"  !CDS_PN = "1";
BODY = "HOLE","I174": LOCATION = "H103" #&CDS_LOCATION = "H103" &SEC = "1" #&CDS_SEC = "1";
"1":   PN = "1"  !CDS_PN = "1";
BODY = "HOLE","I190": LOCATION = "H106" #&CDS_LOCATION = "H106" &SEC = "1" #&CDS_SEC = "1";
"1":   PN = "1"  !CDS_PN = "1";
BODY = "HOLE","I192": LOCATION = "H105" #&CDS_LOCATION = "H105" &SEC = "1" #&CDS_SEC = "1";
"1":   PN = "1"  !CDS_PN = "1";
BODY = "GND_HOLE","I202": LOCATION = "H115" #&CDS_LOCATION = "H115" &SEC = "1" #&CDS_SEC = "1";
"GND2":   PN = "2"  !CDS_PN = "2";
"GND3":   PN = "3"  !CDS_PN = "3";
"GND4":   PN = "4"  !CDS_PN = "4";
"GND5":   PN = "5"  !CDS_PN = "5";
"GND6":   PN = "6"  !CDS_PN = "6";
"GND7":   PN = "7"  !CDS_PN = "7";
"GND8":   PN = "8"  !CDS_PN = "8";
"GND9":   PN = "9"  !CDS_PN = "9";
BODY = "GND_HOLE","I204": LOCATION = "H111" #&CDS_LOCATION = "H111" &SEC = "1" #&CDS_SEC = "1";
"GND2":   PN = "2"  !CDS_PN = "2";
"GND3":   PN = "3"  !CDS_PN = "3";
"GND4":   PN = "4"  !CDS_PN = "4";
"GND5":   PN = "5"  !CDS_PN = "5";
"GND6":   PN = "6"  !CDS_PN = "6";
"GND7":   PN = "7"  !CDS_PN = "7";
"GND8":   PN = "8"  !CDS_PN = "8";
"GND9":   PN = "9"  !CDS_PN = "9";
BODY = "GND_HOLE","I207": LOCATION = "H112" #&CDS_LOCATION = "H112" &SEC = "1" #&CDS_SEC = "1";
"GND2":   PN = "2"  !CDS_PN = "2";
"GND3":   PN = "3"  !CDS_PN = "3";
"GND4":   PN = "4"  !CDS_PN = "4";
"GND5":   PN = "5"  !CDS_PN = "5";
"GND6":   PN = "6"  !CDS_PN = "6";
"GND7":   PN = "7"  !CDS_PN = "7";
"GND8":   PN = "8"  !CDS_PN = "8";
"GND9":   PN = "9"  !CDS_PN = "9";
BODY = "HOLE","I216": #LOCATION = "H44" !CDS_LOCATION = "H44" &SEC = "1" #&CDS_SEC = "1";
"1":   PN = "1"  !CDS_PN = "1";
BODY = "HOLE","I217": #LOCATION = "H45" !CDS_LOCATION = "H45" &SEC = "1" #&CDS_SEC = "1";
"1":   PN = "1"  !CDS_PN = "1";
BODY = "HOLE","I218": #LOCATION = "H47" !CDS_LOCATION = "H47" &SEC = "1" #&CDS_SEC = "1";
"1":   PN = "1"  !CDS_PN = "1";
BODY = "HOLE","I219": #LOCATION = "H49" !CDS_LOCATION = "H49" &SEC = "1" #&CDS_SEC = "1";
"1":   PN = "1"  !CDS_PN = "1";
BODY = "HOLE","I224": LOCATION = "H120" #&CDS_LOCATION = "H120" &SEC = "1" #&CDS_SEC = "1";
"1":   PN = "1"  !CDS_PN = "1";
BODY = "HOLE","I225": LOCATION = "H122" #&CDS_LOCATION = "H122" &SEC = "1" #&CDS_SEC = "1";
"1":   PN = "1"  !CDS_PN = "1";
BODY = "HOLE","I226": LOCATION = "H124" #&CDS_LOCATION = "H124" &SEC = "1" #&CDS_SEC = "1";
"1":   PN = "1"  !CDS_PN = "1";
BODY = "HOLE","I227": LOCATION = "H126" #&CDS_LOCATION = "H126" &SEC = "1" #&CDS_SEC = "1";
"1":   PN = "1"  !CDS_PN = "1";
BODY = "HOLE","I228": LOCATION = "H127" #&CDS_LOCATION = "H127" &SEC = "1" #&CDS_SEC = "1";
"1":   PN = "1"  !CDS_PN = "1";
BODY = "HOLE","I229": LOCATION = "H125" #&CDS_LOCATION = "H125" &SEC = "1" #&CDS_SEC = "1";
"1":   PN = "1"  !CDS_PN = "1";
BODY = "HOLE","I232": LOCATION = "H128" #&CDS_LOCATION = "H128" &SEC = "1" #&CDS_SEC = "1";
"1":   PN = "1"  !CDS_PN = "1";
BODY = "CONN1_10165288101LF","I238": LOCATION = "J122" #&CDS_LOCATION = "J122" &SEC = "1" #&CDS_SEC = "1";
"NC1":   PN = "SCR_H1"  !CDS_PN = "SCR_H1";
BODY = "CONN1_10165288101LF","I239": LOCATION = "J123" #&CDS_LOCATION = "J123" &SEC = "1" #&CDS_SEC = "1";
"NC1":   PN = "SCR_H1"  !CDS_PN = "SCR_H1";
BODY = "GND_HOLE","I247": #LOCATION = "H113" !CDS_LOCATION = "H113" &SEC = "1" #&CDS_SEC = "1";
"GND2":   PN = "2"  !CDS_PN = "2";
"GND3":   PN = "3"  !CDS_PN = "3";
"GND4":   PN = "4"  !CDS_PN = "4";
"GND5":   PN = "5"  !CDS_PN = "5";
"GND6":   PN = "6"  !CDS_PN = "6";
"GND7":   PN = "7"  !CDS_PN = "7";
"GND8":   PN = "8"  !CDS_PN = "8";
"GND9":   PN = "9"  !CDS_PN = "9";
BODY = "GND_HOLE","I248": #LOCATION = "H114" !CDS_LOCATION = "H114" &SEC = "1" #&CDS_SEC = "1";
"GND2":   PN = "2"  !CDS_PN = "2";
"GND3":   PN = "3"  !CDS_PN = "3";
"GND4":   PN = "4"  !CDS_PN = "4";
"GND5":   PN = "5"  !CDS_PN = "5";
"GND6":   PN = "6"  !CDS_PN = "6";
"GND7":   PN = "7"  !CDS_PN = "7";
"GND8":   PN = "8"  !CDS_PN = "8";
"GND9":   PN = "9"  !CDS_PN = "9";
BODY = "HOLE","I249": #LOCATION = "H129" !CDS_LOCATION = "H129" &SEC = "1" #&CDS_SEC = "1";
"1":   PN = "1"  !CDS_PN = "1";
BODY = "HOLE","I254": #LOCATION = "H90" !CDS_LOCATION = "H90" &SEC = "1" #&CDS_SEC = "1";
"1":   PN = "1"  !CDS_PN = "1";
DRAWING = "@s9s_mb_2u_lib.s9s_mb_2u(sch_1):page290";
BODY = "ME_DUMMY_SYMBOL","I9": LOCATION = "ME4" #&CDS_LOCATION = "ME4";
BODY = "ME_DUMMY_SYMBOL","I10": LOCATION = "ME2" #&CDS_LOCATION = "ME2";
BODY = "ME_DUMMY_SYMBOL","I11": LOCATION = "ME3" #&CDS_LOCATION = "ME3";
BODY = "ME_DUMMY_SYMBOL","I12": LOCATION = "ME15" #&CDS_LOCATION = "ME15";
BODY = "ME_DUMMY_SYMBOL","I13": LOCATION = "ME13" #&CDS_LOCATION = "ME13";
BODY = "ME_DUMMY_SYMBOL","I14": LOCATION = "ME11" #&CDS_LOCATION = "ME11";
BODY = "ME_DUMMY_SYMBOL","I15": LOCATION = "ME12" #&CDS_LOCATION = "ME12";
BODY = "ME_DUMMY_SYMBOL","I16": LOCATION = "ME14" #&CDS_LOCATION = "ME14";
BODY = "DUMMY_SYMBOL","I17": LOCATION = "DM13" #&CDS_LOCATION = "DM13" &SEC = "1" #&CDS_SEC = "1";
"1":   PN = "1"  !CDS_PN = "1";
BODY = "ME_DUMMY_SYMBOL","I18": LOCATION = "ME9" #&CDS_LOCATION = "ME9";
BODY = "ME_DUMMY_SYMBOL","I19": LOCATION = "ME10" #&CDS_LOCATION = "ME10";
BODY = "DUMMY_SYMBOL","I23": LOCATION = "DM9" #&CDS_LOCATION = "DM9" &SEC = "1" #&CDS_SEC = "1";
"1":   PN = "1"  !CDS_PN = "1";
BODY = "TP","I40": #LOCATION = "U1_BL" !CDS_LOCATION = "U1_BL" &SEC = "1" #&CDS_SEC = "1";
"TP":   PN = "1"  !CDS_PN = "1";
BODY = "TP","I41": #LOCATION = "U2_BL" !CDS_LOCATION = "U2_BL" &SEC = "1" #&CDS_SEC = "1";
"TP":   PN = "1"  !CDS_PN = "1";
BODY = "TP","I42": #LOCATION = "U2_BP" !CDS_LOCATION = "U2_BP" &SEC = "1" #&CDS_SEC = "1";
"TP":   PN = "1"  !CDS_PN = "1";
BODY = "TP","I43": #LOCATION = "U1_BP" !CDS_LOCATION = "U1_BP" &SEC = "1" #&CDS_SEC = "1";
"TP":   PN = "1"  !CDS_PN = "1";
BODY = "TP","I45": #LOCATION = "U2_DC" !CDS_LOCATION = "U2_DC" &SEC = "1" #&CDS_SEC = "1";
"TP":   PN = "1"  !CDS_PN = "1";
BODY = "TP","I47": #LOCATION = "U1_DC" !CDS_LOCATION = "U1_DC" &SEC = "1" #&CDS_SEC = "1";
"TP":   PN = "1"  !CDS_PN = "1";
BODY = "ME_DUMMY_SYMBOL","I62": LOCATION = "ME17" #&CDS_LOCATION = "ME17";
BODY = "ME_DUMMY_SYMBOL","I63": LOCATION = "ME18" #&CDS_LOCATION = "ME18";
BODY = "ME_DUMMY_SYMBOL","I64": LOCATION = "ME20" #&CDS_LOCATION = "ME20";
BODY = "ME_DUMMY_SYMBOL","I65": LOCATION = "ME21" #&CDS_LOCATION = "ME21";
BODY = "TP","I69": #LOCATION = "J90_CON" !CDS_LOCATION = "J90_CON" &SEC = "1" #&CDS_SEC = "1";
"TP":   PN = "1"  !CDS_PN = "1";
BODY = "TP","I70": #LOCATION = "JP4003_12" !CDS_LOCATION = "JP4003_12" &SEC = "1" #&CDS_SEC = "1";
"TP":   PN = "1"  !CDS_PN = "1";
BODY = "TP","I71": #LOCATION = "JP15_23" !CDS_LOCATION = "JP15_23" &SEC = "1" #&CDS_SEC = "1";
"TP":   PN = "1"  !CDS_PN = "1";
BODY = "TP","I72": #LOCATION = "JP16_23" !CDS_LOCATION = "JP16_23" &SEC = "1" #&CDS_SEC = "1";
"TP":   PN = "1"  !CDS_PN = "1";
BODY = "ME_DUMMY_SYMBOL","I73": #LOCATION = "ME22" !CDS_LOCATION = "ME22";
BODY = "ME_DUMMY_SYMBOL","I74": LOCATION = "ME27" #&CDS_LOCATION = "ME27";
BODY = "ME_DUMMY_SYMBOL","I75": LOCATION = "ME28" #&CDS_LOCATION = "ME28";
BODY = "ME_DUMMY_SYMBOL","I76": LOCATION = "ME29" #&CDS_LOCATION = "ME29";
DRAWING = "@s9s_mb_2u_lib.s9s_mb_2u(sch_1):page150";
BODY = "Q_RES","I2": LOCATION = "R410" #&CDS_LOCATION = "R410" &SEC = "1" #&CDS_SEC = "1";
"A":   PN = "1"  !CDS_PN = "1";
"B":   PN = "2"  !CDS_PN = "2";
BODY = "Q_RES","I4": LOCATION = "R415" #&CDS_LOCATION = "R415" &SEC = "1" #&CDS_SEC = "1";
"A":   PN = "1"  !CDS_PN = "1";
"B":   PN = "2"  !CDS_PN = "2";
BODY = "Q_RES","I5": LOCATION = "R409" #&CDS_LOCATION = "R409" &SEC = "1" #&CDS_SEC = "1";
"A":   PN = "1"  !CDS_PN = "1";
"B":   PN = "2"  !CDS_PN = "2";
BODY = "Q_RES","I6": LOCATION = "R414" #&CDS_LOCATION = "R414" &SEC = "1" #&CDS_SEC = "1";
"A":   PN = "1"  !CDS_PN = "1";
"B":   PN = "2"  !CDS_PN = "2";
BODY = "Q_RES","I35": LOCATION = "R3132" #&CDS_LOCATION = "R3132" &SEC = "1" #&CDS_SEC = "1";
"A":   PN = "1"  !CDS_PN = "1";
"B":   PN = "2"  !CDS_PN = "2";
BODY = "Q_RES","I36": LOCATION = "R1930" #&CDS_LOCATION = "R1930" &SEC = "1" #&CDS_SEC = "1";
"A":   PN = "1"  !CDS_PN = "1";
"B":   PN = "2"  !CDS_PN = "2";
BODY = "Q_RES","I37": LOCATION = "R1929" #&CDS_LOCATION = "R1929" &SEC = "1" #&CDS_SEC = "1";
"A":   PN = "1"  !CDS_PN = "1";
"B":   PN = "2"  !CDS_PN = "2";
BODY = "Q_RES","I51": LOCATION = "R1671" #&CDS_LOCATION = "R1671" &SEC = "1" #&CDS_SEC = "1";
"A":   PN = "1"  !CDS_PN = "1";
"B":   PN = "2"  !CDS_PN = "2";
BODY = "Q_RES","I52": LOCATION = "R418" #&CDS_LOCATION = "R418" &SEC = "1" #&CDS_SEC = "1";
"A":   PN = "1"  !CDS_PN = "1";
"B":   PN = "2"  !CDS_PN = "2";
BODY = "Q_RES","I53": LOCATION = "R417" #&CDS_LOCATION = "R417" &SEC = "1" #&CDS_SEC = "1";
"A":   PN = "1"  !CDS_PN = "1";
"B":   PN = "2"  !CDS_PN = "2";
BODY = "Q_RES","I54": LOCATION = "R416" #&CDS_LOCATION = "R416" &SEC = "1" #&CDS_SEC = "1";
"A":   PN = "1"  !CDS_PN = "1";
"B":   PN = "2"  !CDS_PN = "2";
BODY = "Q_RES","I58": LOCATION = "R429" #&CDS_LOCATION = "R429" &SEC = "1" #&CDS_SEC = "1";
"A":   PN = "1"  !CDS_PN = "1";
"B":   PN = "2"  !CDS_PN = "2";
BODY = "Q_CAP","I89": LOCATION = "C1213" #&CDS_LOCATION = "C1213" &SEC = "1" #&CDS_SEC = "1";
"A":   PN = "1"  !CDS_PN = "1";
"B":   PN = "2"  !CDS_PN = "2";
BODY = "Q_CAP","I90": LOCATION = "C1232" #&CDS_LOCATION = "C1232" &SEC = "1" #&CDS_SEC = "1";
"A":   PN = "1"  !CDS_PN = "1";
"B":   PN = "2"  !CDS_PN = "2";
BODY = "Q_CAP","I91": LOCATION = "C1233" #&CDS_LOCATION = "C1233" &SEC = "1" #&CDS_SEC = "1";
"A":   PN = "1"  !CDS_PN = "1";
"B":   PN = "2"  !CDS_PN = "2";
BODY = "Q_CAP","I110": LOCATION = "C1234" #&CDS_LOCATION = "C1234" &SEC = "1" #&CDS_SEC = "1";
"A":   PN = "1"  !CDS_PN = "1";
"B":   PN = "2"  !CDS_PN = "2";
BODY = "Q_CAP","I111": LOCATION = "C1235" #&CDS_LOCATION = "C1235" &SEC = "1" #&CDS_SEC = "1";
"A":   PN = "1"  !CDS_PN = "1";
"B":   PN = "2"  !CDS_PN = "2";
BODY = "Q_CAP","I113": LOCATION = "C1236" #&CDS_LOCATION = "C1236" &SEC = "1" #&CDS_SEC = "1";
"A":   PN = "1"  !CDS_PN = "1";
"B":   PN = "2"  !CDS_PN = "2";
BODY = "Q_CAP","I114": LOCATION = "C1237" #&CDS_LOCATION = "C1237" &SEC = "1" #&CDS_SEC = "1";
"A":   PN = "1"  !CDS_PN = "1";
"B":   PN = "2"  !CDS_PN = "2";
BODY = "Q_CAP","I115": LOCATION = "C1238" #&CDS_LOCATION = "C1238" &SEC = "1" #&CDS_SEC = "1";
"A":   PN = "1"  !CDS_PN = "1";
"B":   PN = "2"  !CDS_PN = "2";
BODY = "Q_CAP","I116": LOCATION = "C1239" #&CDS_LOCATION = "C1239" &SEC = "1" #&CDS_SEC = "1";
"A":   PN = "1"  !CDS_PN = "1";
"B":   PN = "2"  !CDS_PN = "2";
BODY = "Q_RES","I118": LOCATION = "R444" #&CDS_LOCATION = "R444" &SEC = "1" #&CDS_SEC = "1";
"A":   PN = "1"  !CDS_PN = "1";
"B":   PN = "2"  !CDS_PN = "2";
BODY = "Q_RES","I119": LOCATION = "R445" #&CDS_LOCATION = "R445" &SEC = "1" #&CDS_SEC = "1";
"A":   PN = "1"  !CDS_PN = "1";
"B":   PN = "2"  !CDS_PN = "2";
BODY = "Q_RES","I149": LOCATION = "R1895" #&CDS_LOCATION = "R1895" &SEC = "1" #&CDS_SEC = "1";
"A":   PN = "1"  !CDS_PN = "1";
"B":   PN = "2"  !CDS_PN = "2";
BODY = "Q_RES","I151": LOCATION = "R424" #&CDS_LOCATION = "R424" &SEC = "1" #&CDS_SEC = "1";
"A":   PN = "1"  !CDS_PN = "1";
"B":   PN = "2"  !CDS_PN = "2";
BODY = "Q_CAP","I168": LOCATION = "C1240" #&CDS_LOCATION = "C1240" &SEC = "1" #&CDS_SEC = "1";
"A":   PN = "1"  !CDS_PN = "1";
"B":   PN = "2"  !CDS_PN = "2";
BODY = "SCONN168_ME1016810202011","I199": #LOCATION = "J37" !CDS_LOCATION = "J37" #SEC = "1" !CDS_SEC = "1";
"+3.3V_EDGE":   PN = "B11"  !CDS_PN = "B11";
"+12V_EDGE_B1":   PN = "B1"  !CDS_PN = "B1";
"+12V_EDGE_B2":   PN = "B2"  !CDS_PN = "B2";
"+12V_EDGE_B3":   PN = "B3"  !CDS_PN = "B3";
"+12V_EDGE_B4":   PN = "B4"  !CDS_PN = "B4";
"+12V_EDGE_B5":   PN = "B5"  !CDS_PN = "B5";
"+12V_EDGE_B6":   PN = "B6"  !CDS_PN = "B6";
"AUX_PWR_EN":   PN = "B12"  !CDS_PN = "B12";
"BIF0#":   PN = "B7"  !CDS_PN = "B7";
"BIF1#":   PN = "B8"  !CDS_PN = "B8";
"BIF2#":   PN = "B9"  !CDS_PN = "B9";
"CLK":   PN = "OB6"  !CDS_PN = "OB6";
"DATA_IN":   PN = "OB4"  !CDS_PN = "OB4";
"DATA_OUT":   PN = "OB5"  !CDS_PN = "OB5";
"G1":   PN = "G1"  !CDS_PN = "G1";
"G2":   PN = "G2"  !CDS_PN = "G2";
"G3":   PN = "G3"  !CDS_PN = "G3";
"G4":   PN = "G4"  !CDS_PN = "G4";
"G5":   PN = "G5"  !CDS_PN = "G5";
"GND_A1":   PN = "A1"  !CDS_PN = "A1";
"GND_A2":   PN = "A2"  !CDS_PN = "A2";
"GND_A3":   PN = "A3"  !CDS_PN = "A3";
"GND_A4":   PN = "A4"  !CDS_PN = "A4";
"GND_A5":   PN = "A5"  !CDS_PN = "A5";
"GND_A6":   PN = "A6"  !CDS_PN = "A6";
"GND_A13":   PN = "A13"  !CDS_PN = "A13";
"GND_A16":   PN = "A16"  !CDS_PN = "A16";
"GND_A19":   PN = "A19"  !CDS_PN = "A19";
"GND_A22":   PN = "A22"  !CDS_PN = "A22";
"GND_A25":   PN = "A25"  !CDS_PN = "A25";
"GND_A28":   PN = "A28"  !CDS_PN = "A28";
"GND_A29":   PN = "A29"  !CDS_PN = "A29";
"GND_A32":   PN = "A32"  !CDS_PN = "A32";
"GND_A35":   PN = "A35"  !CDS_PN = "A35";
"GND_A38":   PN = "A38"  !CDS_PN = "A38";
"GND_A41":   PN = "A41"  !CDS_PN = "A41";
"GND_A43":   PN = "A43"  !CDS_PN = "A43";
"GND_A46":   PN = "A46"  !CDS_PN = "A46";
"GND_A49":   PN = "A49"  !CDS_PN = "A49";
"GND_A52":   PN = "A52"  !CDS_PN = "A52";
"GND_A55":   PN = "A55"  !CDS_PN = "A55";
"GND_A58":   PN = "A58"  !CDS_PN = "A58";
"GND_A61":   PN = "A61"  !CDS_PN = "A61";
"GND_A64":   PN = "A64"  !CDS_PN = "A64";
"GND_A67":   PN = "A67"  !CDS_PN = "A67";
"GND_B13":   PN = "B13"  !CDS_PN = "B13";
"GND_B16":   PN = "B16"  !CDS_PN = "B16";
"GND_B19":   PN = "B19"  !CDS_PN = "B19";
"GND_B22":   PN = "B22"  !CDS_PN = "B22";
"GND_B25":   PN = "B25"  !CDS_PN = "B25";
"GND_B28":   PN = "B28"  !CDS_PN = "B28";
"GND_B29":   PN = "B29"  !CDS_PN = "B29";
"GND_B32":   PN = "B32"  !CDS_PN = "B32";
"GND_B35":   PN = "B35"  !CDS_PN = "B35";
"GND_B38":   PN = "B38"  !CDS_PN = "B38";
"GND_B41":   PN = "B41"  !CDS_PN = "B41";
"GND_B43":   PN = "B43"  !CDS_PN = "B43";
"GND_B46":   PN = "B46"  !CDS_PN = "B46";
"GND_B49":   PN = "B49"  !CDS_PN = "B49";
"GND_B52":   PN = "B52"  !CDS_PN = "B52";
"GND_B55":   PN = "B55"  !CDS_PN = "B55";
"GND_B58":   PN = "B58"  !CDS_PN = "B58";
"GND_B61":   PN = "B61"  !CDS_PN = "B61";
"GND_B64":   PN = "B64"  !CDS_PN = "B64";
"GND_B67":   PN = "B67"  !CDS_PN = "B67";
"GND_OA10":   PN = "OA10"  !CDS_PN = "OA10";
"GND_OA13":   PN = "OA13"  !CDS_PN = "OA13";
"GND_OB10":   PN = "OB10"  !CDS_PN = "OB10";
"GND_OB13":   PN = "OB13"  !CDS_PN = "OB13";
"LD#":   PN = "OB3"  !CDS_PN = "OB3";
"MAIN_PWR_EN":   PN = "OB2"  !CDS_PN = "OB2";
"NIC_PWR_GOOD":   PN = "OB1"  !CDS_PN = "OB1";
"PERN0":   PN = "A17"  !CDS_PN = "A17";
"PERN1":   PN = "A20"  !CDS_PN = "A20";
"PERN2":   PN = "A23"  !CDS_PN = "A23";
"PERN3":   PN = "A26"  !CDS_PN = "A26";
"PERN4":   PN = "A30"  !CDS_PN = "A30";
"PERN5":   PN = "A33"  !CDS_PN = "A33";
"PERN6":   PN = "A36"  !CDS_PN = "A36";
"PERN7":   PN = "A39"  !CDS_PN = "A39";
"PERN8":   PN = "A44"  !CDS_PN = "A44";
"PERN9":   PN = "A47"  !CDS_PN = "A47";
"PERN10":   PN = "A50"  !CDS_PN = "A50";
"PERN11":   PN = "A53"  !CDS_PN = "A53";
"PERN12":   PN = "A56"  !CDS_PN = "A56";
"PERN13":   PN = "A59"  !CDS_PN = "A59";
"PERN14":   PN = "A62"  !CDS_PN = "A62";
"PERN15":   PN = "A65"  !CDS_PN = "A65";
"PERP0":   PN = "A18"  !CDS_PN = "A18";
"PERP1":   PN = "A21"  !CDS_PN = "A21";
"PERP2":   PN = "A24"  !CDS_PN = "A24";
"PERP3":   PN = "A27"  !CDS_PN = "A27";
"PERP4":   PN = "A31"  !CDS_PN = "A31";
"PERP5":   PN = "A34"  !CDS_PN = "A34";
"PERP6":   PN = "A37"  !CDS_PN = "A37";
"PERP7":   PN = "A40"  !CDS_PN = "A40";
"PERP8":   PN = "A45"  !CDS_PN = "A45";
"PERP9":   PN = "A48"  !CDS_PN = "A48";
"PERP10":   PN = "A51"  !CDS_PN = "A51";
"PERP11":   PN = "A54"  !CDS_PN = "A54";
"PERP12":   PN = "A57"  !CDS_PN = "A57";
"PERP13":   PN = "A60"  !CDS_PN = "A60";
"PERP14":   PN = "A63"  !CDS_PN = "A63";
"PERP15":   PN = "A66"  !CDS_PN = "A66";
"PERST0#":   PN = "B10"  !CDS_PN = "B10";
"PERST1#":   PN = "A11"  !CDS_PN = "A11";
"PERST2#":   PN = "OA1"  !CDS_PN = "OA1";
"PERST3#":   PN = "OA2"  !CDS_PN = "OA2";
"PETN0":   PN = "B17"  !CDS_PN = "B17";
"PETN1":   PN = "B20"  !CDS_PN = "B20";
"PETN2":   PN = "B23"  !CDS_PN = "B23";
"PETN3":   PN = "B26"  !CDS_PN = "B26";
"PETN4":   PN = "B30"  !CDS_PN = "B30";
"PETN5":   PN = "B33"  !CDS_PN = "B33";
"PETN6":   PN = "B36"  !CDS_PN = "B36";
"PETN7":   PN = "B39"  !CDS_PN = "B39";
"PETN8":   PN = "B44"  !CDS_PN = "B44";
"PETN9":   PN = "B47"  !CDS_PN = "B47";
"PETN10":   PN = "B50"  !CDS_PN = "B50";
"PETN11":   PN = "B53"  !CDS_PN = "B53";
"PETN12":   PN = "B56"  !CDS_PN = "B56";
"PETN13":   PN = "B59"  !CDS_PN = "B59";
"PETN14":   PN = "B62"  !CDS_PN = "B62";
"PETN15":   PN = "B65"  !CDS_PN = "B65";
"PETP0":   PN = "B18"  !CDS_PN = "B18";
"PETP1":   PN = "B21"  !CDS_PN = "B21";
"PETP2":   PN = "B24"  !CDS_PN = "B24";
"PETP3":   PN = "B27"  !CDS_PN = "B27";
"PETP4":   PN = "B31"  !CDS_PN = "B31";
"PETP5":   PN = "B34"  !CDS_PN = "B34";
"PETP6":   PN = "B37"  !CDS_PN = "B37";
"PETP7":   PN = "B40"  !CDS_PN = "B40";
"PETP8":   PN = "B45"  !CDS_PN = "B45";
"PETP9":   PN = "B48"  !CDS_PN = "B48";
"PETP10":   PN = "B51"  !CDS_PN = "B51";
"PETP11":   PN = "B54"  !CDS_PN = "B54";
"PETP12":   PN = "B57"  !CDS_PN = "B57";
"PETP13":   PN = "B60"  !CDS_PN = "B60";
"PETP14":   PN = "B63"  !CDS_PN = "B63";
"PETP15":   PN = "B66"  !CDS_PN = "B66";
"PRSNTA#":   PN = "A10"  !CDS_PN = "A10";
"PRSNTB0#":   PN = "B42"  !CDS_PN = "B42";
"PRSNTB1#":   PN = "A42"  !CDS_PN = "A42";
"PRSNTB2#":   PN = "A12"  !CDS_PN = "A12";
"PRSNTB3#":   PN = "B70"  !CDS_PN = "B70";
"PWRBRK0#":   PN = "A70"  !CDS_PN = "A70";
"RBT_ARB_IN":   PN = "OA4"  !CDS_PN = "OA4";
"RBT_ARB_OUT":   PN = "OA5"  !CDS_PN = "OA5";
"RBT_CLK_IN":   PN = "OA14"  !CDS_PN = "OA14";
"RBT_CRS_DV":   PN = "OB14"  !CDS_PN = "OB14";
"RBT_RXD0":   PN = "OB9"  !CDS_PN = "OB9";
"RBT_RXD1":   PN = "OB8"  !CDS_PN = "OB8";
"RBT_TX_EN":   PN = "OA7"  !CDS_PN = "OA7";
"RBT_TXD0":   PN = "OA9"  !CDS_PN = "OA9";
"RBT_TXD1":   PN = "OA8"  !CDS_PN = "OA8";
"REFCLKN0":   PN = "B14"  !CDS_PN = "B14";
"REFCLKN1":   PN = "A14"  !CDS_PN = "A14";
"REFCLKN2":   PN = "OB11"  !CDS_PN = "OB11";
"REFCLKN3":   PN = "OA11"  !CDS_PN = "OA11";
"REFCLKP0":   PN = "B15"  !CDS_PN = "B15";
"REFCLKP1":   PN = "A15"  !CDS_PN = "A15";
"REFCLKP2":   PN = "OB12"  !CDS_PN = "OB12";
"REFCLKP3":   PN = "OA12"  !CDS_PN = "OA12";
"RFU1_NC_B68":   PN = "B68"  !CDS_PN = "B68";
"RFU1_NC_B69":   PN = "B69"  !CDS_PN = "B69";
"SLOT_ID0":   PN = "OB7"  !CDS_PN = "OB7";
"SLOT_ID1":   PN = "OA6"  !CDS_PN = "OA6";
"SMCLK":   PN = "A7"  !CDS_PN = "A7";
"SMDAT":   PN = "A8"  !CDS_PN = "A8";
"SMRST#":   PN = "A9"  !CDS_PN = "A9";
"USB_DATN":   PN = "A68"  !CDS_PN = "A68";
"USB_DATP":   PN = "A69"  !CDS_PN = "A69";
"WAKE#":   PN = "OA3"  !CDS_PN = "OA3";
BODY = "Q_RES","I212": #LOCATION = "R423" !CDS_LOCATION = "R423" &SEC = "1" #&CDS_SEC = "1";
"A":   PN = "1"  !CDS_PN = "1";
"B":   PN = "2"  !CDS_PN = "2";
BODY = "Q_RES","I215": #LOCATION = "R422" !CDS_LOCATION = "R422" &SEC = "1" #&CDS_SEC = "1";
"A":   PN = "1"  !CDS_PN = "1";
"B":   PN = "2"  !CDS_PN = "2";
BODY = "Q_RES","I217": #LOCATION = "R421" !CDS_LOCATION = "R421" &SEC = "1" #&CDS_SEC = "1";
"A":   PN = "1"  !CDS_PN = "1";
"B":   PN = "2"  !CDS_PN = "2";
BODY = "Q_RES","I218": #LOCATION = "R420" !CDS_LOCATION = "R420" &SEC = "1" #&CDS_SEC = "1";
"A":   PN = "1"  !CDS_PN = "1";
"B":   PN = "2"  !CDS_PN = "2";
BODY = "Q_RES","I220": #LOCATION = "R425" !CDS_LOCATION = "R425" &SEC = "1" #&CDS_SEC = "1";
"A":   PN = "1"  !CDS_PN = "1";
"B":   PN = "2"  !CDS_PN = "2";
DRAWING = "@s9s_mb_2u_lib.s9s_mb_2u(sch_1):page148";
BODY = "CONN112_10137002101LF","I74": #LOCATION = "J111" !CDS_LOCATION = "J111" &SEC = "1" #&CDS_SEC = "1";
"A5":   PN = "A5"  !CDS_PN = "A5";
"A6":   PN = "A6"  !CDS_PN = "A6";
"A7":   PN = "A7"  !CDS_PN = "A7";
"A8":   PN = "A8"  !CDS_PN = "A8";
"B5":   PN = "B5"  !CDS_PN = "B5";
"B6":   PN = "B6"  !CDS_PN = "B6";
"B7":   PN = "B7"  !CDS_PN = "B7";
"B8":   PN = "B8"  !CDS_PN = "B8";
"C5":   PN = "C5"  !CDS_PN = "C5";
"C6":   PN = "C6"  !CDS_PN = "C6";
"C7":   PN = "C7"  !CDS_PN = "C7";
"C8":   PN = "C8"  !CDS_PN = "C8";
"D5":   PN = "D5"  !CDS_PN = "D5";
"D6":   PN = "D6"  !CDS_PN = "D6";
"D7":   PN = "D7"  !CDS_PN = "D7";
"D8":   PN = "D8"  !CDS_PN = "D8";
"E5":   PN = "E5"  !CDS_PN = "E5";
"E6":   PN = "E6"  !CDS_PN = "E6";
"E7":   PN = "E7"  !CDS_PN = "E7";
"E8":   PN = "E8"  !CDS_PN = "E8";
"F5":   PN = "F5"  !CDS_PN = "F5";
"F6":   PN = "F6"  !CDS_PN = "F6";
"F7":   PN = "F7"  !CDS_PN = "F7";
"F8":   PN = "F8"  !CDS_PN = "F8";
"G5":   PN = "G5"  !CDS_PN = "G5";
"G6":   PN = "G6"  !CDS_PN = "G6";
"G7":   PN = "G7"  !CDS_PN = "G7";
"G8":   PN = "G8"  !CDS_PN = "G8";
"H5":   PN = "H5"  !CDS_PN = "H5";
"H6":   PN = "H6"  !CDS_PN = "H6";
"H7":   PN = "H7"  !CDS_PN = "H7";
"H8":   PN = "H8"  !CDS_PN = "H8";
"I5":   PN = "I5"  !CDS_PN = "I5";
"I6":   PN = "I6"  !CDS_PN = "I6";
"I7":   PN = "I7"  !CDS_PN = "I7";
"I8":   PN = "I8"  !CDS_PN = "I8";
"J5":   PN = "J5"  !CDS_PN = "J5";
"J6":   PN = "J6"  !CDS_PN = "J6";
"J7":   PN = "J7"  !CDS_PN = "J7";
"J8":   PN = "J8"  !CDS_PN = "J8";
"K5":   PN = "K5"  !CDS_PN = "K5";
"K6":   PN = "K6"  !CDS_PN = "K6";
"K7":   PN = "K7"  !CDS_PN = "K7";
"K8":   PN = "K8"  !CDS_PN = "K8";
"L5":   PN = "L5"  !CDS_PN = "L5";
"L6":   PN = "L6"  !CDS_PN = "L6";
"L7":   PN = "L7"  !CDS_PN = "L7";
"L8":   PN = "L8"  !CDS_PN = "L8";
"M5":   PN = "M5"  !CDS_PN = "M5";
"M6":   PN = "M6"  !CDS_PN = "M6";
"M7":   PN = "M7"  !CDS_PN = "M7";
"M8":   PN = "M8"  !CDS_PN = "M8";
"N5":   PN = "N5"  !CDS_PN = "N5";
"N6":   PN = "N6"  !CDS_PN = "N6";
"N7":   PN = "N7"  !CDS_PN = "N7";
"N8":   PN = "N8"  !CDS_PN = "N8";
BODY = "CONN112_10137002101LF","I75": #LOCATION = "J111" !CDS_LOCATION = "J111" &SEC = "2" #&CDS_SEC = "2";
"A1":   PN = "A1"  !CDS_PN = "A1";
"A2":   PN = "A2"  !CDS_PN = "A2";
"A3":   PN = "A3"  !CDS_PN = "A3";
"A4":   PN = "A4"  !CDS_PN = "A4";
"B1":   PN = "B1"  !CDS_PN = "B1";
"B2":   PN = "B2"  !CDS_PN = "B2";
"B3":   PN = "B3"  !CDS_PN = "B3";
"B4":   PN = "B4"  !CDS_PN = "B4";
"C1":   PN = "C1"  !CDS_PN = "C1";
"C2":   PN = "C2"  !CDS_PN = "C2";
"C3":   PN = "C3"  !CDS_PN = "C3";
"C4":   PN = "C4"  !CDS_PN = "C4";
"D1":   PN = "D1"  !CDS_PN = "D1";
"D2":   PN = "D2"  !CDS_PN = "D2";
"D3":   PN = "D3"  !CDS_PN = "D3";
"D4":   PN = "D4"  !CDS_PN = "D4";
"E1":   PN = "E1"  !CDS_PN = "E1";
"E2":   PN = "E2"  !CDS_PN = "E2";
"E3":   PN = "E3"  !CDS_PN = "E3";
"E4":   PN = "E4"  !CDS_PN = "E4";
"F1":   PN = "F1"  !CDS_PN = "F1";
"F2":   PN = "F2"  !CDS_PN = "F2";
"F3":   PN = "F3"  !CDS_PN = "F3";
"F4":   PN = "F4"  !CDS_PN = "F4";
"G1":   PN = "G1"  !CDS_PN = "G1";
"G2":   PN = "G2"  !CDS_PN = "G2";
"G3":   PN = "G3"  !CDS_PN = "G3";
"G4":   PN = "G4"  !CDS_PN = "G4";
"H1":   PN = "H1"  !CDS_PN = "H1";
"H2":   PN = "H2"  !CDS_PN = "H2";
"H3":   PN = "H3"  !CDS_PN = "H3";
"H4":   PN = "H4"  !CDS_PN = "H4";
"I1":   PN = "I1"  !CDS_PN = "I1";
"I2":   PN = "I2"  !CDS_PN = "I2";
"I3":   PN = "I3"  !CDS_PN = "I3";
"I4":   PN = "I4"  !CDS_PN = "I4";
"J1":   PN = "J1"  !CDS_PN = "J1";
"J2":   PN = "J2"  !CDS_PN = "J2";
"J3":   PN = "J3"  !CDS_PN = "J3";
"J4":   PN = "J4"  !CDS_PN = "J4";
"K1":   PN = "K1"  !CDS_PN = "K1";
"K2":   PN = "K2"  !CDS_PN = "K2";
"K3":   PN = "K3"  !CDS_PN = "K3";
"K4":   PN = "K4"  !CDS_PN = "K4";
"L1":   PN = "L1"  !CDS_PN = "L1";
"L2":   PN = "L2"  !CDS_PN = "L2";
"L3":   PN = "L3"  !CDS_PN = "L3";
"L4":   PN = "L4"  !CDS_PN = "L4";
"M1":   PN = "M1"  !CDS_PN = "M1";
"M2":   PN = "M2"  !CDS_PN = "M2";
"M3":   PN = "M3"  !CDS_PN = "M3";
"M4":   PN = "M4"  !CDS_PN = "M4";
"N1":   PN = "N1"  !CDS_PN = "N1";
"N2":   PN = "N2"  !CDS_PN = "N2";
"N3":   PN = "N3"  !CDS_PN = "N3";
"N4":   PN = "N4"  !CDS_PN = "N4";
DRAWING = "@s9s_mb_2u_lib.s9s_mb_2u(sch_1):page149";
BODY = "CONN160_10131762101LF","I75": #LOCATION = "J112" !CDS_LOCATION = "J112" &SEC = "1" #&CDS_SEC = "1";
"A5":   PN = "A5"  !CDS_PN = "A5";
"A6":   PN = "A6"  !CDS_PN = "A6";
"A7":   PN = "A7"  !CDS_PN = "A7";
"A8":   PN = "A8"  !CDS_PN = "A8";
"B5":   PN = "B5"  !CDS_PN = "B5";
"B6":   PN = "B6"  !CDS_PN = "B6";
"B7":   PN = "B7"  !CDS_PN = "B7";
"B8":   PN = "B8"  !CDS_PN = "B8";
"C5":   PN = "C5"  !CDS_PN = "C5";
"C6":   PN = "C6"  !CDS_PN = "C6";
"C7":   PN = "C7"  !CDS_PN = "C7";
"C8":   PN = "C8"  !CDS_PN = "C8";
"D5":   PN = "D5"  !CDS_PN = "D5";
"D6":   PN = "D6"  !CDS_PN = "D6";
"D7":   PN = "D7"  !CDS_PN = "D7";
"D8":   PN = "D8"  !CDS_PN = "D8";
"E5":   PN = "E5"  !CDS_PN = "E5";
"E6":   PN = "E6"  !CDS_PN = "E6";
"E7":   PN = "E7"  !CDS_PN = "E7";
"E8":   PN = "E8"  !CDS_PN = "E8";
"F5":   PN = "F5"  !CDS_PN = "F5";
"F6":   PN = "F6"  !CDS_PN = "F6";
"F7":   PN = "F7"  !CDS_PN = "F7";
"F8":   PN = "F8"  !CDS_PN = "F8";
"G5":   PN = "G5"  !CDS_PN = "G5";
"G6":   PN = "G6"  !CDS_PN = "G6";
"G7":   PN = "G7"  !CDS_PN = "G7";
"G8":   PN = "G8"  !CDS_PN = "G8";
"H5":   PN = "H5"  !CDS_PN = "H5";
"H6":   PN = "H6"  !CDS_PN = "H6";
"H7":   PN = "H7"  !CDS_PN = "H7";
"H8":   PN = "H8"  !CDS_PN = "H8";
"I5":   PN = "I5"  !CDS_PN = "I5";
"I6":   PN = "I6"  !CDS_PN = "I6";
"I7":   PN = "I7"  !CDS_PN = "I7";
"I8":   PN = "I8"  !CDS_PN = "I8";
"J5":   PN = "J5"  !CDS_PN = "J5";
"J6":   PN = "J6"  !CDS_PN = "J6";
"J7":   PN = "J7"  !CDS_PN = "J7";
"J8":   PN = "J8"  !CDS_PN = "J8";
"K5":   PN = "K5"  !CDS_PN = "K5";
"K6":   PN = "K6"  !CDS_PN = "K6";
"K7":   PN = "K7"  !CDS_PN = "K7";
"K8":   PN = "K8"  !CDS_PN = "K8";
"L5":   PN = "L5"  !CDS_PN = "L5";
"L6":   PN = "L6"  !CDS_PN = "L6";
"L7":   PN = "L7"  !CDS_PN = "L7";
"L8":   PN = "L8"  !CDS_PN = "L8";
"M5":   PN = "M5"  !CDS_PN = "M5";
"M6":   PN = "M6"  !CDS_PN = "M6";
"M7":   PN = "M7"  !CDS_PN = "M7";
"M8":   PN = "M8"  !CDS_PN = "M8";
"N5":   PN = "N5"  !CDS_PN = "N5";
"N6":   PN = "N6"  !CDS_PN = "N6";
"N7":   PN = "N7"  !CDS_PN = "N7";
"N8":   PN = "N8"  !CDS_PN = "N8";
"O5":   PN = "O5"  !CDS_PN = "O5";
"O6":   PN = "O6"  !CDS_PN = "O6";
"O7":   PN = "O7"  !CDS_PN = "O7";
"O8":   PN = "O8"  !CDS_PN = "O8";
"P5":   PN = "P5"  !CDS_PN = "P5";
"P6":   PN = "P6"  !CDS_PN = "P6";
"P7":   PN = "P7"  !CDS_PN = "P7";
"P8":   PN = "P8"  !CDS_PN = "P8";
"Q5":   PN = "Q5"  !CDS_PN = "Q5";
"Q6":   PN = "Q6"  !CDS_PN = "Q6";
"Q7":   PN = "Q7"  !CDS_PN = "Q7";
"Q8":   PN = "Q8"  !CDS_PN = "Q8";
"R5":   PN = "R5"  !CDS_PN = "R5";
"R6":   PN = "R6"  !CDS_PN = "R6";
"R7":   PN = "R7"  !CDS_PN = "R7";
"R8":   PN = "R8"  !CDS_PN = "R8";
"S5":   PN = "S5"  !CDS_PN = "S5";
"S6":   PN = "S6"  !CDS_PN = "S6";
"S7":   PN = "S7"  !CDS_PN = "S7";
"S8":   PN = "S8"  !CDS_PN = "S8";
"T5":   PN = "T5"  !CDS_PN = "T5";
"T6":   PN = "T6"  !CDS_PN = "T6";
"T7":   PN = "T7"  !CDS_PN = "T7";
"T8":   PN = "T8"  !CDS_PN = "T8";
BODY = "CONN160_10131762101LF","I76": #LOCATION = "J112" !CDS_LOCATION = "J112" &SEC = "2" #&CDS_SEC = "2";
"A1":   PN = "A1"  !CDS_PN = "A1";
"A2":   PN = "A2"  !CDS_PN = "A2";
"A3":   PN = "A3"  !CDS_PN = "A3";
"A4":   PN = "A4"  !CDS_PN = "A4";
"B1":   PN = "B1"  !CDS_PN = "B1";
"B2":   PN = "B2"  !CDS_PN = "B2";
"B3":   PN = "B3"  !CDS_PN = "B3";
"B4":   PN = "B4"  !CDS_PN = "B4";
"C1":   PN = "C1"  !CDS_PN = "C1";
"C2":   PN = "C2"  !CDS_PN = "C2";
"C3":   PN = "C3"  !CDS_PN = "C3";
"C4":   PN = "C4"  !CDS_PN = "C4";
"D1":   PN = "D1"  !CDS_PN = "D1";
"D2":   PN = "D2"  !CDS_PN = "D2";
"D3":   PN = "D3"  !CDS_PN = "D3";
"D4":   PN = "D4"  !CDS_PN = "D4";
"E1":   PN = "E1"  !CDS_PN = "E1";
"E2":   PN = "E2"  !CDS_PN = "E2";
"E3":   PN = "E3"  !CDS_PN = "E3";
"E4":   PN = "E4"  !CDS_PN = "E4";
"F1":   PN = "F1"  !CDS_PN = "F1";
"F2":   PN = "F2"  !CDS_PN = "F2";
"F3":   PN = "F3"  !CDS_PN = "F3";
"F4":   PN = "F4"  !CDS_PN = "F4";
"G1":   PN = "G1"  !CDS_PN = "G1";
"G2":   PN = "G2"  !CDS_PN = "G2";
"G3":   PN = "G3"  !CDS_PN = "G3";
"G4":   PN = "G4"  !CDS_PN = "G4";
"H1":   PN = "H1"  !CDS_PN = "H1";
"H2":   PN = "H2"  !CDS_PN = "H2";
"H3":   PN = "H3"  !CDS_PN = "H3";
"H4":   PN = "H4"  !CDS_PN = "H4";
"I1":   PN = "I1"  !CDS_PN = "I1";
"I2":   PN = "I2"  !CDS_PN = "I2";
"I3":   PN = "I3"  !CDS_PN = "I3";
"I4":   PN = "I4"  !CDS_PN = "I4";
"J1":   PN = "J1"  !CDS_PN = "J1";
"J2":   PN = "J2"  !CDS_PN = "J2";
"J3":   PN = "J3"  !CDS_PN = "J3";
"J4":   PN = "J4"  !CDS_PN = "J4";
"K1":   PN = "K1"  !CDS_PN = "K1";
"K2":   PN = "K2"  !CDS_PN = "K2";
"K3":   PN = "K3"  !CDS_PN = "K3";
"K4":   PN = "K4"  !CDS_PN = "K4";
"L1":   PN = "L1"  !CDS_PN = "L1";
"L2":   PN = "L2"  !CDS_PN = "L2";
"L3":   PN = "L3"  !CDS_PN = "L3";
"L4":   PN = "L4"  !CDS_PN = "L4";
"M1":   PN = "M1"  !CDS_PN = "M1";
"M2":   PN = "M2"  !CDS_PN = "M2";
"M3":   PN = "M3"  !CDS_PN = "M3";
"M4":   PN = "M4"  !CDS_PN = "M4";
"N1":   PN = "N1"  !CDS_PN = "N1";
"N2":   PN = "N2"  !CDS_PN = "N2";
"N3":   PN = "N3"  !CDS_PN = "N3";
"N4":   PN = "N4"  !CDS_PN = "N4";
"O1":   PN = "O1"  !CDS_PN = "O1";
"O2":   PN = "O2"  !CDS_PN = "O2";
"O3":   PN = "O3"  !CDS_PN = "O3";
"O4":   PN = "O4"  !CDS_PN = "O4";
"P1":   PN = "P1"  !CDS_PN = "P1";
"P2":   PN = "P2"  !CDS_PN = "P2";
"P3":   PN = "P3"  !CDS_PN = "P3";
"P4":   PN = "P4"  !CDS_PN = "P4";
"Q1":   PN = "Q1"  !CDS_PN = "Q1";
"Q2":   PN = "Q2"  !CDS_PN = "Q2";
"Q3":   PN = "Q3"  !CDS_PN = "Q3";
"Q4":   PN = "Q4"  !CDS_PN = "Q4";
"R1":   PN = "R1"  !CDS_PN = "R1";
"R2":   PN = "R2"  !CDS_PN = "R2";
"R3":   PN = "R3"  !CDS_PN = "R3";
"R4":   PN = "R4"  !CDS_PN = "R4";
"S1":   PN = "S1"  !CDS_PN = "S1";
"S2":   PN = "S2"  !CDS_PN = "S2";
"S3":   PN = "S3"  !CDS_PN = "S3";
"S4":   PN = "S4"  !CDS_PN = "S4";
"T1":   PN = "T1"  !CDS_PN = "T1";
"T2":   PN = "T2"  !CDS_PN = "T2";
"T3":   PN = "T3"  !CDS_PN = "T3";
"T4":   PN = "T4"  !CDS_PN = "T4";
DRAWING = "@s9s_mb_2u_lib.s9s_mb_2u(sch_1):page142";
BODY = "CONN112_10137002101LF","I65": #LOCATION = "J105" !CDS_LOCATION = "J105" &SEC = "2" #&CDS_SEC = "2";
"A1":   PN = "A1"  !CDS_PN = "A1";
"A2":   PN = "A2"  !CDS_PN = "A2";
"A3":   PN = "A3"  !CDS_PN = "A3";
"A4":   PN = "A4"  !CDS_PN = "A4";
"B1":   PN = "B1"  !CDS_PN = "B1";
"B2":   PN = "B2"  !CDS_PN = "B2";
"B3":   PN = "B3"  !CDS_PN = "B3";
"B4":   PN = "B4"  !CDS_PN = "B4";
"C1":   PN = "C1"  !CDS_PN = "C1";
"C2":   PN = "C2"  !CDS_PN = "C2";
"C3":   PN = "C3"  !CDS_PN = "C3";
"C4":   PN = "C4"  !CDS_PN = "C4";
"D1":   PN = "D1"  !CDS_PN = "D1";
"D2":   PN = "D2"  !CDS_PN = "D2";
"D3":   PN = "D3"  !CDS_PN = "D3";
"D4":   PN = "D4"  !CDS_PN = "D4";
"E1":   PN = "E1"  !CDS_PN = "E1";
"E2":   PN = "E2"  !CDS_PN = "E2";
"E3":   PN = "E3"  !CDS_PN = "E3";
"E4":   PN = "E4"  !CDS_PN = "E4";
"F1":   PN = "F1"  !CDS_PN = "F1";
"F2":   PN = "F2"  !CDS_PN = "F2";
"F3":   PN = "F3"  !CDS_PN = "F3";
"F4":   PN = "F4"  !CDS_PN = "F4";
"G1":   PN = "G1"  !CDS_PN = "G1";
"G2":   PN = "G2"  !CDS_PN = "G2";
"G3":   PN = "G3"  !CDS_PN = "G3";
"G4":   PN = "G4"  !CDS_PN = "G4";
"H1":   PN = "H1"  !CDS_PN = "H1";
"H2":   PN = "H2"  !CDS_PN = "H2";
"H3":   PN = "H3"  !CDS_PN = "H3";
"H4":   PN = "H4"  !CDS_PN = "H4";
"I1":   PN = "I1"  !CDS_PN = "I1";
"I2":   PN = "I2"  !CDS_PN = "I2";
"I3":   PN = "I3"  !CDS_PN = "I3";
"I4":   PN = "I4"  !CDS_PN = "I4";
"J1":   PN = "J1"  !CDS_PN = "J1";
"J2":   PN = "J2"  !CDS_PN = "J2";
"J3":   PN = "J3"  !CDS_PN = "J3";
"J4":   PN = "J4"  !CDS_PN = "J4";
"K1":   PN = "K1"  !CDS_PN = "K1";
"K2":   PN = "K2"  !CDS_PN = "K2";
"K3":   PN = "K3"  !CDS_PN = "K3";
"K4":   PN = "K4"  !CDS_PN = "K4";
"L1":   PN = "L1"  !CDS_PN = "L1";
"L2":   PN = "L2"  !CDS_PN = "L2";
"L3":   PN = "L3"  !CDS_PN = "L3";
"L4":   PN = "L4"  !CDS_PN = "L4";
"M1":   PN = "M1"  !CDS_PN = "M1";
"M2":   PN = "M2"  !CDS_PN = "M2";
"M3":   PN = "M3"  !CDS_PN = "M3";
"M4":   PN = "M4"  !CDS_PN = "M4";
"N1":   PN = "N1"  !CDS_PN = "N1";
"N2":   PN = "N2"  !CDS_PN = "N2";
"N3":   PN = "N3"  !CDS_PN = "N3";
"N4":   PN = "N4"  !CDS_PN = "N4";
BODY = "CONN112_10137002101LF","I68": #LOCATION = "J105" !CDS_LOCATION = "J105" &SEC = "1" #&CDS_SEC = "1";
"A5":   PN = "A5"  !CDS_PN = "A5";
"A6":   PN = "A6"  !CDS_PN = "A6";
"A7":   PN = "A7"  !CDS_PN = "A7";
"A8":   PN = "A8"  !CDS_PN = "A8";
"B5":   PN = "B5"  !CDS_PN = "B5";
"B6":   PN = "B6"  !CDS_PN = "B6";
"B7":   PN = "B7"  !CDS_PN = "B7";
"B8":   PN = "B8"  !CDS_PN = "B8";
"C5":   PN = "C5"  !CDS_PN = "C5";
"C6":   PN = "C6"  !CDS_PN = "C6";
"C7":   PN = "C7"  !CDS_PN = "C7";
"C8":   PN = "C8"  !CDS_PN = "C8";
"D5":   PN = "D5"  !CDS_PN = "D5";
"D6":   PN = "D6"  !CDS_PN = "D6";
"D7":   PN = "D7"  !CDS_PN = "D7";
"D8":   PN = "D8"  !CDS_PN = "D8";
"E5":   PN = "E5"  !CDS_PN = "E5";
"E6":   PN = "E6"  !CDS_PN = "E6";
"E7":   PN = "E7"  !CDS_PN = "E7";
"E8":   PN = "E8"  !CDS_PN = "E8";
"F5":   PN = "F5"  !CDS_PN = "F5";
"F6":   PN = "F6"  !CDS_PN = "F6";
"F7":   PN = "F7"  !CDS_PN = "F7";
"F8":   PN = "F8"  !CDS_PN = "F8";
"G5":   PN = "G5"  !CDS_PN = "G5";
"G6":   PN = "G6"  !CDS_PN = "G6";
"G7":   PN = "G7"  !CDS_PN = "G7";
"G8":   PN = "G8"  !CDS_PN = "G8";
"H5":   PN = "H5"  !CDS_PN = "H5";
"H6":   PN = "H6"  !CDS_PN = "H6";
"H7":   PN = "H7"  !CDS_PN = "H7";
"H8":   PN = "H8"  !CDS_PN = "H8";
"I5":   PN = "I5"  !CDS_PN = "I5";
"I6":   PN = "I6"  !CDS_PN = "I6";
"I7":   PN = "I7"  !CDS_PN = "I7";
"I8":   PN = "I8"  !CDS_PN = "I8";
"J5":   PN = "J5"  !CDS_PN = "J5";
"J6":   PN = "J6"  !CDS_PN = "J6";
"J7":   PN = "J7"  !CDS_PN = "J7";
"J8":   PN = "J8"  !CDS_PN = "J8";
"K5":   PN = "K5"  !CDS_PN = "K5";
"K6":   PN = "K6"  !CDS_PN = "K6";
"K7":   PN = "K7"  !CDS_PN = "K7";
"K8":   PN = "K8"  !CDS_PN = "K8";
"L5":   PN = "L5"  !CDS_PN = "L5";
"L6":   PN = "L6"  !CDS_PN = "L6";
"L7":   PN = "L7"  !CDS_PN = "L7";
"L8":   PN = "L8"  !CDS_PN = "L8";
"M5":   PN = "M5"  !CDS_PN = "M5";
"M6":   PN = "M6"  !CDS_PN = "M6";
"M7":   PN = "M7"  !CDS_PN = "M7";
"M8":   PN = "M8"  !CDS_PN = "M8";
"N5":   PN = "N5"  !CDS_PN = "N5";
"N6":   PN = "N6"  !CDS_PN = "N6";
"N7":   PN = "N7"  !CDS_PN = "N7";
"N8":   PN = "N8"  !CDS_PN = "N8";
DRAWING = "@s9s_mb_2u_lib.s9s_mb_2u(sch_1):page144";
BODY = "CONN112_10137002101LF","I65": #LOCATION = "J106" !CDS_LOCATION = "J106" &SEC = "2" #&CDS_SEC = "2";
"A1":   PN = "A1"  !CDS_PN = "A1";
"A2":   PN = "A2"  !CDS_PN = "A2";
"A3":   PN = "A3"  !CDS_PN = "A3";
"A4":   PN = "A4"  !CDS_PN = "A4";
"B1":   PN = "B1"  !CDS_PN = "B1";
"B2":   PN = "B2"  !CDS_PN = "B2";
"B3":   PN = "B3"  !CDS_PN = "B3";
"B4":   PN = "B4"  !CDS_PN = "B4";
"C1":   PN = "C1"  !CDS_PN = "C1";
"C2":   PN = "C2"  !CDS_PN = "C2";
"C3":   PN = "C3"  !CDS_PN = "C3";
"C4":   PN = "C4"  !CDS_PN = "C4";
"D1":   PN = "D1"  !CDS_PN = "D1";
"D2":   PN = "D2"  !CDS_PN = "D2";
"D3":   PN = "D3"  !CDS_PN = "D3";
"D4":   PN = "D4"  !CDS_PN = "D4";
"E1":   PN = "E1"  !CDS_PN = "E1";
"E2":   PN = "E2"  !CDS_PN = "E2";
"E3":   PN = "E3"  !CDS_PN = "E3";
"E4":   PN = "E4"  !CDS_PN = "E4";
"F1":   PN = "F1"  !CDS_PN = "F1";
"F2":   PN = "F2"  !CDS_PN = "F2";
"F3":   PN = "F3"  !CDS_PN = "F3";
"F4":   PN = "F4"  !CDS_PN = "F4";
"G1":   PN = "G1"  !CDS_PN = "G1";
"G2":   PN = "G2"  !CDS_PN = "G2";
"G3":   PN = "G3"  !CDS_PN = "G3";
"G4":   PN = "G4"  !CDS_PN = "G4";
"H1":   PN = "H1"  !CDS_PN = "H1";
"H2":   PN = "H2"  !CDS_PN = "H2";
"H3":   PN = "H3"  !CDS_PN = "H3";
"H4":   PN = "H4"  !CDS_PN = "H4";
"I1":   PN = "I1"  !CDS_PN = "I1";
"I2":   PN = "I2"  !CDS_PN = "I2";
"I3":   PN = "I3"  !CDS_PN = "I3";
"I4":   PN = "I4"  !CDS_PN = "I4";
"J1":   PN = "J1"  !CDS_PN = "J1";
"J2":   PN = "J2"  !CDS_PN = "J2";
"J3":   PN = "J3"  !CDS_PN = "J3";
"J4":   PN = "J4"  !CDS_PN = "J4";
"K1":   PN = "K1"  !CDS_PN = "K1";
"K2":   PN = "K2"  !CDS_PN = "K2";
"K3":   PN = "K3"  !CDS_PN = "K3";
"K4":   PN = "K4"  !CDS_PN = "K4";
"L1":   PN = "L1"  !CDS_PN = "L1";
"L2":   PN = "L2"  !CDS_PN = "L2";
"L3":   PN = "L3"  !CDS_PN = "L3";
"L4":   PN = "L4"  !CDS_PN = "L4";
"M1":   PN = "M1"  !CDS_PN = "M1";
"M2":   PN = "M2"  !CDS_PN = "M2";
"M3":   PN = "M3"  !CDS_PN = "M3";
"M4":   PN = "M4"  !CDS_PN = "M4";
"N1":   PN = "N1"  !CDS_PN = "N1";
"N2":   PN = "N2"  !CDS_PN = "N2";
"N3":   PN = "N3"  !CDS_PN = "N3";
"N4":   PN = "N4"  !CDS_PN = "N4";
BODY = "CONN112_10137002101LF","I68": #LOCATION = "J106" !CDS_LOCATION = "J106" &SEC = "1" #&CDS_SEC = "1";
"A5":   PN = "A5"  !CDS_PN = "A5";
"A6":   PN = "A6"  !CDS_PN = "A6";
"A7":   PN = "A7"  !CDS_PN = "A7";
"A8":   PN = "A8"  !CDS_PN = "A8";
"B5":   PN = "B5"  !CDS_PN = "B5";
"B6":   PN = "B6"  !CDS_PN = "B6";
"B7":   PN = "B7"  !CDS_PN = "B7";
"B8":   PN = "B8"  !CDS_PN = "B8";
"C5":   PN = "C5"  !CDS_PN = "C5";
"C6":   PN = "C6"  !CDS_PN = "C6";
"C7":   PN = "C7"  !CDS_PN = "C7";
"C8":   PN = "C8"  !CDS_PN = "C8";
"D5":   PN = "D5"  !CDS_PN = "D5";
"D6":   PN = "D6"  !CDS_PN = "D6";
"D7":   PN = "D7"  !CDS_PN = "D7";
"D8":   PN = "D8"  !CDS_PN = "D8";
"E5":   PN = "E5"  !CDS_PN = "E5";
"E6":   PN = "E6"  !CDS_PN = "E6";
"E7":   PN = "E7"  !CDS_PN = "E7";
"E8":   PN = "E8"  !CDS_PN = "E8";
"F5":   PN = "F5"  !CDS_PN = "F5";
"F6":   PN = "F6"  !CDS_PN = "F6";
"F7":   PN = "F7"  !CDS_PN = "F7";
"F8":   PN = "F8"  !CDS_PN = "F8";
"G5":   PN = "G5"  !CDS_PN = "G5";
"G6":   PN = "G6"  !CDS_PN = "G6";
"G7":   PN = "G7"  !CDS_PN = "G7";
"G8":   PN = "G8"  !CDS_PN = "G8";
"H5":   PN = "H5"  !CDS_PN = "H5";
"H6":   PN = "H6"  !CDS_PN = "H6";
"H7":   PN = "H7"  !CDS_PN = "H7";
"H8":   PN = "H8"  !CDS_PN = "H8";
"I5":   PN = "I5"  !CDS_PN = "I5";
"I6":   PN = "I6"  !CDS_PN = "I6";
"I7":   PN = "I7"  !CDS_PN = "I7";
"I8":   PN = "I8"  !CDS_PN = "I8";
"J5":   PN = "J5"  !CDS_PN = "J5";
"J6":   PN = "J6"  !CDS_PN = "J6";
"J7":   PN = "J7"  !CDS_PN = "J7";
"J8":   PN = "J8"  !CDS_PN = "J8";
"K5":   PN = "K5"  !CDS_PN = "K5";
"K6":   PN = "K6"  !CDS_PN = "K6";
"K7":   PN = "K7"  !CDS_PN = "K7";
"K8":   PN = "K8"  !CDS_PN = "K8";
"L5":   PN = "L5"  !CDS_PN = "L5";
"L6":   PN = "L6"  !CDS_PN = "L6";
"L7":   PN = "L7"  !CDS_PN = "L7";
"L8":   PN = "L8"  !CDS_PN = "L8";
"M5":   PN = "M5"  !CDS_PN = "M5";
"M6":   PN = "M6"  !CDS_PN = "M6";
"M7":   PN = "M7"  !CDS_PN = "M7";
"M8":   PN = "M8"  !CDS_PN = "M8";
"N5":   PN = "N5"  !CDS_PN = "N5";
"N6":   PN = "N6"  !CDS_PN = "N6";
"N7":   PN = "N7"  !CDS_PN = "N7";
"N8":   PN = "N8"  !CDS_PN = "N8";
DRAWING = "@s9s_mb_2u_lib.s9s_mb_2u(sch_1):page222";
BODY = "Q_RES","I12": LOCATION = "R2987" #&CDS_LOCATION = "R2987" &SEC = "1" #&CDS_SEC = "1";
"A":   PN = "1"  !CDS_PN = "1";
"B":   PN = "2"  !CDS_PN = "2";
BODY = "Q_RES","I16": LOCATION = "R2666" #&CDS_LOCATION = "R2666" &SEC = "1" #&CDS_SEC = "1";
"A":   PN = "1"  !CDS_PN = "1";
"B":   PN = "2"  !CDS_PN = "2";
BODY = "Q_CAP","I34": LOCATION = "C1708" #&CDS_LOCATION = "C1708" &SEC = "1" #&CDS_SEC = "1";
"A":   PN = "1"  !CDS_PN = "1";
"B":   PN = "2"  !CDS_PN = "2";
BODY = "Q_RES","I38": LOCATION = "R2893" #&CDS_LOCATION = "R2893" &SEC = "1" #&CDS_SEC = "1";
"A":   PN = "1"  !CDS_PN = "1";
"B":   PN = "2"  !CDS_PN = "2";
BODY = "Q_RES","I54": LOCATION = "R2724" #&CDS_LOCATION = "R2724" &SEC = "1" #&CDS_SEC = "1";
"A":   PN = "1"  !CDS_PN = "1";
"B":   PN = "2"  !CDS_PN = "2";
BODY = "Q_RES","I55": LOCATION = "R2705" #&CDS_LOCATION = "R2705" &SEC = "1" #&CDS_SEC = "1";
"A":   PN = "1"  !CDS_PN = "1";
"B":   PN = "2"  !CDS_PN = "2";
BODY = "Q_RES","I65": LOCATION = "R2671" #&CDS_LOCATION = "R2671" &SEC = "1" #&CDS_SEC = "1";
"A":   PN = "1"  !CDS_PN = "1";
"B":   PN = "2"  !CDS_PN = "2";
BODY = "Q_CAP","I66": LOCATION = "C1766" #&CDS_LOCATION = "C1766" &SEC = "1" #&CDS_SEC = "1";
"A":   PN = "1"  !CDS_PN = "1";
"B":   PN = "2"  !CDS_PN = "2";
BODY = "Q_RES","I72": LOCATION = "R2675" #&CDS_LOCATION = "R2675" &SEC = "1" #&CDS_SEC = "1";
"A":   PN = "1"  !CDS_PN = "1";
"B":   PN = "2"  !CDS_PN = "2";
BODY = "Q_RES","I7": LOCATION = "R3108" #&CDS_LOCATION = "R3108" &SEC = "1" #&CDS_SEC = "1";
"A":   PN = "1"  !CDS_PN = "1";
"B":   PN = "2"  !CDS_PN = "2";
BODY = "Q_RES","I8": LOCATION = "R3107" #&CDS_LOCATION = "R3107" &SEC = "1" #&CDS_SEC = "1";
"A":   PN = "1"  !CDS_PN = "1";
"B":   PN = "2"  !CDS_PN = "2";
BODY = "Q_RES","I9": LOCATION = "R2992" #&CDS_LOCATION = "R2992" &SEC = "1" #&CDS_SEC = "1";
"A":   PN = "1"  !CDS_PN = "1";
"B":   PN = "2"  !CDS_PN = "2";
BODY = "LTC4307CMS8","I11": #LOCATION = "U200" !CDS_LOCATION = "U200" &SEC = "1" #&CDS_SEC = "1";
"ENABLE":   PN = "1"  !CDS_PN = "1";
"GND":   PN = "4"  !CDS_PN = "4";
"READY":   PN = "5"  !CDS_PN = "5";
"SCL_IN":   PN = "3"  !CDS_PN = "3";
"SCL_OUT":   PN = "2"  !CDS_PN = "2";
"SDA_IN":   PN = "6"  !CDS_PN = "6";
"SDA_OUT":   PN = "7"  !CDS_PN = "7";
"VCC":   PN = "8"  !CDS_PN = "8";
BODY = "Q_RES","I13": LOCATION = "R2986" #&CDS_LOCATION = "R2986" &SEC = "1" #&CDS_SEC = "1";
"A":   PN = "1"  !CDS_PN = "1";
"B":   PN = "2"  !CDS_PN = "2";
BODY = "Q_RES","I17": #LOCATION = "R3111" !CDS_LOCATION = "R3111" &SEC = "1" #&CDS_SEC = "1";
"A":   PN = "1"  !CDS_PN = "1";
"B":   PN = "2"  !CDS_PN = "2";
BODY = "Q_RES","I18": #LOCATION = "R3112" !CDS_LOCATION = "R3112" &SEC = "1" #&CDS_SEC = "1";
"A":   PN = "1"  !CDS_PN = "1";
"B":   PN = "2"  !CDS_PN = "2";
BODY = "Q_RES","I19": LOCATION = "R2676" #&CDS_LOCATION = "R2676" &SEC = "1" #&CDS_SEC = "1";
"A":   PN = "1"  !CDS_PN = "1";
"B":   PN = "2"  !CDS_PN = "2";
BODY = "Q_CAP","I20": LOCATION = "C1796" #&CDS_LOCATION = "C1796" &SEC = "1" #&CDS_SEC = "1";
"A":   PN = "1"  !CDS_PN = "1";
"B":   PN = "2"  !CDS_PN = "2";
BODY = "Q_RES","I23": LOCATION = "R3521" #&CDS_LOCATION = "R3521" &SEC = "1" #&CDS_SEC = "1";
"A":   PN = "1"  !CDS_PN = "1";
"B":   PN = "2"  !CDS_PN = "2";
BODY = "Q_RES","I25": LOCATION = "R3522" #&CDS_LOCATION = "R3522" &SEC = "1" #&CDS_SEC = "1";
"A":   PN = "1"  !CDS_PN = "1";
"B":   PN = "2"  !CDS_PN = "2";
BODY = "Q_RES","I26": LOCATION = "R2990" #&CDS_LOCATION = "R2990" &SEC = "1" #&CDS_SEC = "1";
"A":   PN = "1"  !CDS_PN = "1";
"B":   PN = "2"  !CDS_PN = "2";
BODY = "Q_RES","I27": LOCATION = "R2991" #&CDS_LOCATION = "R2991" &SEC = "1" #&CDS_SEC = "1";
"A":   PN = "1"  !CDS_PN = "1";
"B":   PN = "2"  !CDS_PN = "2";
BODY = "Q_RES","I29": LOCATION = "R2725" #&CDS_LOCATION = "R2725" &SEC = "1" #&CDS_SEC = "1";
"A":   PN = "1"  !CDS_PN = "1";
"B":   PN = "2"  !CDS_PN = "2";
BODY = "Q_RES","I30": LOCATION = "R2706" #&CDS_LOCATION = "R2706" &SEC = "1" #&CDS_SEC = "1";
"A":   PN = "1"  !CDS_PN = "1";
"B":   PN = "2"  !CDS_PN = "2";
BODY = "LTC4307CMS8","I31": #LOCATION = "U176" !CDS_LOCATION = "U176" &SEC = "1" #&CDS_SEC = "1";
"ENABLE":   PN = "1"  !CDS_PN = "1";
"GND":   PN = "4"  !CDS_PN = "4";
"READY":   PN = "5"  !CDS_PN = "5";
"SCL_IN":   PN = "3"  !CDS_PN = "3";
"SCL_OUT":   PN = "2"  !CDS_PN = "2";
"SDA_IN":   PN = "6"  !CDS_PN = "6";
"SDA_OUT":   PN = "7"  !CDS_PN = "7";
"VCC":   PN = "8"  !CDS_PN = "8";
BODY = "Q_RES","I33": LOCATION = "R2894" #&CDS_LOCATION = "R2894" &SEC = "1" #&CDS_SEC = "1";
"A":   PN = "1"  !CDS_PN = "1";
"B":   PN = "2"  !CDS_PN = "2";
BODY = "Q_RES","I42": LOCATION = "R3106" #&CDS_LOCATION = "R3106" &SEC = "1" #&CDS_SEC = "1";
"A":   PN = "1"  !CDS_PN = "1";
"B":   PN = "2"  !CDS_PN = "2";
BODY = "Q_RES","I43": LOCATION = "R3105" #&CDS_LOCATION = "R3105" &SEC = "1" #&CDS_SEC = "1";
"A":   PN = "1"  !CDS_PN = "1";
"B":   PN = "2"  !CDS_PN = "2";
BODY = "Q_RES","I44": LOCATION = "R2707" #&CDS_LOCATION = "R2707" &SEC = "1" #&CDS_SEC = "1";
"A":   PN = "1"  !CDS_PN = "1";
"B":   PN = "2"  !CDS_PN = "2";
BODY = "Q_RES","I48": LOCATION = "R4603" #&CDS_LOCATION = "R4603" &SEC = "1" #&CDS_SEC = "1";
"A":   PN = "1"  !CDS_PN = "1";
"B":   PN = "2"  !CDS_PN = "2";
BODY = "LTC4307CMS8","I50": #LOCATION = "U175" !CDS_LOCATION = "U175" &SEC = "1" #&CDS_SEC = "1";
"ENABLE":   PN = "1"  !CDS_PN = "1";
"GND":   PN = "4"  !CDS_PN = "4";
"READY":   PN = "5"  !CDS_PN = "5";
"SCL_IN":   PN = "3"  !CDS_PN = "3";
"SCL_OUT":   PN = "2"  !CDS_PN = "2";
"SDA_IN":   PN = "6"  !CDS_PN = "6";
"SDA_OUT":   PN = "7"  !CDS_PN = "7";
"VCC":   PN = "8"  !CDS_PN = "8";
BODY = "Q_RES","I51": LOCATION = "R3109" #&CDS_LOCATION = "R3109" &SEC = "1" #&CDS_SEC = "1";
"A":   PN = "1"  !CDS_PN = "1";
"B":   PN = "2"  !CDS_PN = "2";
BODY = "Q_RES","I52": LOCATION = "R3110" #&CDS_LOCATION = "R3110" &SEC = "1" #&CDS_SEC = "1";
"A":   PN = "1"  !CDS_PN = "1";
"B":   PN = "2"  !CDS_PN = "2";
BODY = "Q_RES","I53": LOCATION = "R2899" #&CDS_LOCATION = "R2899" &SEC = "1" #&CDS_SEC = "1";
"A":   PN = "1"  !CDS_PN = "1";
"B":   PN = "2"  !CDS_PN = "2";
BODY = "Q_CAP","I58": LOCATION = "C1707" #&CDS_LOCATION = "C1707" &SEC = "1" #&CDS_SEC = "1";
"A":   PN = "1"  !CDS_PN = "1";
"B":   PN = "2"  !CDS_PN = "2";
BODY = "Q_RES","I59": LOCATION = "R2667" #&CDS_LOCATION = "R2667" &SEC = "1" #&CDS_SEC = "1";
"A":   PN = "1"  !CDS_PN = "1";
"B":   PN = "2"  !CDS_PN = "2";
BODY = "Q_RES","I61": LOCATION = "R2669" #&CDS_LOCATION = "R2669" &SEC = "1" #&CDS_SEC = "1";
"A":   PN = "1"  !CDS_PN = "1";
"B":   PN = "2"  !CDS_PN = "2";
BODY = "LTC4307CMS8","I63": #LOCATION = "U194" !CDS_LOCATION = "U194" &SEC = "1" #&CDS_SEC = "1";
"ENABLE":   PN = "1"  !CDS_PN = "1";
"GND":   PN = "4"  !CDS_PN = "4";
"READY":   PN = "5"  !CDS_PN = "5";
"SCL_IN":   PN = "3"  !CDS_PN = "3";
"SCL_OUT":   PN = "2"  !CDS_PN = "2";
"SDA_IN":   PN = "6"  !CDS_PN = "6";
"SDA_OUT":   PN = "7"  !CDS_PN = "7";
"VCC":   PN = "8"  !CDS_PN = "8";
BODY = "Q_RES","I64": LOCATION = "R2672" #&CDS_LOCATION = "R2672" &SEC = "1" #&CDS_SEC = "1";
"A":   PN = "1"  !CDS_PN = "1";
"B":   PN = "2"  !CDS_PN = "2";
BODY = "Q_RES","I71": LOCATION = "R2674" #&CDS_LOCATION = "R2674" &SEC = "1" #&CDS_SEC = "1";
"A":   PN = "1"  !CDS_PN = "1";
"B":   PN = "2"  !CDS_PN = "2";
BODY = "Q_RES","I75": LOCATION = "R2668" #&CDS_LOCATION = "R2668" &SEC = "1" #&CDS_SEC = "1";
"A":   PN = "1"  !CDS_PN = "1";
"B":   PN = "2"  !CDS_PN = "2";
BODY = "Q_RES","I77": LOCATION = "R2670" #&CDS_LOCATION = "R2670" &SEC = "1" #&CDS_SEC = "1";
"A":   PN = "1"  !CDS_PN = "1";
"B":   PN = "2"  !CDS_PN = "2";
BODY = "Q_RES","I78": LOCATION = "R2897" #&CDS_LOCATION = "R2897" &SEC = "1" #&CDS_SEC = "1";
"A":   PN = "1"  !CDS_PN = "1";
"B":   PN = "2"  !CDS_PN = "2";
BODY = "Q_RES","I79": LOCATION = "R2898" #&CDS_LOCATION = "R2898" &SEC = "1" #&CDS_SEC = "1";
"A":   PN = "1"  !CDS_PN = "1";
"B":   PN = "2"  !CDS_PN = "2";
BODY = "Q_RES","I80": LOCATION = "R3523" #&CDS_LOCATION = "R3523" &SEC = "1" #&CDS_SEC = "1";
"A":   PN = "1"  !CDS_PN = "1";
"B":   PN = "2"  !CDS_PN = "2";
BODY = "Q_RES","I81": LOCATION = "R3524" #&CDS_LOCATION = "R3524" &SEC = "1" #&CDS_SEC = "1";
"A":   PN = "1"  !CDS_PN = "1";
"B":   PN = "2"  !CDS_PN = "2";
DRAWING = "@s9s_mb_2u_lib.s9s_mb_2u(sch_1):page145";
BODY = "Q_RES","I14": LOCATION = "R2835" #&CDS_LOCATION = "R2835" &SEC = "1" #&CDS_SEC = "1";
"A":   PN = "1"  !CDS_PN = "1";
"B":   PN = "2"  !CDS_PN = "2";
BODY = "Q_RES","I18": LOCATION = "R2834" #&CDS_LOCATION = "R2834" &SEC = "1" #&CDS_SEC = "1";
"A":   PN = "1"  !CDS_PN = "1";
"B":   PN = "2"  !CDS_PN = "2";
BODY = "Q_RES","I19": LOCATION = "R2836" #&CDS_LOCATION = "R2836" &SEC = "1" #&CDS_SEC = "1";
"A":   PN = "1"  !CDS_PN = "1";
"B":   PN = "2"  !CDS_PN = "2";
BODY = "Q_RES","I24": LOCATION = "R2841" #&CDS_LOCATION = "R2841" &SEC = "1" #&CDS_SEC = "1";
"A":   PN = "1"  !CDS_PN = "1";
"B":   PN = "2"  !CDS_PN = "2";
BODY = "Q_RES","I30": LOCATION = "R2842" #&CDS_LOCATION = "R2842" &SEC = "1" #&CDS_SEC = "1";
"A":   PN = "1"  !CDS_PN = "1";
"B":   PN = "2"  !CDS_PN = "2";
BODY = "MOSFET_NCH_DUAL","I33": LOCATION = "Q67" #&CDS_LOCATION = "Q67" &SEC = "1" #&CDS_SEC = "1";
"D1":   PN = "6"  !CDS_PN = "6";
"G1":   PN = "2"  !CDS_PN = "2";
"S1":   PN = "1"  !CDS_PN = "1";
BODY = "MOSFET_NCH_DUAL","I35": #LOCATION = "Q70" !CDS_LOCATION = "Q70" &SEC = "1" #&CDS_SEC = "1";
"D1":   PN = "6"  !CDS_PN = "6";
"G1":   PN = "2"  !CDS_PN = "2";
"S1":   PN = "1"  !CDS_PN = "1";
BODY = "MOSFET_NCH_DUAL","I37": #LOCATION = "Q72" !CDS_LOCATION = "Q72" &SEC = "1" #&CDS_SEC = "1";
"D1":   PN = "6"  !CDS_PN = "6";
"G1":   PN = "2"  !CDS_PN = "2";
"S1":   PN = "1"  !CDS_PN = "1";
BODY = "Q_RES","I56": LOCATION = "R2831" #&CDS_LOCATION = "R2831" &SEC = "1" #&CDS_SEC = "1";
"A":   PN = "1"  !CDS_PN = "1";
"B":   PN = "2"  !CDS_PN = "2";
BODY = "Q_RES","I58": LOCATION = "R2829" #&CDS_LOCATION = "R2829" &SEC = "1" #&CDS_SEC = "1";
"A":   PN = "1"  !CDS_PN = "1";
"B":   PN = "2"  !CDS_PN = "2";
BODY = "Q_RES","I60": LOCATION = "R2833" #&CDS_LOCATION = "R2833" &SEC = "1" #&CDS_SEC = "1";
"A":   PN = "1"  !CDS_PN = "1";
"B":   PN = "2"  !CDS_PN = "2";
BODY = "Q_RES","I62": LOCATION = "R2838" #&CDS_LOCATION = "R2838" &SEC = "1" #&CDS_SEC = "1";
"A":   PN = "1"  !CDS_PN = "1";
"B":   PN = "2"  !CDS_PN = "2";
BODY = "Q_RES","I66": LOCATION = "R2828" #&CDS_LOCATION = "R2828" &SEC = "1" #&CDS_SEC = "1";
"A":   PN = "1"  !CDS_PN = "1";
"B":   PN = "2"  !CDS_PN = "2";
BODY = "Q_RES","I67": LOCATION = "R2832" #&CDS_LOCATION = "R2832" &SEC = "1" #&CDS_SEC = "1";
"A":   PN = "1"  !CDS_PN = "1";
"B":   PN = "2"  !CDS_PN = "2";
BODY = "Q_RES","I68": LOCATION = "R2830" #&CDS_LOCATION = "R2830" &SEC = "1" #&CDS_SEC = "1";
"A":   PN = "1"  !CDS_PN = "1";
"B":   PN = "2"  !CDS_PN = "2";
BODY = "Q_RES","I80": LOCATION = "R2837" #&CDS_LOCATION = "R2837" &SEC = "1" #&CDS_SEC = "1";
"A":   PN = "1"  !CDS_PN = "1";
"B":   PN = "2"  !CDS_PN = "2";
BODY = "MOSFET_NCH_DUAL","I82": #LOCATION = "Q67" !CDS_LOCATION = "Q67" &SEC = "2" #&CDS_SEC = "2";
"D2":   PN = "3"  !CDS_PN = "3";
"G2":   PN = "5"  !CDS_PN = "5";
"S2":   PN = "4"  !CDS_PN = "4";
BODY = "Q_RES","I84": LOCATION = "R2920" #&CDS_LOCATION = "R2920" &SEC = "1" #&CDS_SEC = "1";
"A":   PN = "1"  !CDS_PN = "1";
"B":   PN = "2"  !CDS_PN = "2";
BODY = "MOSFET_NCH_DUAL","I88": #LOCATION = "Q69" !CDS_LOCATION = "Q69" &SEC = "2" #&CDS_SEC = "2";
"D2":   PN = "3"  !CDS_PN = "3";
"G2":   PN = "5"  !CDS_PN = "5";
"S2":   PN = "4"  !CDS_PN = "4";
BODY = "Q_RES","I91": LOCATION = "R2919" #&CDS_LOCATION = "R2919" &SEC = "1" #&CDS_SEC = "1";
"A":   PN = "1"  !CDS_PN = "1";
"B":   PN = "2"  !CDS_PN = "2";
BODY = "Q_CAP","I92": LOCATION = "C1754" #&CDS_LOCATION = "C1754" &SEC = "1" #&CDS_SEC = "1";
"A":   PN = "1"  !CDS_PN = "1";
"B":   PN = "2"  !CDS_PN = "2";
BODY = "Q_RES","I97": LOCATION = "R2933" #&CDS_LOCATION = "R2933" &SEC = "1" #&CDS_SEC = "1";
"A":   PN = "1"  !CDS_PN = "1";
"B":   PN = "2"  !CDS_PN = "2";
BODY = "MOSFET_NCH_DUAL","I100": #LOCATION = "Q71" !CDS_LOCATION = "Q71" &SEC = "2" #&CDS_SEC = "2";
"D2":   PN = "3"  !CDS_PN = "3";
"G2":   PN = "5"  !CDS_PN = "5";
"S2":   PN = "4"  !CDS_PN = "4";
BODY = "Q_RES","I101": LOCATION = "R2934" #&CDS_LOCATION = "R2934" &SEC = "1" #&CDS_SEC = "1";
"A":   PN = "1"  !CDS_PN = "1";
"B":   PN = "2"  !CDS_PN = "2";
BODY = "Q_CAP","I105": LOCATION = "C1756" #&CDS_LOCATION = "C1756" &SEC = "1" #&CDS_SEC = "1";
"A":   PN = "1"  !CDS_PN = "1";
"B":   PN = "2"  !CDS_PN = "2";
BODY = "Q_RES","I109": LOCATION = "R2935" #&CDS_LOCATION = "R2935" &SEC = "1" #&CDS_SEC = "1";
"A":   PN = "1"  !CDS_PN = "1";
"B":   PN = "2"  !CDS_PN = "2";
BODY = "Q_CAP","I111": LOCATION = "C1774" #&CDS_LOCATION = "C1774" &SEC = "1" #&CDS_SEC = "1";
"A":   PN = "1"  !CDS_PN = "1";
"B":   PN = "2"  !CDS_PN = "2";
BODY = "Q_CAP","I114": LOCATION = "C1773" #&CDS_LOCATION = "C1773" &SEC = "1" #&CDS_SEC = "1";
"A":   PN = "1"  !CDS_PN = "1";
"B":   PN = "2"  !CDS_PN = "2";
BODY = "Q_CAP","I116": LOCATION = "C1772" #&CDS_LOCATION = "C1772" &SEC = "1" #&CDS_SEC = "1";
"A":   PN = "1"  !CDS_PN = "1";
"B":   PN = "2"  !CDS_PN = "2";
BODY = "MOSFET_NCH_DUAL","I117": #LOCATION = "Q69" !CDS_LOCATION = "Q69" &SEC = "1" #&CDS_SEC = "1";
"D1":   PN = "6"  !CDS_PN = "6";
"G1":   PN = "2"  !CDS_PN = "2";
"S1":   PN = "1"  !CDS_PN = "1";
BODY = "MOSFET_NCH_DUAL","I118": #LOCATION = "Q71" !CDS_LOCATION = "Q71" &SEC = "1" #&CDS_SEC = "1";
"D1":   PN = "6"  !CDS_PN = "6";
"G1":   PN = "2"  !CDS_PN = "2";
"S1":   PN = "1"  !CDS_PN = "1";
BODY = "MOSFET_NCH_DUAL","I119": #LOCATION = "Q72" !CDS_LOCATION = "Q72" #SEC = "2" !CDS_SEC = "2";
"D2":   PN = "3"  !CDS_PN = "3";
"G2":   PN = "5"  !CDS_PN = "5";
"S2":   PN = "4"  !CDS_PN = "4";
BODY = "MOSFET_NCH_DUAL","I120": #LOCATION = "Q70" !CDS_LOCATION = "Q70" &SEC = "2" #&CDS_SEC = "2";
"D2":   PN = "3"  !CDS_PN = "3";
"G2":   PN = "5"  !CDS_PN = "5";
"S2":   PN = "4"  !CDS_PN = "4";
BODY = "MOSFET_NCH_DUAL","I121": #LOCATION = "Q74" !CDS_LOCATION = "Q74" #SEC = "1" !CDS_SEC = "1";
"D1":   PN = "6"  !CDS_PN = "6";
"G1":   PN = "2"  !CDS_PN = "2";
"S1":   PN = "1"  !CDS_PN = "1";
BODY = "MOSFET_NCH_DUAL","I122": #LOCATION = "Q74" !CDS_LOCATION = "Q74" #SEC = "2" !CDS_SEC = "2";
"D2":   PN = "3"  !CDS_PN = "3";
"G2":   PN = "5"  !CDS_PN = "5";
"S2":   PN = "4"  !CDS_PN = "4";
BODY = "Q_CAP","I125": LOCATION = "C1804" #&CDS_LOCATION = "C1804" &SEC = "1" #&CDS_SEC = "1";
"A":   PN = "1"  !CDS_PN = "1";
"B":   PN = "2"  !CDS_PN = "2";
BODY = "Q_RES","I127": LOCATION = "R3035" #&CDS_LOCATION = "R3035" &SEC = "1" #&CDS_SEC = "1";
"A":   PN = "1"  !CDS_PN = "1";
"B":   PN = "2"  !CDS_PN = "2";
BODY = "Q_RES","I129": LOCATION = "R3034" #&CDS_LOCATION = "R3034" &SEC = "1" #&CDS_SEC = "1";
"A":   PN = "1"  !CDS_PN = "1";
"B":   PN = "2"  !CDS_PN = "2";
BODY = "Q_RES","I134": LOCATION = "R3032" #&CDS_LOCATION = "R3032" &SEC = "1" #&CDS_SEC = "1";
"A":   PN = "1"  !CDS_PN = "1";
"B":   PN = "2"  !CDS_PN = "2";
BODY = "Q_RES","I139": LOCATION = "R3028" #&CDS_LOCATION = "R3028" &SEC = "1" #&CDS_SEC = "1";
"A":   PN = "1"  !CDS_PN = "1";
"B":   PN = "2"  !CDS_PN = "2";
BODY = "Q_RES","I144": LOCATION = "R3029" #&CDS_LOCATION = "R3029" &SEC = "1" #&CDS_SEC = "1";
"A":   PN = "1"  !CDS_PN = "1";
"B":   PN = "2"  !CDS_PN = "2";
BODY = "Q_RES","I146": LOCATION = "R3030" #&CDS_LOCATION = "R3030" &SEC = "1" #&CDS_SEC = "1";
"A":   PN = "1"  !CDS_PN = "1";
"B":   PN = "2"  !CDS_PN = "2";
BODY = "Q_CAP","I148": LOCATION = "C1802" #&CDS_LOCATION = "C1802" &SEC = "1" #&CDS_SEC = "1";
"A":   PN = "1"  !CDS_PN = "1";
"B":   PN = "2"  !CDS_PN = "2";
BODY = "MOSFET_NCH_DUAL","I151": #LOCATION = "Q75" !CDS_LOCATION = "Q75" &SEC = "2" #&CDS_SEC = "2";
"D2":   PN = "3"  !CDS_PN = "3";
"G2":   PN = "5"  !CDS_PN = "5";
"S2":   PN = "4"  !CDS_PN = "4";
BODY = "MOSFET_NCH_DUAL","I152": #LOCATION = "Q75" !CDS_LOCATION = "Q75" &SEC = "1" #&CDS_SEC = "1";
"D1":   PN = "6"  !CDS_PN = "6";
"G1":   PN = "2"  !CDS_PN = "2";
"S1":   PN = "1"  !CDS_PN = "1";
BODY = "MOSFET_NCH_DUAL","I159": #LOCATION = "Q96" !CDS_LOCATION = "Q96" &SEC = "2" #&CDS_SEC = "2";
"D2":   PN = "3"  !CDS_PN = "3";
"G2":   PN = "5"  !CDS_PN = "5";
"S2":   PN = "4"  !CDS_PN = "4";
BODY = "MOSFET_NCH_DUAL","I154": LOCATION = "Q96" #&CDS_LOCATION = "Q96" &SEC = "1" #&CDS_SEC = "1";
"D1":   PN = "6"  !CDS_PN = "6";
"G1":   PN = "2"  !CDS_PN = "2";
"S1":   PN = "1"  !CDS_PN = "1";
BODY = "Q_CAP","I156": LOCATION = "C1881" #&CDS_LOCATION = "C1881" &SEC = "1" #&CDS_SEC = "1";
"A":   PN = "1"  !CDS_PN = "1";
"B":   PN = "2"  !CDS_PN = "2";
BODY = "Q_RES","I158": LOCATION = "R3321" #&CDS_LOCATION = "R3321" &SEC = "1" #&CDS_SEC = "1";
"A":   PN = "1"  !CDS_PN = "1";
"B":   PN = "2"  !CDS_PN = "2";
BODY = "Q_RES","I162": LOCATION = "R3320" #&CDS_LOCATION = "R3320" &SEC = "1" #&CDS_SEC = "1";
"A":   PN = "1"  !CDS_PN = "1";
"B":   PN = "2"  !CDS_PN = "2";
BODY = "Q_RES","I171": LOCATION = "R3318" #&CDS_LOCATION = "R3318" &SEC = "1" #&CDS_SEC = "1";
"A":   PN = "1"  !CDS_PN = "1";
"B":   PN = "2"  !CDS_PN = "2";
BODY = "Q_RES","I172": LOCATION = "R3511" #&CDS_LOCATION = "R3511" &SEC = "1" #&CDS_SEC = "1";
"A":   PN = "1"  !CDS_PN = "1";
"B":   PN = "2"  !CDS_PN = "2";
BODY = "Q_RES","I173": LOCATION = "R3513" #&CDS_LOCATION = "R3513" &SEC = "1" #&CDS_SEC = "1";
"A":   PN = "1"  !CDS_PN = "1";
"B":   PN = "2"  !CDS_PN = "2";
BODY = "Q_RES","I174": LOCATION = "R3512" #&CDS_LOCATION = "R3512" &SEC = "1" #&CDS_SEC = "1";
"A":   PN = "1"  !CDS_PN = "1";
"B":   PN = "2"  !CDS_PN = "2";
BODY = "Q_RES","I175": LOCATION = "R3514" #&CDS_LOCATION = "R3514" &SEC = "1" #&CDS_SEC = "1";
"A":   PN = "1"  !CDS_PN = "1";
"B":   PN = "2"  !CDS_PN = "2";
BODY = "Q_RES","I176": LOCATION = "R3510" #&CDS_LOCATION = "R3510" &SEC = "1" #&CDS_SEC = "1";
"A":   PN = "1"  !CDS_PN = "1";
"B":   PN = "2"  !CDS_PN = "2";
DRAWING = "@s9s_mb_2u_lib.s9s_mb_2u(sch_1):page214";
BODY = "Q_RES","I34": LOCATION = "R2848" #&CDS_LOCATION = "R2848" &SEC = "1" #&CDS_SEC = "1";
"A":   PN = "1"  !CDS_PN = "1";
"B":   PN = "2"  !CDS_PN = "2";
BODY = "PCA9539RPW","I66": #LOCATION = "U181" !CDS_LOCATION = "U181" #SEC = "1" !CDS_SEC = "1";
"A0":   PN = "21"  !CDS_PN = "21";
"A1":   PN = "2"  !CDS_PN = "2";
"INT":   PN = "1"  !CDS_PN = "1";
"IO0_0":   PN = "4"  !CDS_PN = "4";
"IO0_1":   PN = "5"  !CDS_PN = "5";
"IO0_2":   PN = "6"  !CDS_PN = "6";
"IO0_3":   PN = "7"  !CDS_PN = "7";
"IO0_4":   PN = "8"  !CDS_PN = "8";
"IO0_5":   PN = "9"  !CDS_PN = "9";
"IO0_6":   PN = "10"  !CDS_PN = "10";
"IO0_7":   PN = "11"  !CDS_PN = "11";
"IO1_0":   PN = "13"  !CDS_PN = "13";
"IO1_1":   PN = "14"  !CDS_PN = "14";
"IO1_2":   PN = "15"  !CDS_PN = "15";
"IO1_3":   PN = "16"  !CDS_PN = "16";
"IO1_4":   PN = "17"  !CDS_PN = "17";
"IO1_5":   PN = "18"  !CDS_PN = "18";
"IO1_6":   PN = "19"  !CDS_PN = "19";
"IO1_7":   PN = "20"  !CDS_PN = "20";
"RESET":   PN = "3"  !CDS_PN = "3";
"SCL":   PN = "22"  !CDS_PN = "22";
"SDA":   PN = "23"  !CDS_PN = "23";
"VDD":   PN = "24"  !CDS_PN = "24";
"VSS":   PN = "12"  !CDS_PN = "12";
BODY = "Q_RES","I74": LOCATION = "R2695" #&CDS_LOCATION = "R2695" &SEC = "1" #&CDS_SEC = "1";
"A":   PN = "1"  !CDS_PN = "1";
"B":   PN = "2"  !CDS_PN = "2";
BODY = "Q_RES","I75": LOCATION = "R2696" #&CDS_LOCATION = "R2696" &SEC = "1" #&CDS_SEC = "1";
"A":   PN = "1"  !CDS_PN = "1";
"B":   PN = "2"  !CDS_PN = "2";
BODY = "Q_RES","I76": LOCATION = "R2693" #&CDS_LOCATION = "R2693" &SEC = "1" #&CDS_SEC = "1";
"A":   PN = "1"  !CDS_PN = "1";
"B":   PN = "2"  !CDS_PN = "2";
BODY = "Q_RES","I77": LOCATION = "R2694" #&CDS_LOCATION = "R2694" &SEC = "1" #&CDS_SEC = "1";
"A":   PN = "1"  !CDS_PN = "1";
"B":   PN = "2"  !CDS_PN = "2";
BODY = "Q_CAP","I87": LOCATION = "C1713" #&CDS_LOCATION = "C1713" &SEC = "1" #&CDS_SEC = "1";
"A":   PN = "1"  !CDS_PN = "1";
"B":   PN = "2"  !CDS_PN = "2";
BODY = "Q_RES","I90": LOCATION = "R2923" #&CDS_LOCATION = "R2923" &SEC = "1" #&CDS_SEC = "1";
"A":   PN = "1"  !CDS_PN = "1";
"B":   PN = "2"  !CDS_PN = "2";
BODY = "Q_RES","I93": LOCATION = "R2921" #&CDS_LOCATION = "R2921" &SEC = "1" #&CDS_SEC = "1";
"A":   PN = "1"  !CDS_PN = "1";
"B":   PN = "2"  !CDS_PN = "2";
BODY = "Q_RES","I95": LOCATION = "R2922" #&CDS_LOCATION = "R2922" &SEC = "1" #&CDS_SEC = "1";
"A":   PN = "1"  !CDS_PN = "1";
"B":   PN = "2"  !CDS_PN = "2";
BODY = "Q_RES","I96": LOCATION = "R2982" #&CDS_LOCATION = "R2982" &SEC = "1" #&CDS_SEC = "1";
"A":   PN = "1"  !CDS_PN = "1";
"B":   PN = "2"  !CDS_PN = "2";
BODY = "Q_RES","I101": LOCATION = "R2983" #&CDS_LOCATION = "R2983" &SEC = "1" #&CDS_SEC = "1";
"A":   PN = "1"  !CDS_PN = "1";
"B":   PN = "2"  !CDS_PN = "2";
BODY = "Q_RES","I118": LOCATION = "R3499" #&CDS_LOCATION = "R3499" &SEC = "1" #&CDS_SEC = "1";
"A":   PN = "1"  !CDS_PN = "1";
"B":   PN = "2"  !CDS_PN = "2";
BODY = "Q_RES","I127": LOCATION = "R3516" #&CDS_LOCATION = "R3516" &SEC = "1" #&CDS_SEC = "1";
"A":   PN = "1"  !CDS_PN = "1";
"B":   PN = "2"  !CDS_PN = "2";
BODY = "Q_RES","I128": LOCATION = "R3517" #&CDS_LOCATION = "R3517" &SEC = "1" #&CDS_SEC = "1";
"A":   PN = "1"  !CDS_PN = "1";
"B":   PN = "2"  !CDS_PN = "2";
BODY = "Q_RES","I129": LOCATION = "R3518" #&CDS_LOCATION = "R3518" &SEC = "1" #&CDS_SEC = "1";
"A":   PN = "1"  !CDS_PN = "1";
"B":   PN = "2"  !CDS_PN = "2";
BODY = "Q_RES","I137": LOCATION = "R4728" #&CDS_LOCATION = "R4728" &SEC = "1" #&CDS_SEC = "1";
"A":   PN = "1"  !CDS_PN = "1";
"B":   PN = "2"  !CDS_PN = "2";
BODY = "Q_RES","I140": LOCATION = "R4729" #&CDS_LOCATION = "R4729" &SEC = "1" #&CDS_SEC = "1";
"A":   PN = "1"  !CDS_PN = "1";
"B":   PN = "2"  !CDS_PN = "2";
BODY = "Q_RES","I144": LOCATION = "R4734" #&CDS_LOCATION = "R4734" &SEC = "1" #&CDS_SEC = "1";
"A":   PN = "1"  !CDS_PN = "1";
"B":   PN = "2"  !CDS_PN = "2";
BODY = "Q_RES","I148": LOCATION = "R4735" #&CDS_LOCATION = "R4735" &SEC = "1" #&CDS_SEC = "1";
"A":   PN = "1"  !CDS_PN = "1";
"B":   PN = "2"  !CDS_PN = "2";
BODY = "Q_RES","I153": LOCATION = "R4736" #&CDS_LOCATION = "R4736" &SEC = "1" #&CDS_SEC = "1";
"A":   PN = "1"  !CDS_PN = "1";
"B":   PN = "2"  !CDS_PN = "2";
BODY = "Q_RES","I156": LOCATION = "R4741" #&CDS_LOCATION = "R4741" &SEC = "1" #&CDS_SEC = "1";
"A":   PN = "1"  !CDS_PN = "1";
"B":   PN = "2"  !CDS_PN = "2";
BODY = "Q_RES","I161": LOCATION = "R4742" #&CDS_LOCATION = "R4742" &SEC = "1" #&CDS_SEC = "1";
"A":   PN = "1"  !CDS_PN = "1";
"B":   PN = "2"  !CDS_PN = "2";
BODY = "Q_RES","I164": LOCATION = "R4802" #&CDS_LOCATION = "R4802" &SEC = "1" #&CDS_SEC = "1";
"A":   PN = "1"  !CDS_PN = "1";
"B":   PN = "2"  !CDS_PN = "2";
DRAWING = "@s9s_mb_2u_lib.s9s_mb_2u(sch_1):page140";
BODY = "74LVC2G17GW","I65": LOCATION = "U195" #&CDS_LOCATION = "U195" &SEC = "1" #&CDS_SEC = "1";
"A0":   PN = "1"  !CDS_PN = "1";
"A1":   PN = "3"  !CDS_PN = "3";
"B0":   PN = "6"  !CDS_PN = "6";
"B1":   PN = "4"  !CDS_PN = "4";
"GND":   PN = "2"  !CDS_PN = "2";
"VCC":   PN = "5"  !CDS_PN = "5";
BODY = "Q_RES","I68": LOCATION = "R2815" #&CDS_LOCATION = "R2815" &SEC = "1" #&CDS_SEC = "1";
"A":   PN = "1"  !CDS_PN = "1";
"B":   PN = "2"  !CDS_PN = "2";
BODY = "Q_RES","I78": LOCATION = "R2820" #&CDS_LOCATION = "R2820" &SEC = "1" #&CDS_SEC = "1";
"A":   PN = "1"  !CDS_PN = "1";
"B":   PN = "2"  !CDS_PN = "2";
BODY = "Q_CAP","I89": LOCATION = "C1769" #&CDS_LOCATION = "C1769" &SEC = "1" #&CDS_SEC = "1";
"A":   PN = "1"  !CDS_PN = "1";
"B":   PN = "2"  !CDS_PN = "2";
BODY = "Q_RES","I92": LOCATION = "R2915" #&CDS_LOCATION = "R2915" &SEC = "1" #&CDS_SEC = "1";
"A":   PN = "1"  !CDS_PN = "1";
"B":   PN = "2"  !CDS_PN = "2";
BODY = "Q_RES","I93": LOCATION = "R2916" #&CDS_LOCATION = "R2916" &SEC = "1" #&CDS_SEC = "1";
"A":   PN = "1"  !CDS_PN = "1";
"B":   PN = "2"  !CDS_PN = "2";
BODY = "Q_RES","I121": LOCATION = "R2926" #&CDS_LOCATION = "R2926" &SEC = "1" #&CDS_SEC = "1";
"A":   PN = "1"  !CDS_PN = "1";
"B":   PN = "2"  !CDS_PN = "2";
BODY = "74LVC2G17GW","I127": LOCATION = "U196" #&CDS_LOCATION = "U196" &SEC = "1" #&CDS_SEC = "1";
"A0":   PN = "1"  !CDS_PN = "1";
"A1":   PN = "3"  !CDS_PN = "3";
"B0":   PN = "6"  !CDS_PN = "6";
"B1":   PN = "4"  !CDS_PN = "4";
"GND":   PN = "2"  !CDS_PN = "2";
"VCC":   PN = "5"  !CDS_PN = "5";
BODY = "Q_CAP","I140": LOCATION = "C1770" #&CDS_LOCATION = "C1770" &SEC = "1" #&CDS_SEC = "1";
"A":   PN = "1"  !CDS_PN = "1";
"B":   PN = "2"  !CDS_PN = "2";
BODY = "Q_RES","I147": LOCATION = "R2912" #&CDS_LOCATION = "R2912" &SEC = "1" #&CDS_SEC = "1";
"A":   PN = "1"  !CDS_PN = "1";
"B":   PN = "2"  !CDS_PN = "2";
BODY = "Q_RES","I153": LOCATION = "R2911" #&CDS_LOCATION = "R2911" &SEC = "1" #&CDS_SEC = "1";
"A":   PN = "1"  !CDS_PN = "1";
"B":   PN = "2"  !CDS_PN = "2";
BODY = "Q_RES","I160": LOCATION = "R2937" #&CDS_LOCATION = "R2937" &SEC = "1" #&CDS_SEC = "1";
"A":   PN = "1"  !CDS_PN = "1";
"B":   PN = "2"  !CDS_PN = "2";
BODY = "Q_RES","I162": LOCATION = "R2936" #&CDS_LOCATION = "R2936" &SEC = "1" #&CDS_SEC = "1";
"A":   PN = "1"  !CDS_PN = "1";
"B":   PN = "2"  !CDS_PN = "2";
BODY = "Q_CAP","I166": LOCATION = "C1803" #&CDS_LOCATION = "C1803" &SEC = "1" #&CDS_SEC = "1";
"A":   PN = "1"  !CDS_PN = "1";
"B":   PN = "2"  !CDS_PN = "2";
BODY = "Q_RES","I170": LOCATION = "R3033" #&CDS_LOCATION = "R3033" &SEC = "1" #&CDS_SEC = "1";
"A":   PN = "1"  !CDS_PN = "1";
"B":   PN = "2"  !CDS_PN = "2";
BODY = "Q_RES","I190": LOCATION = "R3317" #&CDS_LOCATION = "R3317" &SEC = "1" #&CDS_SEC = "1";
"A":   PN = "1"  !CDS_PN = "1";
"B":   PN = "2"  !CDS_PN = "2";
BODY = "Q_RES","I191": LOCATION = "R3509" #&CDS_LOCATION = "R3509" &SEC = "1" #&CDS_SEC = "1";
"A":   PN = "1"  !CDS_PN = "1";
"B":   PN = "2"  !CDS_PN = "2";
BODY = "Q_RES","I192": LOCATION = "R3507" #&CDS_LOCATION = "R3507" &SEC = "1" #&CDS_SEC = "1";
"A":   PN = "1"  !CDS_PN = "1";
"B":   PN = "2"  !CDS_PN = "2";
BODY = "Q_RES","I193": LOCATION = "R3506" #&CDS_LOCATION = "R3506" &SEC = "1" #&CDS_SEC = "1";
"A":   PN = "1"  !CDS_PN = "1";
"B":   PN = "2"  !CDS_PN = "2";
BODY = "Q_RES","I194": LOCATION = "R3508" #&CDS_LOCATION = "R3508" &SEC = "1" #&CDS_SEC = "1";
"A":   PN = "1"  !CDS_PN = "1";
"B":   PN = "2"  !CDS_PN = "2";
BODY = "74LVC1G126SE7","I195": #LOCATION = "U204" !CDS_LOCATION = "U204" &SEC = "1" #&CDS_SEC = "1";
"A":   PN = "2"  !CDS_PN = "2";
"GND":   PN = "3"  !CDS_PN = "3";
"OE":   PN = "1"  !CDS_PN = "1";
"VCC":   PN = "5"  !CDS_PN = "5";
"Y":   PN = "4"  !CDS_PN = "4";
BODY = "Q_RES","I197": #LOCATION = "R3036" !CDS_LOCATION = "R3036" &SEC = "1" #&CDS_SEC = "1";
"A":   PN = "1"  !CDS_PN = "1";
"B":   PN = "2"  !CDS_PN = "2";
BODY = "Q_RES","I198": #LOCATION = "R2909" !CDS_LOCATION = "R2909" &SEC = "1" #&CDS_SEC = "1";
"A":   PN = "1"  !CDS_PN = "1";
"B":   PN = "2"  !CDS_PN = "2";
BODY = "Q_RES","I200": #LOCATION = "R4515" !CDS_LOCATION = "R4515" &SEC = "1" #&CDS_SEC = "1";
"A":   PN = "1"  !CDS_PN = "1";
"B":   PN = "2"  !CDS_PN = "2";
BODY = "Q_RES","I202": #LOCATION = "R4173" !CDS_LOCATION = "R4173" &SEC = "1" #&CDS_SEC = "1";
"A":   PN = "1"  !CDS_PN = "1";
"B":   PN = "2"  !CDS_PN = "2";
BODY = "Q_RES","I203": #LOCATION = "R2927" !CDS_LOCATION = "R2927" &SEC = "1" #&CDS_SEC = "1";
"A":   PN = "1"  !CDS_PN = "1";
"B":   PN = "2"  !CDS_PN = "2";
BODY = "Q_RES","I204": #LOCATION = "R2925" !CDS_LOCATION = "R2925" &SEC = "1" #&CDS_SEC = "1";
"A":   PN = "1"  !CDS_PN = "1";
"B":   PN = "2"  !CDS_PN = "2";
BODY = "Q_RES","I205": #LOCATION = "R3315" !CDS_LOCATION = "R3315" &SEC = "1" #&CDS_SEC = "1";
"A":   PN = "1"  !CDS_PN = "1";
"B":   PN = "2"  !CDS_PN = "2";
BODY = "Q_RES","I206": #LOCATION = "R2917" !CDS_LOCATION = "R2917" &SEC = "1" #&CDS_SEC = "1";
"A":   PN = "1"  !CDS_PN = "1";
"B":   PN = "2"  !CDS_PN = "2";
BODY = "Q_RES","I207": #LOCATION = "R2924" !CDS_LOCATION = "R2924" &SEC = "1" #&CDS_SEC = "1";
"A":   PN = "1"  !CDS_PN = "1";
"B":   PN = "2"  !CDS_PN = "2";
BODY = "Q_RES","I208": #LOCATION = "R3063" !CDS_LOCATION = "R3063" &SEC = "1" #&CDS_SEC = "1";
"A":   PN = "1"  !CDS_PN = "1";
"B":   PN = "2"  !CDS_PN = "2";
DRAWING = "@s9s_mb_2u_lib.s9s_mb_2u(sch_1):page230";
BODY = "Q_CAP","I14": LOCATION = "C1775" #&CDS_LOCATION = "C1775" &SEC = "1" #&CDS_SEC = "1";
"A":   PN = "1"  !CDS_PN = "1";
"B":   PN = "2"  !CDS_PN = "2";
BODY = "Q_RES","I24": LOCATION = "R2944" #&CDS_LOCATION = "R2944" &SEC = "1" #&CDS_SEC = "1";
"A":   PN = "1"  !CDS_PN = "1";
"B":   PN = "2"  !CDS_PN = "2";
BODY = "Q_RES","I25": LOCATION = "R2946" #&CDS_LOCATION = "R2946" &SEC = "1" #&CDS_SEC = "1";
"A":   PN = "1"  !CDS_PN = "1";
"B":   PN = "2"  !CDS_PN = "2";
BODY = "Q_RES","I28": LOCATION = "R2940" #&CDS_LOCATION = "R2940" &SEC = "1" #&CDS_SEC = "1";
"A":   PN = "1"  !CDS_PN = "1";
"B":   PN = "2"  !CDS_PN = "2";
BODY = "Q_RES","I29": LOCATION = "R2941" #&CDS_LOCATION = "R2941" &SEC = "1" #&CDS_SEC = "1";
"A":   PN = "1"  !CDS_PN = "1";
"B":   PN = "2"  !CDS_PN = "2";
BODY = "Q_RES","I30": LOCATION = "R2948" #&CDS_LOCATION = "R2948" &SEC = "1" #&CDS_SEC = "1";
"A":   PN = "1"  !CDS_PN = "1";
"B":   PN = "2"  !CDS_PN = "2";
BODY = "74LVC1G08W57","I31": LOCATION = "U278" #&CDS_LOCATION = "U278" &SEC = "1" #&CDS_SEC = "1";
"A":   PN = "1"  !CDS_PN = "1";
"B":   PN = "2"  !CDS_PN = "2";
"GND":   PN = "3"  !CDS_PN = "3";
"VCC":   PN = "5"  !CDS_PN = "5";
"Y":   PN = "4"  !CDS_PN = "4";
BODY = "Q_RES","I34": LOCATION = "R3770" #&CDS_LOCATION = "R3770" &SEC = "1" #&CDS_SEC = "1";
"A":   PN = "1"  !CDS_PN = "1";
"B":   PN = "2"  !CDS_PN = "2";
BODY = "74LVC2G07DW7","I37": LOCATION = "U308" #&CDS_LOCATION = "U308" &SEC = "1" #&CDS_SEC = "1";
"1A":   PN = "1"  !CDS_PN = "1";
"1Y":   PN = "6"  !CDS_PN = "6";
"2A":   PN = "3"  !CDS_PN = "3";
"2Y":   PN = "4"  !CDS_PN = "4";
"GND":   PN = "2"  !CDS_PN = "2";
"VCC":   PN = "5"  !CDS_PN = "5";
BODY = "Q_CAP","I40": LOCATION = "C2283" #&CDS_LOCATION = "C2283" &SEC = "1" #&CDS_SEC = "1";
"A":   PN = "1"  !CDS_PN = "1";
"B":   PN = "2"  !CDS_PN = "2";
BODY = "Q_RES","I41": LOCATION = "R4268" #&CDS_LOCATION = "R4268" &SEC = "1" #&CDS_SEC = "1";
"A":   PN = "1"  !CDS_PN = "1";
"B":   PN = "2"  !CDS_PN = "2";
BODY = "Q_RES","I43": LOCATION = "R4265" #&CDS_LOCATION = "R4265" &SEC = "1" #&CDS_SEC = "1";
"A":   PN = "1"  !CDS_PN = "1";
"B":   PN = "2"  !CDS_PN = "2";
BODY = "Q_RES","I47": LOCATION = "R4264" #&CDS_LOCATION = "R4264" &SEC = "1" #&CDS_SEC = "1";
"A":   PN = "1"  !CDS_PN = "1";
"B":   PN = "2"  !CDS_PN = "2";
BODY = "Q_RES","I48": LOCATION = "R4266" #&CDS_LOCATION = "R4266" &SEC = "1" #&CDS_SEC = "1";
"A":   PN = "1"  !CDS_PN = "1";
"B":   PN = "2"  !CDS_PN = "2";
BODY = "Q_RES","I50": LOCATION = "R4552" #&CDS_LOCATION = "R4552" &SEC = "1" #&CDS_SEC = "1";
"A":   PN = "1"  !CDS_PN = "1";
"B":   PN = "2"  !CDS_PN = "2";
BODY = "Q_RES","I51": LOCATION = "R4551" #&CDS_LOCATION = "R4551" &SEC = "1" #&CDS_SEC = "1";
"A":   PN = "1"  !CDS_PN = "1";
"B":   PN = "2"  !CDS_PN = "2";
BODY = "MOSFET_NCH_DUAL","I53": LOCATION = "Q145" #&CDS_LOCATION = "Q145" &SEC = "1" #&CDS_SEC = "1";
"D1":   PN = "6"  !CDS_PN = "6";
"G1":   PN = "2"  !CDS_PN = "2";
"S1":   PN = "1"  !CDS_PN = "1";
BODY = "Q_RES","I55": LOCATION = "R4553" #&CDS_LOCATION = "R4553" &SEC = "1" #&CDS_SEC = "1";
"A":   PN = "1"  !CDS_PN = "1";
"B":   PN = "2"  !CDS_PN = "2";
BODY = "MOSFET_NCH_DUAL","I58": LOCATION = "Q145" #&CDS_LOCATION = "Q145" &SEC = "2" #&CDS_SEC = "2";
"D2":   PN = "3"  !CDS_PN = "3";
"G2":   PN = "5"  !CDS_PN = "5";
"S2":   PN = "4"  !CDS_PN = "4";
BODY = "Q_RES","I59": LOCATION = "R4554" #&CDS_LOCATION = "R4554" &SEC = "1" #&CDS_SEC = "1";
"A":   PN = "1"  !CDS_PN = "1";
"B":   PN = "2"  !CDS_PN = "2";
BODY = "Q_CAP","I62": LOCATION = "C2342" #&CDS_LOCATION = "C2342" &SEC = "1" #&CDS_SEC = "1";
"A":   PN = "1"  !CDS_PN = "1";
"B":   PN = "2"  !CDS_PN = "2";
DRAWING = "@s9s_mb_2u_lib.s9s_mb_2u(sch_1):page155";
BODY = "Q_RES","I78": LOCATION = "R2787" #&CDS_LOCATION = "R2787" &SEC = "1" #&CDS_SEC = "1";
"A":   PN = "1"  !CDS_PN = "1";
"B":   PN = "2"  !CDS_PN = "2";
BODY = "Q_RES","I79": LOCATION = "R2786" #&CDS_LOCATION = "R2786" &SEC = "1" #&CDS_SEC = "1";
"A":   PN = "1"  !CDS_PN = "1";
"B":   PN = "2"  !CDS_PN = "2";
BODY = "Q_CAP","I81": LOCATION = "C5232" #&CDS_LOCATION = "C5232" &SEC = "1" #&CDS_SEC = "1";
"A":   PN = "1"  !CDS_PN = "1";
"B":   PN = "2"  !CDS_PN = "2";
BODY = "Q_RES","I83": LOCATION = "R5238" #&CDS_LOCATION = "R5238" &SEC = "1" #&CDS_SEC = "1";
"A":   PN = "1"  !CDS_PN = "1";
"B":   PN = "2"  !CDS_PN = "2";
BODY = "TUSB211IRWBR","I84": LOCATION = "U5201" #&CDS_LOCATION = "U5201" &SEC = "1" #&CDS_SEC = "1";
"CD":   PN = "4"  !CDS_PN = "4";
"D1M":   PN = "1"  !CDS_PN = "1";
"D1P":   PN = "2"  !CDS_PN = "2";
"D2M":   PN = "8"  !CDS_PN = "8";
"D2P":   PN = "7"  !CDS_PN = "7";
"ENA_HS":   PN = "9"  !CDS_PN = "9";
"EQ":   PN = "6"  !CDS_PN = "6";
"GND":   PN = "10"  !CDS_PN = "10";
"RSTN":   PN = "5"  !CDS_PN = "5";
"TEST":   PN = "3"  !CDS_PN = "3";
"VCC":   PN = "12"  !CDS_PN = "12";
"VREG":   PN = "11"  !CDS_PN = "11";
BODY = "Q_CAP","I87": LOCATION = "C5236" #&CDS_LOCATION = "C5236" &SEC = "1" #&CDS_SEC = "1";
"A":   PN = "1"  !CDS_PN = "1";
"B":   PN = "2"  !CDS_PN = "2";
BODY = "Q_CAP","I88": LOCATION = "C5229" #&CDS_LOCATION = "C5229" &SEC = "1" #&CDS_SEC = "1";
"A":   PN = "1"  !CDS_PN = "1";
"B":   PN = "2"  !CDS_PN = "2";
BODY = "Q_RES","I90": LOCATION = "R5236" #&CDS_LOCATION = "R5236" &SEC = "1" #&CDS_SEC = "1";
"A":   PN = "1"  !CDS_PN = "1";
"B":   PN = "2"  !CDS_PN = "2";
BODY = "Q_RES","I91": LOCATION = "R5234" #&CDS_LOCATION = "R5234" &SEC = "1" #&CDS_SEC = "1";
"A":   PN = "1"  !CDS_PN = "1";
"B":   PN = "2"  !CDS_PN = "2";
BODY = "Q_CAP","I92": LOCATION = "C5234" #&CDS_LOCATION = "C5234" &SEC = "1" #&CDS_SEC = "1";
"A":   PN = "1"  !CDS_PN = "1";
"B":   PN = "2"  !CDS_PN = "2";
BODY = "Q_RES","I96": LOCATION = "R2790" #&CDS_LOCATION = "R2790" &SEC = "1" #&CDS_SEC = "1";
"A":   PN = "1"  !CDS_PN = "1";
"B":   PN = "2"  !CDS_PN = "2";
BODY = "Q_RES","I97": LOCATION = "R2791" #&CDS_LOCATION = "R2791" &SEC = "1" #&CDS_SEC = "1";
"A":   PN = "1"  !CDS_PN = "1";
"B":   PN = "2"  !CDS_PN = "2";
BODY = "Q_RES","I98": LOCATION = "R2789" #&CDS_LOCATION = "R2789" &SEC = "1" #&CDS_SEC = "1";
"A":   PN = "1"  !CDS_PN = "1";
"B":   PN = "2"  !CDS_PN = "2";
BODY = "Q_RES","I99": LOCATION = "R2788" #&CDS_LOCATION = "R2788" &SEC = "1" #&CDS_SEC = "1";
"A":   PN = "1"  !CDS_PN = "1";
"B":   PN = "2"  !CDS_PN = "2";
BODY = "GL852GOHY60","I100": LOCATION = "U268" #&CDS_LOCATION = "U268" &SEC = "1" #&CDS_SEC = "1";
"AVDD<0>":   PN = "5"  !CDS_PN = "5";
"AVDD<1>":   PN = "9"  !CDS_PN = "9";
"AVDD<2>":   PN = "14"  !CDS_PN = "14";
"DM0":   PN = "1"  !CDS_PN = "1";
"DM1":   PN = "3"  !CDS_PN = "3";
"DM2":   PN = "6"  !CDS_PN = "6";
"DM3":   PN = "12"  !CDS_PN = "12";
"DM4":   PN = "15"  !CDS_PN = "15";
"DP0":   PN = "2"  !CDS_PN = "2";
"DP1":   PN = "4"  !CDS_PN = "4";
"DP2":   PN = "7"  !CDS_PN = "7";
"DP3":   PN = "13"  !CDS_PN = "13";
"DP4":   PN = "16"  !CDS_PN = "16";
"DVDD":   PN = "21"  !CDS_PN = "21";
"OVCUR1#||SMC":   PN = "25"  !CDS_PN = "25";
"OVCUR2#||SMD":   PN = "24"  !CDS_PN = "24";
"OVCUR3#":   PN = "20"  !CDS_PN = "20";
"OVCUR4#":   PN = "19"  !CDS_PN = "19";
"PGANG":   PN = "23"  !CDS_PN = "23";
"PSELF":   PN = "22"  !CDS_PN = "22";
"RESET#":   PN = "17"  !CDS_PN = "17";
"RREF":   PN = "8"  !CDS_PN = "8";
"SDA":   PN = "26"  !CDS_PN = "26";
"TEST||SCL":   PN = "18"  !CDS_PN = "18";
"TH":   PN = "TH"  !CDS_PN = "TH";
"V5":   PN = "27"  !CDS_PN = "27";
"V33":   PN = "28"  !CDS_PN = "28";
"X1":   PN = "10"  !CDS_PN = "10";
"X2":   PN = "11"  !CDS_PN = "11";
BODY = "Q_RES","I137": LOCATION = "R3652" #&CDS_LOCATION = "R3652" &SEC = "1" #&CDS_SEC = "1";
"A":   PN = "1"  !CDS_PN = "1";
"B":   PN = "2"  !CDS_PN = "2";
BODY = "Q_RES","I138": LOCATION = "R3651" #&CDS_LOCATION = "R3651" &SEC = "1" #&CDS_SEC = "1";
"A":   PN = "1"  !CDS_PN = "1";
"B":   PN = "2"  !CDS_PN = "2";
BODY = "Q_RES","I139": LOCATION = "R3653" #&CDS_LOCATION = "R3653" &SEC = "1" #&CDS_SEC = "1";
"A":   PN = "1"  !CDS_PN = "1";
"B":   PN = "2"  !CDS_PN = "2";
BODY = "Q_CAP","I142": LOCATION = "C2034" #&CDS_LOCATION = "C2034" &SEC = "1" #&CDS_SEC = "1";
"A":   PN = "1"  !CDS_PN = "1";
"B":   PN = "2"  !CDS_PN = "2";
BODY = "Q_CAP","I143": LOCATION = "C2033" #&CDS_LOCATION = "C2033" &SEC = "1" #&CDS_SEC = "1";
"A":   PN = "1"  !CDS_PN = "1";
"B":   PN = "2"  !CDS_PN = "2";
BODY = "Q_CAP","I145": LOCATION = "C2032" #&CDS_LOCATION = "C2032" &SEC = "1" #&CDS_SEC = "1";
"A":   PN = "1"  !CDS_PN = "1";
"B":   PN = "2"  !CDS_PN = "2";
BODY = "Q_CAP","I147": LOCATION = "C2035" #&CDS_LOCATION = "C2035" &SEC = "1" #&CDS_SEC = "1";
"A":   PN = "1"  !CDS_PN = "1";
"B":   PN = "2"  !CDS_PN = "2";
BODY = "Q_CAP","I148": LOCATION = "C2031" #&CDS_LOCATION = "C2031" &SEC = "1" #&CDS_SEC = "1";
"A":   PN = "1"  !CDS_PN = "1";
"B":   PN = "2"  !CDS_PN = "2";
BODY = "Q_RES","I155": LOCATION = "R3654" #&CDS_LOCATION = "R3654" &SEC = "1" #&CDS_SEC = "1";
"A":   PN = "1"  !CDS_PN = "1";
"B":   PN = "2"  !CDS_PN = "2";
BODY = "Q_CAP","I158": LOCATION = "C2041" #&CDS_LOCATION = "C2041" &SEC = "1" #&CDS_SEC = "1";
"A":   PN = "1"  !CDS_PN = "1";
"B":   PN = "2"  !CDS_PN = "2";
BODY = "Q_RES","I159": LOCATION = "R3660" #&CDS_LOCATION = "R3660" &SEC = "1" #&CDS_SEC = "1";
"A":   PN = "1"  !CDS_PN = "1";
"B":   PN = "2"  !CDS_PN = "2";
BODY = "Q_RES","I161": LOCATION = "R3655" #&CDS_LOCATION = "R3655" &SEC = "1" #&CDS_SEC = "1";
"A":   PN = "1"  !CDS_PN = "1";
"B":   PN = "2"  !CDS_PN = "2";
BODY = "Q_CAP","I162": LOCATION = "C2040" #&CDS_LOCATION = "C2040" &SEC = "1" #&CDS_SEC = "1";
"A":   PN = "1"  !CDS_PN = "1";
"B":   PN = "2"  !CDS_PN = "2";
BODY = "Q_CAP","I163": LOCATION = "C2039" #&CDS_LOCATION = "C2039" &SEC = "1" #&CDS_SEC = "1";
"A":   PN = "1"  !CDS_PN = "1";
"B":   PN = "2"  !CDS_PN = "2";
BODY = "Q_CAP","I164": LOCATION = "C2038" #&CDS_LOCATION = "C2038" &SEC = "1" #&CDS_SEC = "1";
"A":   PN = "1"  !CDS_PN = "1";
"B":   PN = "2"  !CDS_PN = "2";
BODY = "Q_RES","I167": LOCATION = "R3662" #&CDS_LOCATION = "R3662" &SEC = "1" #&CDS_SEC = "1";
"A":   PN = "1"  !CDS_PN = "1";
"B":   PN = "2"  !CDS_PN = "2";
BODY = "Q_RES","I182": LOCATION = "R3665" #&CDS_LOCATION = "R3665" &SEC = "1" #&CDS_SEC = "1";
"A":   PN = "1"  !CDS_PN = "1";
"B":   PN = "2"  !CDS_PN = "2";
BODY = "Q_RES","I186": LOCATION = "R3663" #&CDS_LOCATION = "R3663" &SEC = "1" #&CDS_SEC = "1";
"A":   PN = "1"  !CDS_PN = "1";
"B":   PN = "2"  !CDS_PN = "2";
BODY = "Q_RES","I187": LOCATION = "R3664" #&CDS_LOCATION = "R3664" &SEC = "1" #&CDS_SEC = "1";
"A":   PN = "1"  !CDS_PN = "1";
"B":   PN = "2"  !CDS_PN = "2";
BODY = "Q_RES","I194": LOCATION = "R3656" #&CDS_LOCATION = "R3656" &SEC = "1" #&CDS_SEC = "1";
"A":   PN = "1"  !CDS_PN = "1";
"B":   PN = "2"  !CDS_PN = "2";
BODY = "Q_RES","I195": LOCATION = "R3657" #&CDS_LOCATION = "R3657" &SEC = "1" #&CDS_SEC = "1";
"A":   PN = "1"  !CDS_PN = "1";
"B":   PN = "2"  !CDS_PN = "2";
BODY = "Q_RES","I196": LOCATION = "R3658" #&CDS_LOCATION = "R3658" &SEC = "1" #&CDS_SEC = "1";
"A":   PN = "1"  !CDS_PN = "1";
"B":   PN = "2"  !CDS_PN = "2";
BODY = "Q_RES","I198": LOCATION = "R3659" #&CDS_LOCATION = "R3659" &SEC = "1" #&CDS_SEC = "1";
"A":   PN = "1"  !CDS_PN = "1";
"B":   PN = "2"  !CDS_PN = "2";
BODY = "Q_RES","I199": LOCATION = "R3666" #&CDS_LOCATION = "R3666" &SEC = "1" #&CDS_SEC = "1";
"A":   PN = "1"  !CDS_PN = "1";
"B":   PN = "2"  !CDS_PN = "2";
BODY = "Q_XTAL_4P_13BI_24GND","I200": #LOCATION = "Y4" !CDS_LOCATION = "Y4" &SEC = "1" #&CDS_SEC = "1";
"G1":   PN = "2"  !CDS_PN = "2";
"G2":   PN = "4"  !CDS_PN = "4";
"X1":   PN = "1"  !CDS_PN = "1";
"X2":   PN = "3"  !CDS_PN = "3";
BODY = "Q_RES","I201": #LOCATION = "R3661" !CDS_LOCATION = "R3661" &SEC = "1" #&CDS_SEC = "1";
"A":   PN = "1"  !CDS_PN = "1";
"B":   PN = "2"  !CDS_PN = "2";
BODY = "Q_RES","I202": LOCATION = "R4420" #&CDS_LOCATION = "R4420" &SEC = "1" #&CDS_SEC = "1";
"A":   PN = "1"  !CDS_PN = "1";
"B":   PN = "2"  !CDS_PN = "2";
BODY = "Q_RES","I203": LOCATION = "R4419" #&CDS_LOCATION = "R4419" &SEC = "1" #&CDS_SEC = "1";
"A":   PN = "1"  !CDS_PN = "1";
"B":   PN = "2"  !CDS_PN = "2";
BODY = "Q_RES","I208": LOCATION = "R4482" #&CDS_LOCATION = "R4482" &SEC = "1" #&CDS_SEC = "1";
"A":   PN = "1"  !CDS_PN = "1";
"B":   PN = "2"  !CDS_PN = "2";
BODY = "Q_RES","I206": LOCATION = "R4483" #&CDS_LOCATION = "R4483" &SEC = "1" #&CDS_SEC = "1";
"A":   PN = "1"  !CDS_PN = "1";
"B":   PN = "2"  !CDS_PN = "2";
BODY = "Q_CAP","I210": #LOCATION = "C2029" !CDS_LOCATION = "C2029" &SEC = "1" #&CDS_SEC = "1";
"A":   PN = "1"  !CDS_PN = "1";
"B":   PN = "2"  !CDS_PN = "2";
BODY = "Q_CAP","I211": #LOCATION = "C2030" !CDS_LOCATION = "C2030" &SEC = "1" #&CDS_SEC = "1";
"A":   PN = "1"  !CDS_PN = "1";
"B":   PN = "2"  !CDS_PN = "2";
DRAWING = "@s9s_mb_2u_lib.s9s_mb_2u(sch_1):page301";
BODY = "Q_CAP","I2": #LOCATION = "PC2183" !CDS_LOCATION = "PC2183" &SEC = "1" #&CDS_SEC = "1";
"A":   PN = "1"  !CDS_PN = "1";
"B":   PN = "2"  !CDS_PN = "2";
BODY = "Q_RES","I12": #LOCATION = "PR3915" !CDS_LOCATION = "PR3915" &SEC = "1" #&CDS_SEC = "1";
"A":   PN = "1"  !CDS_PN = "1";
"B":   PN = "2"  !CDS_PN = "2";
BODY = "Q_RES","I13": LOCATION = "PR1101" #&CDS_LOCATION = "PR1101" &SEC = "1" #&CDS_SEC = "1";
"A":   PN = "1"  !CDS_PN = "1";
"B":   PN = "2"  !CDS_PN = "2";
BODY = "Q_CAP","I29": #LOCATION = "PC2347" !CDS_LOCATION = "PC2347" &SEC = "1" #&CDS_SEC = "1";
"A":   PN = "1"  !CDS_PN = "1";
"B":   PN = "2"  !CDS_PN = "2";
BODY = "Q_CAP","I4": #LOCATION = "PC2181" !CDS_LOCATION = "PC2181" &SEC = "1" #&CDS_SEC = "1";
"A":   PN = "1"  !CDS_PN = "1";
"B":   PN = "2"  !CDS_PN = "2";
BODY = "Q_CAP","I20": #LOCATION = "PC1525" !CDS_LOCATION = "PC1525" &SEC = "1" #&CDS_SEC = "1";
"A":   PN = "1"  !CDS_PN = "1";
"B":   PN = "2"  !CDS_PN = "2";
BODY = "Q_RES","I33": #LOCATION = "PR3916" !CDS_LOCATION = "PR3916" &SEC = "1" #&CDS_SEC = "1";
"A":   PN = "1"  !CDS_PN = "1";
"B":   PN = "2"  !CDS_PN = "2";
BODY = "Q_RES","I5": #LOCATION = "PR3911" !CDS_LOCATION = "PR3911" &SEC = "1" #&CDS_SEC = "1";
"A":   PN = "1"  !CDS_PN = "1";
"B":   PN = "2"  !CDS_PN = "2";
BODY = "Q_CAP","I11": #LOCATION = "PC2348" !CDS_LOCATION = "PC2348" &SEC = "1" #&CDS_SEC = "1";
"A":   PN = "1"  !CDS_PN = "1";
"B":   PN = "2"  !CDS_PN = "2";
BODY = "Q_RES","I34": #LOCATION = "PR3918" !CDS_LOCATION = "PR3918" &SEC = "1" #&CDS_SEC = "1";
"A":   PN = "1"  !CDS_PN = "1";
"B":   PN = "2"  !CDS_PN = "2";
BODY = "Q_RES","I39": #LOCATION = "PR3921" !CDS_LOCATION = "PR3921" &SEC = "1" #&CDS_SEC = "1";
"A":   PN = "1"  !CDS_PN = "1";
"B":   PN = "2"  !CDS_PN = "2";
BODY = "Q_RES","I49": #LOCATION = "PR3919" !CDS_LOCATION = "PR3919" &SEC = "1" #&CDS_SEC = "1";
"A":   PN = "1"  !CDS_PN = "1";
"B":   PN = "2"  !CDS_PN = "2";
BODY = "Q_RES","I15": #LOCATION = "PR3912" !CDS_LOCATION = "PR3912" &SEC = "1" #&CDS_SEC = "1";
"A":   PN = "1"  !CDS_PN = "1";
"B":   PN = "2"  !CDS_PN = "2";
BODY = "Q_RES","I21": #LOCATION = "PR3910" !CDS_LOCATION = "PR3910" &SEC = "1" #&CDS_SEC = "1";
"A":   PN = "1"  !CDS_PN = "1";
"B":   PN = "2"  !CDS_PN = "2";
BODY = "Q_RES","I17": #LOCATION = "PR3917" !CDS_LOCATION = "PR3917" &SEC = "1" #&CDS_SEC = "1";
"A":   PN = "1"  !CDS_PN = "1";
"B":   PN = "2"  !CDS_PN = "2";
BODY = "Q_RES","I30": #LOCATION = "PR3914" !CDS_LOCATION = "PR3914" &SEC = "1" #&CDS_SEC = "1";
"A":   PN = "1"  !CDS_PN = "1";
"B":   PN = "2"  !CDS_PN = "2";
BODY = "MP5991GLUZ","I35": #LOCATION = "PU287" !CDS_LOCATION = "PU287" #SEC = "1" !CDS_SEC = "1";
"CS":   PN = "23"  !CDS_PN = "23";
"D_OC":   PN = "3"  !CDS_PN = "3";
"FLT_TYPE":   PN = "6"  !CDS_PN = "6";
"GND":   PN = "20"  !CDS_PN = "20";
"GOK":   PN = "5"  !CDS_PN = "5";
"IMON":   PN = "22"  !CDS_PN = "22";
"MODE":   PN = "8"  !CDS_PN = "8";
"NC1":   PN = "7"  !CDS_PN = "7";
"OCREF":   PN = "24"  !CDS_PN = "24";
"ON":   PN = "4"  !CDS_PN = "4";
"SCREF_OCWREF":   PN = "17"  !CDS_PN = "17";
"SS":   PN = "19"  !CDS_PN = "19";
"VDD33":   PN = "21"  !CDS_PN = "21";
"VIN1":   PN = "9"  !CDS_PN = "9";
"VIN2":   PN = "10"  !CDS_PN = "10";
"VIN3":   PN = "11"  !CDS_PN = "11";
"VIN4":   PN = "12"  !CDS_PN = "12";
"VIN5":   PN = "13"  !CDS_PN = "13";
"VIN6":   PN = "14"  !CDS_PN = "14";
"VIN7":   PN = "15"  !CDS_PN = "15";
"VIN8":   PN = "16"  !CDS_PN = "16";
"VIN9":   PN = "33"  !CDS_PN = "33";
"VOUT1":   PN = "1"  !CDS_PN = "1";
"VOUT2":   PN = "2"  !CDS_PN = "2";
"VOUT3":   PN = "25"  !CDS_PN = "25";
"VOUT4":   PN = "26"  !CDS_PN = "26";
"VOUT5":   PN = "27"  !CDS_PN = "27";
"VOUT6":   PN = "28"  !CDS_PN = "28";
"VOUT7":   PN = "29"  !CDS_PN = "29";
"VOUT8":   PN = "30"  !CDS_PN = "30";
"VOUT9":   PN = "31"  !CDS_PN = "31";
"VOUT10":   PN = "32"  !CDS_PN = "32";
"VTEMP":   PN = "18"  !CDS_PN = "18";
BODY = "Q_RES","I40": #LOCATION = "PR3922" !CDS_LOCATION = "PR3922" &SEC = "1" #&CDS_SEC = "1";
"A":   PN = "1"  !CDS_PN = "1";
"B":   PN = "2"  !CDS_PN = "2";
BODY = "Q_RES","I50": #LOCATION = "PR3920" !CDS_LOCATION = "PR3920" &SEC = "1" #&CDS_SEC = "1";
"A":   PN = "1"  !CDS_PN = "1";
"B":   PN = "2"  !CDS_PN = "2";
BODY = "MP5991GLUZ","I14": #LOCATION = "PU288" !CDS_LOCATION = "PU288" #SEC = "1" !CDS_SEC = "1";
"CS":   PN = "23"  !CDS_PN = "23";
"D_OC":   PN = "3"  !CDS_PN = "3";
"FLT_TYPE":   PN = "6"  !CDS_PN = "6";
"GND":   PN = "20"  !CDS_PN = "20";
"GOK":   PN = "5"  !CDS_PN = "5";
"IMON":   PN = "22"  !CDS_PN = "22";
"MODE":   PN = "8"  !CDS_PN = "8";
"NC1":   PN = "7"  !CDS_PN = "7";
"OCREF":   PN = "24"  !CDS_PN = "24";
"ON":   PN = "4"  !CDS_PN = "4";
"SCREF_OCWREF":   PN = "17"  !CDS_PN = "17";
"SS":   PN = "19"  !CDS_PN = "19";
"VDD33":   PN = "21"  !CDS_PN = "21";
"VIN1":   PN = "9"  !CDS_PN = "9";
"VIN2":   PN = "10"  !CDS_PN = "10";
"VIN3":   PN = "11"  !CDS_PN = "11";
"VIN4":   PN = "12"  !CDS_PN = "12";
"VIN5":   PN = "13"  !CDS_PN = "13";
"VIN6":   PN = "14"  !CDS_PN = "14";
"VIN7":   PN = "15"  !CDS_PN = "15";
"VIN8":   PN = "16"  !CDS_PN = "16";
"VIN9":   PN = "33"  !CDS_PN = "33";
"VOUT1":   PN = "1"  !CDS_PN = "1";
"VOUT2":   PN = "2"  !CDS_PN = "2";
"VOUT3":   PN = "25"  !CDS_PN = "25";
"VOUT4":   PN = "26"  !CDS_PN = "26";
"VOUT5":   PN = "27"  !CDS_PN = "27";
"VOUT6":   PN = "28"  !CDS_PN = "28";
"VOUT7":   PN = "29"  !CDS_PN = "29";
"VOUT8":   PN = "30"  !CDS_PN = "30";
"VOUT9":   PN = "31"  !CDS_PN = "31";
"VOUT10":   PN = "32"  !CDS_PN = "32";
"VTEMP":   PN = "18"  !CDS_PN = "18";
BODY = "Q_RES","I32": LOCATION = "PR1134" #&CDS_LOCATION = "PR1134" &SEC = "1" #&CDS_SEC = "1";
"A":   PN = "1"  !CDS_PN = "1";
"B":   PN = "2"  !CDS_PN = "2";
BODY = "Q_CAP","I23": #LOCATION = "PC2182" !CDS_LOCATION = "PC2182" &SEC = "1" #&CDS_SEC = "1";
"A":   PN = "1"  !CDS_PN = "1";
"B":   PN = "2"  !CDS_PN = "2";
BODY = "Q_CAP","I37": #LOCATION = "PC2185" !CDS_LOCATION = "PC2185" &SEC = "1" #&CDS_SEC = "1";
"A":   PN = "1"  !CDS_PN = "1";
"B":   PN = "2"  !CDS_PN = "2";
BODY = "Q_CAP","I47": #LOCATION = "PC2184" !CDS_LOCATION = "PC2184" &SEC = "1" #&CDS_SEC = "1";
"A":   PN = "1"  !CDS_PN = "1";
"B":   PN = "2"  !CDS_PN = "2";
DRAWING = "@s9s_mb_2u_lib.s9s_mb_2u(sch_1):page215";
BODY = "Q_RES","I2": LOCATION = "R3051" #&CDS_LOCATION = "R3051" &SEC = "1" #&CDS_SEC = "1";
"A":   PN = "1"  !CDS_PN = "1";
"B":   PN = "2"  !CDS_PN = "2";
BODY = "Q_RES","I12": LOCATION = "R3053" #&CDS_LOCATION = "R3053" &SEC = "1" #&CDS_SEC = "1";
"A":   PN = "1"  !CDS_PN = "1";
"B":   PN = "2"  !CDS_PN = "2";
BODY = "Q_RES","I13": LOCATION = "R3052" #&CDS_LOCATION = "R3052" &SEC = "1" #&CDS_SEC = "1";
"A":   PN = "1"  !CDS_PN = "1";
"B":   PN = "2"  !CDS_PN = "2";
BODY = "Q_RES","I23": LOCATION = "R3054" #&CDS_LOCATION = "R3054" &SEC = "1" #&CDS_SEC = "1";
"A":   PN = "1"  !CDS_PN = "1";
"B":   PN = "2"  !CDS_PN = "2";
BODY = "Q_RES","I28": LOCATION = "R3103" #&CDS_LOCATION = "R3103" &SEC = "1" #&CDS_SEC = "1";
"A":   PN = "1"  !CDS_PN = "1";
"B":   PN = "2"  !CDS_PN = "2";
BODY = "SCONN20_513860200CV01","I32": #LOCATION = "J100" !CDS_LOCATION = "J100" &SEC = "1" #&CDS_SEC = "1";
"1":   PN = "1"  !CDS_PN = "1";
"2":   PN = "2"  !CDS_PN = "2";
"3":   PN = "3"  !CDS_PN = "3";
"4":   PN = "4"  !CDS_PN = "4";
"5":   PN = "5"  !CDS_PN = "5";
"6":   PN = "6"  !CDS_PN = "6";
"7":   PN = "7"  !CDS_PN = "7";
"8":   PN = "8"  !CDS_PN = "8";
"9":   PN = "9"  !CDS_PN = "9";
"10":   PN = "10"  !CDS_PN = "10";
"11":   PN = "11"  !CDS_PN = "11";
"12":   PN = "12"  !CDS_PN = "12";
"13":   PN = "13"  !CDS_PN = "13";
"14":   PN = "14"  !CDS_PN = "14";
"15":   PN = "15"  !CDS_PN = "15";
"16":   PN = "16"  !CDS_PN = "16";
"17":   PN = "17"  !CDS_PN = "17";
"18":   PN = "18"  !CDS_PN = "18";
"19":   PN = "19"  !CDS_PN = "19";
"20":   PN = "20"  !CDS_PN = "20";
DRAWING = "@s9s_mb_2u_lib.s9s_mb_2u(sch_1):page305";
BODY = "MOSFET_NCH_DUAL","I2": #LOCATION = "Q80" !CDS_LOCATION = "Q80" #SEC = "2" !CDS_SEC = "2";
"D2":   PN = "3"  !CDS_PN = "3";
"G2":   PN = "5"  !CDS_PN = "5";
"S2":   PN = "4"  !CDS_PN = "4";
BODY = "MOSFET_NCH_DUAL","I4": #LOCATION = "Q80" !CDS_LOCATION = "Q80" &SEC = "1" #&CDS_SEC = "1";
"D1":   PN = "6"  !CDS_PN = "6";
"G1":   PN = "2"  !CDS_PN = "2";
"S1":   PN = "1"  !CDS_PN = "1";
BODY = "MOSFET_NCH_DUAL","I7": #LOCATION = "Q79" !CDS_LOCATION = "Q79" #SEC = "2" !CDS_SEC = "2";
"D2":   PN = "3"  !CDS_PN = "3";
"G2":   PN = "5"  !CDS_PN = "5";
"S2":   PN = "4"  !CDS_PN = "4";
BODY = "MOSFET_NCH_DUAL","I8": #LOCATION = "Q79" !CDS_LOCATION = "Q79" &SEC = "1" #&CDS_SEC = "1";
"D1":   PN = "6"  !CDS_PN = "6";
"G1":   PN = "2"  !CDS_PN = "2";
"S1":   PN = "1"  !CDS_PN = "1";
BODY = "Q_LED","I10": #LOCATION = "D76" !CDS_LOCATION = "D76" &SEC = "1" #&CDS_SEC = "1";
"A":   PN = "A"  !CDS_PN = "A";
"C":   PN = "C"  !CDS_PN = "C";
BODY = "Q_LED","I13": #LOCATION = "D75" !CDS_LOCATION = "D75" &SEC = "1" #&CDS_SEC = "1";
"A":   PN = "A"  !CDS_PN = "A";
"C":   PN = "C"  !CDS_PN = "C";
BODY = "Q_LED","I21": #LOCATION = "D74" !CDS_LOCATION = "D74" &SEC = "1" #&CDS_SEC = "1";
"A":   PN = "A"  !CDS_PN = "A";
"C":   PN = "C"  !CDS_PN = "C";
BODY = "Q_LED","I22": #LOCATION = "D73" !CDS_LOCATION = "D73" &SEC = "1" #&CDS_SEC = "1";
"A":   PN = "A"  !CDS_PN = "A";
"C":   PN = "C"  !CDS_PN = "C";
BODY = "MOSFET_NCH_DUAL","I32": #LOCATION = "Q83" !CDS_LOCATION = "Q83" &SEC = "1" #&CDS_SEC = "1";
"D1":   PN = "6"  !CDS_PN = "6";
"G1":   PN = "2"  !CDS_PN = "2";
"S1":   PN = "1"  !CDS_PN = "1";
BODY = "Q_LED","I35": #LOCATION = "D79" !CDS_LOCATION = "D79" &SEC = "1" #&CDS_SEC = "1";
"A":   PN = "A"  !CDS_PN = "A";
"C":   PN = "C"  !CDS_PN = "C";
BODY = "MOSFET_NCH_DUAL","I40": #LOCATION = "Q81" !CDS_LOCATION = "Q81" #SEC = "2" !CDS_SEC = "2";
"D2":   PN = "3"  !CDS_PN = "3";
"G2":   PN = "5"  !CDS_PN = "5";
"S2":   PN = "4"  !CDS_PN = "4";
BODY = "MOSFET_NCH_DUAL","I41": #LOCATION = "Q81" !CDS_LOCATION = "Q81" &SEC = "1" #&CDS_SEC = "1";
"D1":   PN = "6"  !CDS_PN = "6";
"G1":   PN = "2"  !CDS_PN = "2";
"S1":   PN = "1"  !CDS_PN = "1";
BODY = "Q_LED","I43": #LOCATION = "D78" !CDS_LOCATION = "D78" &SEC = "1" #&CDS_SEC = "1";
"A":   PN = "A"  !CDS_PN = "A";
"C":   PN = "C"  !CDS_PN = "C";
BODY = "Q_LED","I44": #LOCATION = "D77" !CDS_LOCATION = "D77" &SEC = "1" #&CDS_SEC = "1";
"A":   PN = "A"  !CDS_PN = "A";
"C":   PN = "C"  !CDS_PN = "C";
BODY = "Q_RES","I49": LOCATION = "R3086" #&CDS_LOCATION = "R3086" &SEC = "1" #&CDS_SEC = "1";
"A":   PN = "1"  !CDS_PN = "1";
"B":   PN = "2"  !CDS_PN = "2";
BODY = "Q_RES","I50": LOCATION = "R3087" #&CDS_LOCATION = "R3087" &SEC = "1" #&CDS_SEC = "1";
"A":   PN = "1"  !CDS_PN = "1";
"B":   PN = "2"  !CDS_PN = "2";
BODY = "Q_RES","I51": LOCATION = "R3089" #&CDS_LOCATION = "R3089" &SEC = "1" #&CDS_SEC = "1";
"A":   PN = "1"  !CDS_PN = "1";
"B":   PN = "2"  !CDS_PN = "2";
BODY = "Q_RES","I52": LOCATION = "R3088" #&CDS_LOCATION = "R3088" &SEC = "1" #&CDS_SEC = "1";
"A":   PN = "1"  !CDS_PN = "1";
"B":   PN = "2"  !CDS_PN = "2";
BODY = "Q_RES","I53": LOCATION = "R3091" #&CDS_LOCATION = "R3091" &SEC = "1" #&CDS_SEC = "1";
"A":   PN = "1"  !CDS_PN = "1";
"B":   PN = "2"  !CDS_PN = "2";
BODY = "Q_RES","I54": LOCATION = "R3090" #&CDS_LOCATION = "R3090" &SEC = "1" #&CDS_SEC = "1";
"A":   PN = "1"  !CDS_PN = "1";
"B":   PN = "2"  !CDS_PN = "2";
BODY = "Q_RES","I55": LOCATION = "R3092" #&CDS_LOCATION = "R3092" &SEC = "1" #&CDS_SEC = "1";
"A":   PN = "1"  !CDS_PN = "1";
"B":   PN = "2"  !CDS_PN = "2";
DRAWING = "@s9s_mb_2u_lib.s9s_mb_2u(sch_1):page241";
BODY = "MOSFET_NCH_DUAL","I8": #LOCATION = "Q88" !CDS_LOCATION = "Q88" &SEC = "1" #&CDS_SEC = "1";
"D1":   PN = "6"  !CDS_PN = "6";
"G1":   PN = "2"  !CDS_PN = "2";
"S1":   PN = "1"  !CDS_PN = "1";
BODY = "Q_LED","I11": #LOCATION = "D89" !CDS_LOCATION = "D89" &SEC = "1" #&CDS_SEC = "1";
"A":   PN = "A"  !CDS_PN = "A";
"C":   PN = "C"  !CDS_PN = "C";
BODY = "MOSFET_NCH_DUAL","I16": #LOCATION = "Q87" !CDS_LOCATION = "Q87" #SEC = "2" !CDS_SEC = "2";
"D2":   PN = "3"  !CDS_PN = "3";
"G2":   PN = "5"  !CDS_PN = "5";
"S2":   PN = "4"  !CDS_PN = "4";
BODY = "MOSFET_NCH_DUAL","I17": #LOCATION = "Q87" !CDS_LOCATION = "Q87" &SEC = "1" #&CDS_SEC = "1";
"D1":   PN = "6"  !CDS_PN = "6";
"G1":   PN = "2"  !CDS_PN = "2";
"S1":   PN = "1"  !CDS_PN = "1";
BODY = "Q_LED","I19": #LOCATION = "D88" !CDS_LOCATION = "D88" &SEC = "1" #&CDS_SEC = "1";
"A":   PN = "A"  !CDS_PN = "A";
"C":   PN = "C"  !CDS_PN = "C";
BODY = "Q_LED","I20": #LOCATION = "D87" !CDS_LOCATION = "D87" &SEC = "1" #&CDS_SEC = "1";
"A":   PN = "A"  !CDS_PN = "A";
"C":   PN = "C"  !CDS_PN = "C";
BODY = "Q_LED","I33": #LOCATION = "D90" !CDS_LOCATION = "D90" &SEC = "1" #&CDS_SEC = "1";
"A":   PN = "A"  !CDS_PN = "A";
"C":   PN = "C"  !CDS_PN = "C";
BODY = "Q_RES","I38": LOCATION = "R3068" #&CDS_LOCATION = "R3068" &SEC = "1" #&CDS_SEC = "1";
"A":   PN = "1"  !CDS_PN = "1";
"B":   PN = "2"  !CDS_PN = "2";
BODY = "Q_RES","I39": LOCATION = "R3069" #&CDS_LOCATION = "R3069" &SEC = "1" #&CDS_SEC = "1";
"A":   PN = "1"  !CDS_PN = "1";
"B":   PN = "2"  !CDS_PN = "2";
BODY = "Q_RES","I40": LOCATION = "R1044" #&CDS_LOCATION = "R1044" &SEC = "1" #&CDS_SEC = "1";
"A":   PN = "1"  !CDS_PN = "1";
"B":   PN = "2"  !CDS_PN = "2";
BODY = "Q_RES","I41": LOCATION = "R3070" #&CDS_LOCATION = "R3070" &SEC = "1" #&CDS_SEC = "1";
"A":   PN = "1"  !CDS_PN = "1";
"B":   PN = "2"  !CDS_PN = "2";
BODY = "MOSFET_NCH_DUAL","I42": #LOCATION = "Q88" !CDS_LOCATION = "Q88" &SEC = "2" #&CDS_SEC = "2";
"D2":   PN = "3"  !CDS_PN = "3";
"G2":   PN = "5"  !CDS_PN = "5";
"S2":   PN = "4"  !CDS_PN = "4";
BODY = "Q_LED","I49": LOCATION = "D143" #&CDS_LOCATION = "D143" &SEC = "1" #&CDS_SEC = "1";
"A":   PN = "A"  !CDS_PN = "A";
"C":   PN = "C"  !CDS_PN = "C";
BODY = "Q_LED","I58": LOCATION = "D142" #&CDS_LOCATION = "D142" &SEC = "1" #&CDS_SEC = "1";
"A":   PN = "A"  !CDS_PN = "A";
"C":   PN = "C"  !CDS_PN = "C";
BODY = "Q_RES","I61": LOCATION = "R4703" #&CDS_LOCATION = "R4703" &SEC = "1" #&CDS_SEC = "1";
"A":   PN = "1"  !CDS_PN = "1";
"B":   PN = "2"  !CDS_PN = "2";
BODY = "Q_RES","I62": LOCATION = "R4705" #&CDS_LOCATION = "R4705" &SEC = "1" #&CDS_SEC = "1";
"A":   PN = "1"  !CDS_PN = "1";
"B":   PN = "2"  !CDS_PN = "2";
BODY = "Q_RES","I63": LOCATION = "R4707" #&CDS_LOCATION = "R4707" &SEC = "1" #&CDS_SEC = "1";
"A":   PN = "1"  !CDS_PN = "1";
"B":   PN = "2"  !CDS_PN = "2";
BODY = "Q_RES","I64": LOCATION = "R4702" #&CDS_LOCATION = "R4702" &SEC = "1" #&CDS_SEC = "1";
"A":   PN = "1"  !CDS_PN = "1";
"B":   PN = "2"  !CDS_PN = "2";
BODY = "Q_RES","I65": LOCATION = "R4704" #&CDS_LOCATION = "R4704" &SEC = "1" #&CDS_SEC = "1";
"A":   PN = "1"  !CDS_PN = "1";
"B":   PN = "2"  !CDS_PN = "2";
BODY = "Q_RES","I66": LOCATION = "R4706" #&CDS_LOCATION = "R4706" &SEC = "1" #&CDS_SEC = "1";
"A":   PN = "1"  !CDS_PN = "1";
"B":   PN = "2"  !CDS_PN = "2";
BODY = "Q_LED","I67": LOCATION = "D144" #&CDS_LOCATION = "D144" &SEC = "1" #&CDS_SEC = "1";
"A":   PN = "A"  !CDS_PN = "A";
"C":   PN = "C"  !CDS_PN = "C";
BODY = "Q_RES","I68": LOCATION = "R4711" #&CDS_LOCATION = "R4711" &SEC = "1" #&CDS_SEC = "1";
"A":   PN = "1"  !CDS_PN = "1";
"B":   PN = "2"  !CDS_PN = "2";
BODY = "MOSFET_NCH_DUAL","I69": LOCATION = "Q150" #&CDS_LOCATION = "Q150" &SEC = "1" #&CDS_SEC = "1";
"D1":   PN = "6"  !CDS_PN = "6";
"G1":   PN = "2"  !CDS_PN = "2";
"S1":   PN = "1"  !CDS_PN = "1";
BODY = "MOSFET_NCH_DUAL","I72": LOCATION = "Q150" #&CDS_LOCATION = "Q150" &SEC = "2" #&CDS_SEC = "2";
"D2":   PN = "3"  !CDS_PN = "3";
"G2":   PN = "5"  !CDS_PN = "5";
"S2":   PN = "4"  !CDS_PN = "4";
BODY = "Q_RES","I74": LOCATION = "R4710" #&CDS_LOCATION = "R4710" &SEC = "1" #&CDS_SEC = "1";
"A":   PN = "1"  !CDS_PN = "1";
"B":   PN = "2"  !CDS_PN = "2";
DRAWING = "@s9s_mb_2u_lib.s9s_mb_2u(sch_1):page304";
BODY = "Q_LED","I9": #LOCATION = "D68" !CDS_LOCATION = "D68" &SEC = "1" #&CDS_SEC = "1";
"A":   PN = "A"  !CDS_PN = "A";
"C":   PN = "C"  !CDS_PN = "C";
BODY = "Q_LED","I12": #LOCATION = "D67" !CDS_LOCATION = "D67" &SEC = "1" #&CDS_SEC = "1";
"A":   PN = "A"  !CDS_PN = "A";
"C":   PN = "C"  !CDS_PN = "C";
BODY = "Q_LED","I20": #LOCATION = "D66" !CDS_LOCATION = "D66" &SEC = "1" #&CDS_SEC = "1";
"A":   PN = "A"  !CDS_PN = "A";
"C":   PN = "C"  !CDS_PN = "C";
BODY = "Q_LED","I21": #LOCATION = "D65" !CDS_LOCATION = "D65" &SEC = "1" #&CDS_SEC = "1";
"A":   PN = "A"  !CDS_PN = "A";
"C":   PN = "C"  !CDS_PN = "C";
BODY = "Q_LED","I31": #LOCATION = "D70" !CDS_LOCATION = "D70" &SEC = "1" #&CDS_SEC = "1";
"A":   PN = "A"  !CDS_PN = "A";
"C":   PN = "C"  !CDS_PN = "C";
BODY = "Q_LED","I32": #LOCATION = "D69" !CDS_LOCATION = "D69" &SEC = "1" #&CDS_SEC = "1";
"A":   PN = "A"  !CDS_PN = "A";
"C":   PN = "C"  !CDS_PN = "C";
BODY = "Q_RES","I49": #LOCATION = "R1371" !CDS_LOCATION = "R1371" &SEC = "1" #&CDS_SEC = "1";
"A":   PN = "1"  !CDS_PN = "1";
"B":   PN = "2"  !CDS_PN = "2";
BODY = "Q_RES","I50": LOCATION = "R3080" #&CDS_LOCATION = "R3080" &SEC = "1" #&CDS_SEC = "1";
"A":   PN = "1"  !CDS_PN = "1";
"B":   PN = "2"  !CDS_PN = "2";
BODY = "Q_RES","I51": LOCATION = "R3079" #&CDS_LOCATION = "R3079" &SEC = "1" #&CDS_SEC = "1";
"A":   PN = "1"  !CDS_PN = "1";
"B":   PN = "2"  !CDS_PN = "2";
BODY = "Q_RES","I52": LOCATION = "R3081" #&CDS_LOCATION = "R3081" &SEC = "1" #&CDS_SEC = "1";
"A":   PN = "1"  !CDS_PN = "1";
"B":   PN = "2"  !CDS_PN = "2";
BODY = "Q_RES","I53": LOCATION = "R3084" #&CDS_LOCATION = "R3084" &SEC = "1" #&CDS_SEC = "1";
"A":   PN = "1"  !CDS_PN = "1";
"B":   PN = "2"  !CDS_PN = "2";
BODY = "Q_RES","I54": LOCATION = "R3082" #&CDS_LOCATION = "R3082" &SEC = "1" #&CDS_SEC = "1";
"A":   PN = "1"  !CDS_PN = "1";
"B":   PN = "2"  !CDS_PN = "2";
BODY = "Q_RES","I57": LOCATION = "R3083" #&CDS_LOCATION = "R3083" &SEC = "1" #&CDS_SEC = "1";
"A":   PN = "1"  !CDS_PN = "1";
"B":   PN = "2"  !CDS_PN = "2";
BODY = "Q_LED","I58": #LOCATION = "D71" !CDS_LOCATION = "D71" &SEC = "1" #&CDS_SEC = "1";
"A":   PN = "A"  !CDS_PN = "A";
"C":   PN = "C"  !CDS_PN = "C";
BODY = "Q_RES","I62": LOCATION = "R3085" #&CDS_LOCATION = "R3085" &SEC = "1" #&CDS_SEC = "1";
"A":   PN = "1"  !CDS_PN = "1";
"B":   PN = "2"  !CDS_PN = "2";
BODY = "Q_LED","I63": #LOCATION = "D72" !CDS_LOCATION = "D72" &SEC = "1" #&CDS_SEC = "1";
"A":   PN = "A"  !CDS_PN = "A";
"C":   PN = "C"  !CDS_PN = "C";
BODY = "MOSFET_NCH_DUAL","I68": LOCATION = "Q98" #&CDS_LOCATION = "Q98" &SEC = "1" #&CDS_SEC = "1";
"D1":   PN = "6"  !CDS_PN = "6";
"G1":   PN = "2"  !CDS_PN = "2";
"S1":   PN = "1"  !CDS_PN = "1";
BODY = "MOSFET_NCH_DUAL","I69": LOCATION = "Q98" #&CDS_LOCATION = "Q98" &SEC = "2" #&CDS_SEC = "2";
"D2":   PN = "3"  !CDS_PN = "3";
"G2":   PN = "5"  !CDS_PN = "5";
"S2":   PN = "4"  !CDS_PN = "4";
BODY = "MOSFET_NCH_DUAL","I70": LOCATION = "Q97" #&CDS_LOCATION = "Q97" &SEC = "2" #&CDS_SEC = "2";
"D2":   PN = "3"  !CDS_PN = "3";
"G2":   PN = "5"  !CDS_PN = "5";
"S2":   PN = "4"  !CDS_PN = "4";
BODY = "MOSFET_NCH_DUAL","I71": LOCATION = "Q97" #&CDS_LOCATION = "Q97" &SEC = "1" #&CDS_SEC = "1";
"D1":   PN = "6"  !CDS_PN = "6";
"G1":   PN = "2"  !CDS_PN = "2";
"S1":   PN = "1"  !CDS_PN = "1";
BODY = "MOSFET_NCH_DUAL","I72": LOCATION = "Q99" #&CDS_LOCATION = "Q99" &SEC = "1" #&CDS_SEC = "1";
"D1":   PN = "6"  !CDS_PN = "6";
"G1":   PN = "2"  !CDS_PN = "2";
"S1":   PN = "1"  !CDS_PN = "1";
BODY = "MOSFET_NCH_DUAL","I74": LOCATION = "Q100" #&CDS_LOCATION = "Q100" &SEC = "1" #&CDS_SEC = "1";
"D1":   PN = "6"  !CDS_PN = "6";
"G1":   PN = "2"  !CDS_PN = "2";
"S1":   PN = "1"  !CDS_PN = "1";
BODY = "MOSFET_NCH_DUAL","I75": LOCATION = "Q100" #&CDS_LOCATION = "Q100" &SEC = "2" #&CDS_SEC = "2";
"D2":   PN = "3"  !CDS_PN = "3";
"G2":   PN = "5"  !CDS_PN = "5";
"S2":   PN = "4"  !CDS_PN = "4";
BODY = "MOSFET_NCH_DUAL","I76": LOCATION = "Q105" #&CDS_LOCATION = "Q105" &SEC = "1" #&CDS_SEC = "1";
"D1":   PN = "6"  !CDS_PN = "6";
"G1":   PN = "2"  !CDS_PN = "2";
"S1":   PN = "1"  !CDS_PN = "1";
DRAWING = "@s9s_mb_2u_lib.s9s_mb_2u(sch_1):page242";
BODY = "MOSFET_NCH_DUAL","I8": #LOCATION = "Q76" !CDS_LOCATION = "Q76" #SEC = "2" !CDS_SEC = "2";
"D2":   PN = "3"  !CDS_PN = "3";
"G2":   PN = "5"  !CDS_PN = "5";
"S2":   PN = "4"  !CDS_PN = "4";
BODY = "MOSFET_NCH_DUAL","I3": #LOCATION = "Q77" !CDS_LOCATION = "Q77" #SEC = "2" !CDS_SEC = "2";
"D2":   PN = "3"  !CDS_PN = "3";
"G2":   PN = "5"  !CDS_PN = "5";
"S2":   PN = "4"  !CDS_PN = "4";
BODY = "MOSFET_NCH_DUAL","I6": #LOCATION = "Q77" !CDS_LOCATION = "Q77" &SEC = "1" #&CDS_SEC = "1";
"D1":   PN = "6"  !CDS_PN = "6";
"G1":   PN = "2"  !CDS_PN = "2";
"S1":   PN = "1"  !CDS_PN = "1";
BODY = "Q_LED","I11": #LOCATION = "D94" !CDS_LOCATION = "D94" &SEC = "1" #&CDS_SEC = "1";
"A":   PN = "A"  !CDS_PN = "A";
"C":   PN = "C"  !CDS_PN = "C";
BODY = "Q_RES","I12": LOCATION = "R3073" #&CDS_LOCATION = "R3073" &SEC = "1" #&CDS_SEC = "1";
"A":   PN = "1"  !CDS_PN = "1";
"B":   PN = "2"  !CDS_PN = "2";
BODY = "Q_LED","I13": #LOCATION = "D93" !CDS_LOCATION = "D93" &SEC = "1" #&CDS_SEC = "1";
"A":   PN = "A"  !CDS_PN = "A";
"C":   PN = "C"  !CDS_PN = "C";
BODY = "Q_RES","I14": LOCATION = "R3074" #&CDS_LOCATION = "R3074" &SEC = "1" #&CDS_SEC = "1";
"A":   PN = "1"  !CDS_PN = "1";
"B":   PN = "2"  !CDS_PN = "2";
BODY = "Q_RES","I15": LOCATION = "R3072" #&CDS_LOCATION = "R3072" &SEC = "1" #&CDS_SEC = "1";
"A":   PN = "1"  !CDS_PN = "1";
"B":   PN = "2"  !CDS_PN = "2";
BODY = "MOSFET_NCH_DUAL","I17": #LOCATION = "Q76" !CDS_LOCATION = "Q76" &SEC = "1" #&CDS_SEC = "1";
"D1":   PN = "6"  !CDS_PN = "6";
"G1":   PN = "2"  !CDS_PN = "2";
"S1":   PN = "1"  !CDS_PN = "1";
BODY = "Q_LED","I18": #LOCATION = "D91" !CDS_LOCATION = "D91" &SEC = "1" #&CDS_SEC = "1";
"A":   PN = "A"  !CDS_PN = "A";
"C":   PN = "C"  !CDS_PN = "C";
BODY = "Q_RES","I19": LOCATION = "R3071" #&CDS_LOCATION = "R3071" &SEC = "1" #&CDS_SEC = "1";
"A":   PN = "1"  !CDS_PN = "1";
"B":   PN = "2"  !CDS_PN = "2";
BODY = "MOSFET_NCH_DUAL","I26": #LOCATION = "Q78" !CDS_LOCATION = "Q78" #SEC = "2" !CDS_SEC = "2";
"D2":   PN = "3"  !CDS_PN = "3";
"G2":   PN = "5"  !CDS_PN = "5";
"S2":   PN = "4"  !CDS_PN = "4";
BODY = "Q_LED","I31": #LOCATION = "D96" !CDS_LOCATION = "D96" &SEC = "1" #&CDS_SEC = "1";
"A":   PN = "A"  !CDS_PN = "A";
"C":   PN = "C"  !CDS_PN = "C";
BODY = "MOSFET_NCH_DUAL","I34": #LOCATION = "Q78" !CDS_LOCATION = "Q78" &SEC = "1" #&CDS_SEC = "1";
"D1":   PN = "6"  !CDS_PN = "6";
"G1":   PN = "2"  !CDS_PN = "2";
"S1":   PN = "1"  !CDS_PN = "1";
BODY = "Q_LED","I35": #LOCATION = "D95" !CDS_LOCATION = "D95" &SEC = "1" #&CDS_SEC = "1";
"A":   PN = "A"  !CDS_PN = "A";
"C":   PN = "C"  !CDS_PN = "C";
BODY = "Q_RES","I37": LOCATION = "R3075" #&CDS_LOCATION = "R3075" &SEC = "1" #&CDS_SEC = "1";
"A":   PN = "1"  !CDS_PN = "1";
"B":   PN = "2"  !CDS_PN = "2";
BODY = "Q_RES","I41": LOCATION = "R3078" #&CDS_LOCATION = "R3078" &SEC = "1" #&CDS_SEC = "1";
"A":   PN = "1"  !CDS_PN = "1";
"B":   PN = "2"  !CDS_PN = "2";
BODY = "Q_LED","I42": #LOCATION = "D92" !CDS_LOCATION = "D92" &SEC = "1" #&CDS_SEC = "1";
"A":   PN = "A"  !CDS_PN = "A";
"C":   PN = "C"  !CDS_PN = "C";
BODY = "Q_LED","I52": #LOCATION = "D97" !CDS_LOCATION = "D97" &SEC = "1" #&CDS_SEC = "1";
"A":   PN = "A"  !CDS_PN = "A";
"C":   PN = "C"  !CDS_PN = "C";
BODY = "Q_LED","I53": #LOCATION = "D98" !CDS_LOCATION = "D98" &SEC = "1" #&CDS_SEC = "1";
"A":   PN = "A"  !CDS_PN = "A";
"C":   PN = "C"  !CDS_PN = "C";
BODY = "Q_LED","I60": #LOCATION = "D99" !CDS_LOCATION = "D99" &SEC = "1" #&CDS_SEC = "1";
"A":   PN = "A"  !CDS_PN = "A";
"C":   PN = "C"  !CDS_PN = "C";
BODY = "Q_RES","I61": LOCATION = "R3102" #&CDS_LOCATION = "R3102" &SEC = "1" #&CDS_SEC = "1";
"A":   PN = "1"  !CDS_PN = "1";
"B":   PN = "2"  !CDS_PN = "2";
BODY = "Q_RES","I62": LOCATION = "R3101" #&CDS_LOCATION = "R3101" &SEC = "1" #&CDS_SEC = "1";
"A":   PN = "1"  !CDS_PN = "1";
"B":   PN = "2"  !CDS_PN = "2";
BODY = "Q_RES","I64": #LOCATION = "R3100" !CDS_LOCATION = "R3100" &SEC = "1" #&CDS_SEC = "1";
"A":   PN = "1"  !CDS_PN = "1";
"B":   PN = "2"  !CDS_PN = "2";
DRAWING = "@s9s_mb_2u_lib.s9s_mb_2u(sch_1):page306";
BODY = "MOSFET_NCH_DUAL","I3": #LOCATION = "Q85" !CDS_LOCATION = "Q85" #SEC = "2" !CDS_SEC = "2";
"D2":   PN = "3"  !CDS_PN = "3";
"G2":   PN = "5"  !CDS_PN = "5";
"S2":   PN = "4"  !CDS_PN = "4";
BODY = "MOSFET_NCH_DUAL","I6": #LOCATION = "Q85" !CDS_LOCATION = "Q85" &SEC = "1" #&CDS_SEC = "1";
"D1":   PN = "6"  !CDS_PN = "6";
"G1":   PN = "2"  !CDS_PN = "2";
"S1":   PN = "1"  !CDS_PN = "1";
BODY = "MOSFET_NCH_DUAL","I8": #LOCATION = "Q84" !CDS_LOCATION = "Q84" #SEC = "2" !CDS_SEC = "2";
"D2":   PN = "3"  !CDS_PN = "3";
"G2":   PN = "5"  !CDS_PN = "5";
"S2":   PN = "4"  !CDS_PN = "4";
BODY = "Q_LED","I11": #LOCATION = "D83" !CDS_LOCATION = "D83" &SEC = "1" #&CDS_SEC = "1";
"A":   PN = "A"  !CDS_PN = "A";
"C":   PN = "C"  !CDS_PN = "C";
BODY = "Q_RES","I12": LOCATION = "R3095" #&CDS_LOCATION = "R3095" &SEC = "1" #&CDS_SEC = "1";
"A":   PN = "1"  !CDS_PN = "1";
"B":   PN = "2"  !CDS_PN = "2";
BODY = "Q_LED","I13": #LOCATION = "D82" !CDS_LOCATION = "D82" &SEC = "1" #&CDS_SEC = "1";
"A":   PN = "A"  !CDS_PN = "A";
"C":   PN = "C"  !CDS_PN = "C";
BODY = "Q_LED","I14": #LOCATION = "D81" !CDS_LOCATION = "D81" &SEC = "1" #&CDS_SEC = "1";
"A":   PN = "A"  !CDS_PN = "A";
"C":   PN = "C"  !CDS_PN = "C";
BODY = "Q_RES","I15": LOCATION = "R3096" #&CDS_LOCATION = "R3096" &SEC = "1" #&CDS_SEC = "1";
"A":   PN = "1"  !CDS_PN = "1";
"B":   PN = "2"  !CDS_PN = "2";
BODY = "Q_RES","I16": LOCATION = "R3094" #&CDS_LOCATION = "R3094" &SEC = "1" #&CDS_SEC = "1";
"A":   PN = "1"  !CDS_PN = "1";
"B":   PN = "2"  !CDS_PN = "2";
BODY = "MOSFET_NCH_DUAL","I18": #LOCATION = "Q84" !CDS_LOCATION = "Q84" &SEC = "1" #&CDS_SEC = "1";
"D1":   PN = "6"  !CDS_PN = "6";
"G1":   PN = "2"  !CDS_PN = "2";
"S1":   PN = "1"  !CDS_PN = "1";
BODY = "Q_LED","I19": #LOCATION = "D80" !CDS_LOCATION = "D80" &SEC = "1" #&CDS_SEC = "1";
"A":   PN = "A"  !CDS_PN = "A";
"C":   PN = "C"  !CDS_PN = "C";
BODY = "Q_RES","I20": LOCATION = "R3093" #&CDS_LOCATION = "R3093" &SEC = "1" #&CDS_SEC = "1";
"A":   PN = "1"  !CDS_PN = "1";
"B":   PN = "2"  !CDS_PN = "2";
BODY = "MOSFET_NCH_DUAL","I27": #LOCATION = "Q86" !CDS_LOCATION = "Q86" #SEC = "2" !CDS_SEC = "2";
"D2":   PN = "3"  !CDS_PN = "3";
"G2":   PN = "5"  !CDS_PN = "5";
"S2":   PN = "4"  !CDS_PN = "4";
BODY = "Q_LED","I30": #LOCATION = "D86" !CDS_LOCATION = "D86" &SEC = "1" #&CDS_SEC = "1";
"A":   PN = "A"  !CDS_PN = "A";
"C":   PN = "C"  !CDS_PN = "C";
BODY = "Q_LED","I32": #LOCATION = "D85" !CDS_LOCATION = "D85" &SEC = "1" #&CDS_SEC = "1";
"A":   PN = "A"  !CDS_PN = "A";
"C":   PN = "C"  !CDS_PN = "C";
BODY = "MOSFET_NCH_DUAL","I35": #LOCATION = "Q86" !CDS_LOCATION = "Q86" &SEC = "1" #&CDS_SEC = "1";
"D1":   PN = "6"  !CDS_PN = "6";
"G1":   PN = "2"  !CDS_PN = "2";
"S1":   PN = "1"  !CDS_PN = "1";
BODY = "Q_LED","I36": #LOCATION = "D84" !CDS_LOCATION = "D84" &SEC = "1" #&CDS_SEC = "1";
"A":   PN = "A"  !CDS_PN = "A";
"C":   PN = "C"  !CDS_PN = "C";
BODY = "Q_RES","I37": LOCATION = "R3098" #&CDS_LOCATION = "R3098" &SEC = "1" #&CDS_SEC = "1";
"A":   PN = "1"  !CDS_PN = "1";
"B":   PN = "2"  !CDS_PN = "2";
BODY = "Q_RES","I38": LOCATION = "R3097" #&CDS_LOCATION = "R3097" &SEC = "1" #&CDS_SEC = "1";
"A":   PN = "1"  !CDS_PN = "1";
"B":   PN = "2"  !CDS_PN = "2";
BODY = "Q_RES","I41": LOCATION = "R3099" #&CDS_LOCATION = "R3099" &SEC = "1" #&CDS_SEC = "1";
"A":   PN = "1"  !CDS_PN = "1";
"B":   PN = "2"  !CDS_PN = "2";
BODY = "MOSFET_NCH_DUAL","I43": #LOCATION = "Q83" !CDS_LOCATION = "Q83" &SEC = "2" #&CDS_SEC = "2";
"D2":   PN = "3"  !CDS_PN = "3";
"G2":   PN = "5"  !CDS_PN = "5";
"S2":   PN = "4"  !CDS_PN = "4";
DRAWING = "@s9s_mb_2u_lib.s9s_mb_2u(sch_1):page234";
BODY = "Q_RES","I3": LOCATION = "R2531" #&CDS_LOCATION = "R2531" &SEC = "1" #&CDS_SEC = "1";
"A":   PN = "1"  !CDS_PN = "1";
"B":   PN = "2"  !CDS_PN = "2";
BODY = "MOSFET_NCH_GDS_ESD_PROTECTED","I6": LOCATION = "U158" #&CDS_LOCATION = "U158" &SEC = "1" #&CDS_SEC = "1";
"D":   PN = "D"  !CDS_PN = "D";
"G":   PN = "G"  !CDS_PN = "G";
"S":   PN = "S"  !CDS_PN = "S";
BODY = "Q_RES","I7": LOCATION = "R2529" #&CDS_LOCATION = "R2529" &SEC = "1" #&CDS_SEC = "1";
"A":   PN = "1"  !CDS_PN = "1";
"B":   PN = "2"  !CDS_PN = "2";
BODY = "Q_RES","I8": LOCATION = "R2528" #&CDS_LOCATION = "R2528" &SEC = "1" #&CDS_SEC = "1";
"A":   PN = "1"  !CDS_PN = "1";
"B":   PN = "2"  !CDS_PN = "2";
BODY = "Q_RES","I10": LOCATION = "R2530" #&CDS_LOCATION = "R2530" &SEC = "1" #&CDS_SEC = "1";
"A":   PN = "1"  !CDS_PN = "1";
"B":   PN = "2"  !CDS_PN = "2";
BODY = "MOSFET_NCH_GDS_ESD_PROTECTED","I14": #LOCATION = "Q54" !CDS_LOCATION = "Q54" &SEC = "1" #&CDS_SEC = "1";
"D":   PN = "D"  !CDS_PN = "D";
"G":   PN = "G"  !CDS_PN = "G";
"S":   PN = "S"  !CDS_PN = "S";
DRAWING = "@s9s_mb_2u_lib.s9s_mb_2u(sch_1):page131";
BODY = "Q_CAP","I26": LOCATION = "C1809" #&CDS_LOCATION = "C1809" &SEC = "1" #&CDS_SEC = "1";
"A":   PN = "1"  !CDS_PN = "1";
"B":   PN = "2"  !CDS_PN = "2";
BODY = "MOSFET_NCH_DUAL","I38": LOCATION = "Q119" #&CDS_LOCATION = "Q119" &SEC = "1" #&CDS_SEC = "1";
"D1":   PN = "6"  !CDS_PN = "6";
"G1":   PN = "2"  !CDS_PN = "2";
"S1":   PN = "1"  !CDS_PN = "1";
BODY = "Q_CAP","I87": #LOCATION = "PC2147" !CDS_LOCATION = "PC2147" &SEC = "1" #&CDS_SEC = "1";
"A":   PN = "1"  !CDS_PN = "1";
"B":   PN = "2"  !CDS_PN = "2";
BODY = "Q_RES","I59": #LOCATION = "PR3821" !CDS_LOCATION = "PR3821" &SEC = "1" #&CDS_SEC = "1";
"A":   PN = "1"  !CDS_PN = "1";
"B":   PN = "2"  !CDS_PN = "2";
BODY = "Q_RES","I70": LOCATION = "R4761" #&CDS_LOCATION = "R4761" &SEC = "1" #&CDS_SEC = "1";
"A":   PN = "1"  !CDS_PN = "1";
"B":   PN = "2"  !CDS_PN = "2";
BODY = "Q_RES","I85": #LOCATION = "PR3830" !CDS_LOCATION = "PR3830" &SEC = "1" #&CDS_SEC = "1";
"A":   PN = "1"  !CDS_PN = "1";
"B":   PN = "2"  !CDS_PN = "2";
BODY = "Q_RES","I97": #LOCATION = "R3832" !CDS_LOCATION = "R3832" &SEC = "1" #&CDS_SEC = "1";
"A":   PN = "1"  !CDS_PN = "1";
"B":   PN = "2"  !CDS_PN = "2";
BODY = "Q_RES","I33": #LOCATION = "PR3805" !CDS_LOCATION = "PR3805" &SEC = "1" #&CDS_SEC = "1";
"A":   PN = "1"  !CDS_PN = "1";
"B":   PN = "2"  !CDS_PN = "2";
BODY = "Q_RES","I35": LOCATION = "R4060" #&CDS_LOCATION = "R4060" &SEC = "1" #&CDS_SEC = "1";
"A":   PN = "1"  !CDS_PN = "1";
"B":   PN = "2"  !CDS_PN = "2";
BODY = "Q_RES","I40": LOCATION = "R4067" #&CDS_LOCATION = "R4067" &SEC = "1" #&CDS_SEC = "1";
"A":   PN = "1"  !CDS_PN = "1";
"B":   PN = "2"  !CDS_PN = "2";
BODY = "Q_RES","I48": #LOCATION = "PR3812" !CDS_LOCATION = "PR3812" &SEC = "1" #&CDS_SEC = "1";
"A":   PN = "1"  !CDS_PN = "1";
"B":   PN = "2"  !CDS_PN = "2";
BODY = "Q_RES","I57": LOCATION = "R3142" #&CDS_LOCATION = "R3142" &SEC = "1" #&CDS_SEC = "1";
"A":   PN = "1"  !CDS_PN = "1";
"B":   PN = "2"  !CDS_PN = "2";
BODY = "Q_RES","I74": LOCATION = "R3868" #&CDS_LOCATION = "R3868" &SEC = "1" #&CDS_SEC = "1";
"A":   PN = "1"  !CDS_PN = "1";
"B":   PN = "2"  !CDS_PN = "2";
BODY = "Q_RES","I78": LOCATION = "R3831" #&CDS_LOCATION = "R3831" &SEC = "1" #&CDS_SEC = "1";
"A":   PN = "1"  !CDS_PN = "1";
"B":   PN = "2"  !CDS_PN = "2";
BODY = "Q_RES","I80": #LOCATION = "R3816" !CDS_LOCATION = "R3816" &SEC = "1" #&CDS_SEC = "1";
"A":   PN = "1"  !CDS_PN = "1";
"B":   PN = "2"  !CDS_PN = "2";
BODY = "Q_RES","I3": #LOCATION = "R3134" !CDS_LOCATION = "R3134" &SEC = "1" #&CDS_SEC = "1";
"A":   PN = "1"  !CDS_PN = "1";
"B":   PN = "2"  !CDS_PN = "2";
BODY = "Q_RES","I5": #LOCATION = "R3136" !CDS_LOCATION = "R3136" &SEC = "1" #&CDS_SEC = "1";
"A":   PN = "1"  !CDS_PN = "1";
"B":   PN = "2"  !CDS_PN = "2";
BODY = "Q_RES","I6": LOCATION = "R4059" #&CDS_LOCATION = "R4059" &SEC = "1" #&CDS_SEC = "1";
"A":   PN = "1"  !CDS_PN = "1";
"B":   PN = "2"  !CDS_PN = "2";
BODY = "Q_RES","I11": #LOCATION = "R3133" !CDS_LOCATION = "R3133" &SEC = "1" #&CDS_SEC = "1";
"A":   PN = "1"  !CDS_PN = "1";
"B":   PN = "2"  !CDS_PN = "2";
BODY = "Q_RES","I13": #LOCATION = "R3135" !CDS_LOCATION = "R3135" &SEC = "1" #&CDS_SEC = "1";
"A":   PN = "1"  !CDS_PN = "1";
"B":   PN = "2"  !CDS_PN = "2";
BODY = "Q_RES","I14": LOCATION = "R4065" #&CDS_LOCATION = "R4065" &SEC = "1" #&CDS_SEC = "1";
"A":   PN = "1"  !CDS_PN = "1";
"B":   PN = "2"  !CDS_PN = "2";
BODY = "MOSFET_NCH_DUAL","I16": LOCATION = "Q118" #&CDS_LOCATION = "Q118" &SEC = "2" #&CDS_SEC = "2";
"D2":   PN = "3"  !CDS_PN = "3";
"G2":   PN = "5"  !CDS_PN = "5";
"S2":   PN = "4"  !CDS_PN = "4";
BODY = "74LVC2G07DW7","I19": #LOCATION = "U59" !CDS_LOCATION = "U59" &SEC = "1" #&CDS_SEC = "1";
"1A":   PN = "1"  !CDS_PN = "1";
"1Y":   PN = "6"  !CDS_PN = "6";
"2A":   PN = "3"  !CDS_PN = "3";
"2Y":   PN = "4"  !CDS_PN = "4";
"GND":   PN = "2"  !CDS_PN = "2";
"VCC":   PN = "5"  !CDS_PN = "5";
BODY = "74LVC2G07DW7","I25": #LOCATION = "U58" !CDS_LOCATION = "U58" &SEC = "1" #&CDS_SEC = "1";
"1A":   PN = "1"  !CDS_PN = "1";
"1Y":   PN = "6"  !CDS_PN = "6";
"2A":   PN = "3"  !CDS_PN = "3";
"2Y":   PN = "4"  !CDS_PN = "4";
"GND":   PN = "2"  !CDS_PN = "2";
"VCC":   PN = "5"  !CDS_PN = "5";
BODY = "Q_RES","I32": #LOCATION = "PR3806" !CDS_LOCATION = "PR3806" &SEC = "1" #&CDS_SEC = "1";
"A":   PN = "1"  !CDS_PN = "1";
"B":   PN = "2"  !CDS_PN = "2";
BODY = "MOSFET_NCH_DUAL","I42": LOCATION = "Q119" #&CDS_LOCATION = "Q119" &SEC = "2" #&CDS_SEC = "2";
"D2":   PN = "3"  !CDS_PN = "3";
"G2":   PN = "5"  !CDS_PN = "5";
"S2":   PN = "4"  !CDS_PN = "4";
BODY = "Q_RES","I47": LOCATION = "R3807" #&CDS_LOCATION = "R3807" &SEC = "1" #&CDS_SEC = "1";
"A":   PN = "1"  !CDS_PN = "1";
"B":   PN = "2"  !CDS_PN = "2";
BODY = "Q_CAP","I52": #LOCATION = "PC2140" !CDS_LOCATION = "PC2140" &SEC = "1" #&CDS_SEC = "1";
"A":   PN = "1"  !CDS_PN = "1";
"B":   PN = "2"  !CDS_PN = "2";
BODY = "Q_RES","I56": LOCATION = "R3143" #&CDS_LOCATION = "R3143" &SEC = "1" #&CDS_SEC = "1";
"A":   PN = "1"  !CDS_PN = "1";
"B":   PN = "2"  !CDS_PN = "2";
BODY = "MAX15090BEWIT","I63": #LOCATION = "PU201" !CDS_LOCATION = "PU201" &SEC = "1" #&CDS_SEC = "1";
"CB":   PN = "B1"  !CDS_PN = "B1";
"CDLY":   PN = "A7"  !CDS_PN = "A7";
"EN#":   PN = "B7"  !CDS_PN = "B7";
"FAULT#":   PN = "C7"  !CDS_PN = "C7";
"GATE":   PN = "A6"  !CDS_PN = "A6";
"GND_B2":   PN = "B2"  !CDS_PN = "B2";
"GND_C1":   PN = "C1"  !CDS_PN = "C1";
"GND_C2":   PN = "C2"  !CDS_PN = "C2";
"IN_A3":   PN = "A3"  !CDS_PN = "A3";
"IN_A5":   PN = "A5"  !CDS_PN = "A5";
"IN_B3":   PN = "B3"  !CDS_PN = "B3";
"IN_B5":   PN = "B5"  !CDS_PN = "B5";
"IN_C3":   PN = "C3"  !CDS_PN = "C3";
"IN_C5":   PN = "C5"  !CDS_PN = "C5";
"IN_D5":   PN = "D5"  !CDS_PN = "D5";
"ISENSE":   PN = "A1"  !CDS_PN = "A1";
"OUT_A4":   PN = "A4"  !CDS_PN = "A4";
"OUT_B4":   PN = "B4"  !CDS_PN = "B4";
"OUT_B6":   PN = "B6"  !CDS_PN = "B6";
"OUT_C4":   PN = "C4"  !CDS_PN = "C4";
"OUT_C6":   PN = "C6"  !CDS_PN = "C6";
"OUT_D4":   PN = "D4"  !CDS_PN = "D4";
"OUT_D6":   PN = "D6"  !CDS_PN = "D6";
"OV":   PN = "D3"  !CDS_PN = "D3";
"PG":   PN = "D7"  !CDS_PN = "D7";
"REG":   PN = "D1"  !CDS_PN = "D1";
"UV":   PN = "D2"  !CDS_PN = "D2";
"VCC":   PN = "A2"  !CDS_PN = "A2";
BODY = "Q_RES","I66": LOCATION = "R3147" #&CDS_LOCATION = "R3147" &SEC = "1" #&CDS_SEC = "1";
"A":   PN = "1"  !CDS_PN = "1";
"B":   PN = "2"  !CDS_PN = "2";
BODY = "Q_CAP","I73": LOCATION = "C2148" #&CDS_LOCATION = "C2148" &SEC = "1" #&CDS_SEC = "1";
"A":   PN = "1"  !CDS_PN = "1";
"B":   PN = "2"  !CDS_PN = "2";
BODY = "Q_RES","I81": #LOCATION = "R3825" !CDS_LOCATION = "R3825" &SEC = "1" #&CDS_SEC = "1";
"A":   PN = "1"  !CDS_PN = "1";
"B":   PN = "2"  !CDS_PN = "2";
BODY = "Q_RES","I89": #LOCATION = "PR3822" !CDS_LOCATION = "PR3822" &SEC = "1" #&CDS_SEC = "1";
"A":   PN = "1"  !CDS_PN = "1";
"B":   PN = "2"  !CDS_PN = "2";
BODY = "MAX15090BEWIT","I90": #LOCATION = "PU200" !CDS_LOCATION = "PU200" &SEC = "1" #&CDS_SEC = "1";
"CB":   PN = "B1"  !CDS_PN = "B1";
"CDLY":   PN = "A7"  !CDS_PN = "A7";
"EN#":   PN = "B7"  !CDS_PN = "B7";
"FAULT#":   PN = "C7"  !CDS_PN = "C7";
"GATE":   PN = "A6"  !CDS_PN = "A6";
"GND_B2":   PN = "B2"  !CDS_PN = "B2";
"GND_C1":   PN = "C1"  !CDS_PN = "C1";
"GND_C2":   PN = "C2"  !CDS_PN = "C2";
"IN_A3":   PN = "A3"  !CDS_PN = "A3";
"IN_A5":   PN = "A5"  !CDS_PN = "A5";
"IN_B3":   PN = "B3"  !CDS_PN = "B3";
"IN_B5":   PN = "B5"  !CDS_PN = "B5";
"IN_C3":   PN = "C3"  !CDS_PN = "C3";
"IN_C5":   PN = "C5"  !CDS_PN = "C5";
"IN_D5":   PN = "D5"  !CDS_PN = "D5";
"ISENSE":   PN = "A1"  !CDS_PN = "A1";
"OUT_A4":   PN = "A4"  !CDS_PN = "A4";
"OUT_B4":   PN = "B4"  !CDS_PN = "B4";
"OUT_B6":   PN = "B6"  !CDS_PN = "B6";
"OUT_C4":   PN = "C4"  !CDS_PN = "C4";
"OUT_C6":   PN = "C6"  !CDS_PN = "C6";
"OUT_D4":   PN = "D4"  !CDS_PN = "D4";
"OUT_D6":   PN = "D6"  !CDS_PN = "D6";
"OV":   PN = "D3"  !CDS_PN = "D3";
"PG":   PN = "D7"  !CDS_PN = "D7";
"REG":   PN = "D1"  !CDS_PN = "D1";
"UV":   PN = "D2"  !CDS_PN = "D2";
"VCC":   PN = "A2"  !CDS_PN = "A2";
BODY = "Q_RES","I92": #LOCATION = "PR3782" !CDS_LOCATION = "PR3782" &SEC = "1" #&CDS_SEC = "1";
"A":   PN = "1"  !CDS_PN = "1";
"B":   PN = "2"  !CDS_PN = "2";
BODY = "SCHOTTKY_AC","I93": #LOCATION = "PD108" !CDS_LOCATION = "PD108" &SEC = "1" #&CDS_SEC = "1";
"A":   PN = "A"  !CDS_PN = "A";
"C":   PN = "C"  !CDS_PN = "C";
BODY = "Q_CAP","I96": #LOCATION = "PC2151" !CDS_LOCATION = "PC2151" &SEC = "1" #&CDS_SEC = "1";
"A":   PN = "1"  !CDS_PN = "1";
"B":   PN = "2"  !CDS_PN = "2";
BODY = "Q_CAP","I100": #LOCATION = "PC2141" !CDS_LOCATION = "PC2141" &SEC = "1" #&CDS_SEC = "1";
"A":   PN = "1"  !CDS_PN = "1";
"B":   PN = "2"  !CDS_PN = "2";
BODY = "Q_CAP","I102": #LOCATION = "PC2143" !CDS_LOCATION = "PC2143" &SEC = "1" #&CDS_SEC = "1";
"A":   PN = "1"  !CDS_PN = "1";
"B":   PN = "2"  !CDS_PN = "2";
BODY = "Q_CAP","I105": #LOCATION = "PC2149" !CDS_LOCATION = "PC2149" &SEC = "1" #&CDS_SEC = "1";
"A":   PN = "1"  !CDS_PN = "1";
"B":   PN = "2"  !CDS_PN = "2";
BODY = "SCHOTTKY_AC","I107": #LOCATION = "PD109" !CDS_LOCATION = "PD109" &SEC = "1" #&CDS_SEC = "1";
"A":   PN = "A"  !CDS_PN = "A";
"C":   PN = "C"  !CDS_PN = "C";
BODY = "Q_CAP","I109": #LOCATION = "PC2137" !CDS_LOCATION = "PC2137" &SEC = "1" #&CDS_SEC = "1";
"A":   PN = "1"  !CDS_PN = "1";
"B":   PN = "2"  !CDS_PN = "2";
BODY = "Q_CAP","I113": #LOCATION = "PC2142" !CDS_LOCATION = "PC2142" &SEC = "1" #&CDS_SEC = "1";
"A":   PN = "1"  !CDS_PN = "1";
"B":   PN = "2"  !CDS_PN = "2";
BODY = "MOSFET_NCH_DUAL","I7": LOCATION = "Q118" #&CDS_LOCATION = "Q118" &SEC = "1" #&CDS_SEC = "1";
"D1":   PN = "6"  !CDS_PN = "6";
"G1":   PN = "2"  !CDS_PN = "2";
"S1":   PN = "1"  !CDS_PN = "1";
BODY = "Q_CAP","I21": LOCATION = "C1810" #&CDS_LOCATION = "C1810" &SEC = "1" #&CDS_SEC = "1";
"A":   PN = "1"  !CDS_PN = "1";
"B":   PN = "2"  !CDS_PN = "2";
BODY = "Q_RES","I29": #LOCATION = "PR3828" !CDS_LOCATION = "PR3828" &SEC = "1" #&CDS_SEC = "1";
"A":   PN = "1"  !CDS_PN = "1";
"B":   PN = "2"  !CDS_PN = "2";
BODY = "Q_RES","I30": LOCATION = "R3827" #&CDS_LOCATION = "R3827" &SEC = "1" #&CDS_SEC = "1";
"A":   PN = "1"  !CDS_PN = "1";
"B":   PN = "2"  !CDS_PN = "2";
BODY = "Q_RES","I37": LOCATION = "R4066" #&CDS_LOCATION = "R4066" &SEC = "1" #&CDS_SEC = "1";
"A":   PN = "1"  !CDS_PN = "1";
"B":   PN = "2"  !CDS_PN = "2";
BODY = "DIODE_TVS","I44": #LOCATION = "PD107" !CDS_LOCATION = "PD107" &SEC = "1" #&CDS_SEC = "1";
"A":   PN = "A"  !CDS_PN = "A";
"C":   PN = "C"  !CDS_PN = "C";
BODY = "Q_CAP","I46": #LOCATION = "PC2139" !CDS_LOCATION = "PC2139" &SEC = "1" #&CDS_SEC = "1";
"A":   PN = "1"  !CDS_PN = "1";
"B":   PN = "2"  !CDS_PN = "2";
BODY = "Q_RES","I50": #LOCATION = "PR3829" !CDS_LOCATION = "PR3829" &SEC = "1" #&CDS_SEC = "1";
"A":   PN = "1"  !CDS_PN = "1";
"B":   PN = "2"  !CDS_PN = "2";
BODY = "Q_RES","I53": #LOCATION = "PR3795" !CDS_LOCATION = "PR3795" &SEC = "1" #&CDS_SEC = "1";
"A":   PN = "1"  !CDS_PN = "1";
"B":   PN = "2"  !CDS_PN = "2";
BODY = "Q_RES","I55": LOCATION = "R4753" #&CDS_LOCATION = "R4753" &SEC = "1" #&CDS_SEC = "1";
"A":   PN = "1"  !CDS_PN = "1";
"B":   PN = "2"  !CDS_PN = "2";
BODY = "Q_CAP","I61": #LOCATION = "PC2098" !CDS_LOCATION = "PC2098" &SEC = "1" #&CDS_SEC = "1";
"A":   PN = "1"  !CDS_PN = "1";
"B":   PN = "2"  !CDS_PN = "2";
BODY = "Q_CAP","I62": #LOCATION = "PC2146" !CDS_LOCATION = "PC2146" &SEC = "1" #&CDS_SEC = "1";
"A":   PN = "1"  !CDS_PN = "1";
"B":   PN = "2"  !CDS_PN = "2";
BODY = "Q_RES","I64": LOCATION = "R3145" #&CDS_LOCATION = "R3145" &SEC = "1" #&CDS_SEC = "1";
"A":   PN = "1"  !CDS_PN = "1";
"B":   PN = "2"  !CDS_PN = "2";
BODY = "Q_RES","I72": #LOCATION = "PR3823" !CDS_LOCATION = "PR3823" &SEC = "1" #&CDS_SEC = "1";
"A":   PN = "1"  !CDS_PN = "1";
"B":   PN = "2"  !CDS_PN = "2";
BODY = "Q_RES","I75": LOCATION = "R3867" #&CDS_LOCATION = "R3867" &SEC = "1" #&CDS_SEC = "1";
"A":   PN = "1"  !CDS_PN = "1";
"B":   PN = "2"  !CDS_PN = "2";
BODY = "Q_CAP","I76": #LOCATION = "PC2150" !CDS_LOCATION = "PC2150" &SEC = "1" #&CDS_SEC = "1";
"A":   PN = "1"  !CDS_PN = "1";
"B":   PN = "2"  !CDS_PN = "2";
BODY = "Q_RES","I77": #LOCATION = "PR4522" !CDS_LOCATION = "PR4522" &SEC = "1" #&CDS_SEC = "1";
"A":   PN = "1"  !CDS_PN = "1";
"B":   PN = "2"  !CDS_PN = "2";
BODY = "Q_CAP","I91": LOCATION = "PC190" #&CDS_LOCATION = "PC190" &SEC = "1" #&CDS_SEC = "1";
"A":   PN = "1"  !CDS_PN = "1";
"B":   PN = "2"  !CDS_PN = "2";
BODY = "Q_RES","I95": #LOCATION = "PR3824" !CDS_LOCATION = "PR3824" &SEC = "1" #&CDS_SEC = "1";
"A":   PN = "1"  !CDS_PN = "1";
"B":   PN = "2"  !CDS_PN = "2";
BODY = "Q_CAP","I98": #LOCATION = "PC2152" !CDS_LOCATION = "PC2152" &SEC = "1" #&CDS_SEC = "1";
"A":   PN = "1"  !CDS_PN = "1";
"B":   PN = "2"  !CDS_PN = "2";
BODY = "Q_RES","I106": #LOCATION = "PR4523" !CDS_LOCATION = "PR4523" &SEC = "1" #&CDS_SEC = "1";
"A":   PN = "1"  !CDS_PN = "1";
"B":   PN = "2"  !CDS_PN = "2";
BODY = "Q_RES","I108": #LOCATION = "R3833" !CDS_LOCATION = "R3833" &SEC = "1" #&CDS_SEC = "1";
"A":   PN = "1"  !CDS_PN = "1";
"B":   PN = "2"  !CDS_PN = "2";
BODY = "Q_RES","I110": #LOCATION = "R3826" !CDS_LOCATION = "R3826" &SEC = "1" #&CDS_SEC = "1";
"A":   PN = "1"  !CDS_PN = "1";
"B":   PN = "2"  !CDS_PN = "2";
DRAWING = "@s9s_mb_2u_lib.s9s_mb_2u(sch_1):page132";
BODY = "Q_RES","I7": LOCATION = "R3155" #&CDS_LOCATION = "R3155" &SEC = "1" #&CDS_SEC = "1";
"A":   PN = "1"  !CDS_PN = "1";
"B":   PN = "2"  !CDS_PN = "2";
BODY = "74LVC1G08W57","I9": #LOCATION = "U50" !CDS_LOCATION = "U50" &SEC = "1" #&CDS_SEC = "1";
"A":   PN = "1"  !CDS_PN = "1";
"B":   PN = "2"  !CDS_PN = "2";
"GND":   PN = "3"  !CDS_PN = "3";
"VCC":   PN = "5"  !CDS_PN = "5";
"Y":   PN = "4"  !CDS_PN = "4";
BODY = "Q_CAP","I15": LOCATION = "C1818" #&CDS_LOCATION = "C1818" &SEC = "1" #&CDS_SEC = "1";
"A":   PN = "1"  !CDS_PN = "1";
"B":   PN = "2"  !CDS_PN = "2";
BODY = "Q_RES","I23": LOCATION = "R3158" #&CDS_LOCATION = "R3158" &SEC = "1" #&CDS_SEC = "1";
"A":   PN = "1"  !CDS_PN = "1";
"B":   PN = "2"  !CDS_PN = "2";
BODY = "Q_RES","I29": LOCATION = "R3149" #&CDS_LOCATION = "R3149" &SEC = "1" #&CDS_SEC = "1";
"A":   PN = "1"  !CDS_PN = "1";
"B":   PN = "2"  !CDS_PN = "2";
BODY = "Q_RES","I32": LOCATION = "R3153" #&CDS_LOCATION = "R3153" &SEC = "1" #&CDS_SEC = "1";
"A":   PN = "1"  !CDS_PN = "1";
"B":   PN = "2"  !CDS_PN = "2";
BODY = "Q_RES","I34": LOCATION = "R3156" #&CDS_LOCATION = "R3156" &SEC = "1" #&CDS_SEC = "1";
"A":   PN = "1"  !CDS_PN = "1";
"B":   PN = "2"  !CDS_PN = "2";
BODY = "74LVC1G08W57","I56": #LOCATION = "U53" !CDS_LOCATION = "U53" &SEC = "1" #&CDS_SEC = "1";
"A":   PN = "1"  !CDS_PN = "1";
"B":   PN = "2"  !CDS_PN = "2";
"GND":   PN = "3"  !CDS_PN = "3";
"VCC":   PN = "5"  !CDS_PN = "5";
"Y":   PN = "4"  !CDS_PN = "4";
BODY = "Q_RES","I65": LOCATION = "R3154" #&CDS_LOCATION = "R3154" &SEC = "1" #&CDS_SEC = "1";
"A":   PN = "1"  !CDS_PN = "1";
"B":   PN = "2"  !CDS_PN = "2";
BODY = "MOSFET_N","I3": LOCATION = "U215" #&CDS_LOCATION = "U215" &SEC = "1" #&CDS_SEC = "1";
"DRAIN":   PN = "D"  !CDS_PN = "D";
"GATE":   PN = "G"  !CDS_PN = "G";
"SOURCE":   PN = "S"  !CDS_PN = "S";
BODY = "Q_RES","I25": LOCATION = "R3150" #&CDS_LOCATION = "R3150" &SEC = "1" #&CDS_SEC = "1";
"A":   PN = "1"  !CDS_PN = "1";
"B":   PN = "2"  !CDS_PN = "2";
BODY = "Q_RES","I27": LOCATION = "R3152" #&CDS_LOCATION = "R3152" &SEC = "1" #&CDS_SEC = "1";
"A":   PN = "1"  !CDS_PN = "1";
"B":   PN = "2"  !CDS_PN = "2";
BODY = "Q_RES","I31": LOCATION = "R3151" #&CDS_LOCATION = "R3151" &SEC = "1" #&CDS_SEC = "1";
"A":   PN = "1"  !CDS_PN = "1";
"B":   PN = "2"  !CDS_PN = "2";
BODY = "Q_RES","I33": LOCATION = "R3157" #&CDS_LOCATION = "R3157" &SEC = "1" #&CDS_SEC = "1";
"A":   PN = "1"  !CDS_PN = "1";
"B":   PN = "2"  !CDS_PN = "2";
BODY = "Q_CAP","I39": LOCATION = "C1817" #&CDS_LOCATION = "C1817" &SEC = "1" #&CDS_SEC = "1";
"A":   PN = "1"  !CDS_PN = "1";
"B":   PN = "2"  !CDS_PN = "2";
BODY = "Q_CAP","I58": LOCATION = "C1820" #&CDS_LOCATION = "C1820" &SEC = "1" #&CDS_SEC = "1";
"A":   PN = "1"  !CDS_PN = "1";
"B":   PN = "2"  !CDS_PN = "2";
BODY = "PCA9555APW","I66": #LOCATION = "U51" !CDS_LOCATION = "U51" &SEC = "1" #&CDS_SEC = "1";
"A0":   PN = "21"  !CDS_PN = "21";
"A1":   PN = "2"  !CDS_PN = "2";
"A2":   PN = "3"  !CDS_PN = "3";
"INT#":   PN = "1"  !CDS_PN = "1";
"P0_0":   PN = "4"  !CDS_PN = "4";
"P0_1":   PN = "5"  !CDS_PN = "5";
"P0_2":   PN = "6"  !CDS_PN = "6";
"P0_3":   PN = "7"  !CDS_PN = "7";
"P0_4":   PN = "8"  !CDS_PN = "8";
"P0_5":   PN = "9"  !CDS_PN = "9";
"P0_6":   PN = "10"  !CDS_PN = "10";
"P0_7":   PN = "11"  !CDS_PN = "11";
"P1_0":   PN = "13"  !CDS_PN = "13";
"P1_1":   PN = "14"  !CDS_PN = "14";
"P1_2":   PN = "15"  !CDS_PN = "15";
"P1_3":   PN = "16"  !CDS_PN = "16";
"P1_4":   PN = "17"  !CDS_PN = "17";
"P1_5":   PN = "18"  !CDS_PN = "18";
"P1_6":   PN = "19"  !CDS_PN = "19";
"P1_7":   PN = "20"  !CDS_PN = "20";
"SCL":   PN = "22"  !CDS_PN = "22";
"SDA":   PN = "23"  !CDS_PN = "23";
"VDD":   PN = "24"  !CDS_PN = "24";
"VSS":   PN = "12"  !CDS_PN = "12";
BODY = "APX80929SAG7","I85": LOCATION = "U216" #&CDS_LOCATION = "U216" &SEC = "1" #&CDS_SEC = "1";
"GND":   PN = "1"  !CDS_PN = "1";
"RESET_L":   PN = "2"  !CDS_PN = "2";
"VCC":   PN = "3"  !CDS_PN = "3";
BODY = "Q_CAP","I87": LOCATION = "C1819" #&CDS_LOCATION = "C1819" &SEC = "1" #&CDS_SEC = "1";
"A":   PN = "1"  !CDS_PN = "1";
"B":   PN = "2"  !CDS_PN = "2";
BODY = "Q_CAP","I90": LOCATION = "C2347" #&CDS_LOCATION = "C2347" &SEC = "1" #&CDS_SEC = "1";
"A":   PN = "1"  !CDS_PN = "1";
"B":   PN = "2"  !CDS_PN = "2";
BODY = "74LVC1G08W57","I92": LOCATION = "U323" #&CDS_LOCATION = "U323" &SEC = "1" #&CDS_SEC = "1";
"A":   PN = "1"  !CDS_PN = "1";
"B":   PN = "2"  !CDS_PN = "2";
"GND":   PN = "3"  !CDS_PN = "3";
"VCC":   PN = "5"  !CDS_PN = "5";
"Y":   PN = "4"  !CDS_PN = "4";
BODY = "Q_RES","I95": #LOCATION = "R1132" !CDS_LOCATION = "R1132" &SEC = "1" #&CDS_SEC = "1";
"A":   PN = "1"  !CDS_PN = "1";
"B":   PN = "2"  !CDS_PN = "2";
BODY = "Q_RES","I96": LOCATION = "R4615" #&CDS_LOCATION = "R4615" &SEC = "1" #&CDS_SEC = "1";
"A":   PN = "1"  !CDS_PN = "1";
"B":   PN = "2"  !CDS_PN = "2";
BODY = "Q_RES","I99": LOCATION = "R4617" #&CDS_LOCATION = "R4617" &SEC = "1" #&CDS_SEC = "1";
"A":   PN = "1"  !CDS_PN = "1";
"B":   PN = "2"  !CDS_PN = "2";
BODY = "Q_RES","I100": #LOCATION = "R4616" !CDS_LOCATION = "R4616" &SEC = "1" #&CDS_SEC = "1";
"A":   PN = "1"  !CDS_PN = "1";
"B":   PN = "2"  !CDS_PN = "2";
BODY = "Q_RES","I103": LOCATION = "R4755" #&CDS_LOCATION = "R4755" &SEC = "1" #&CDS_SEC = "1";
"A":   PN = "1"  !CDS_PN = "1";
"B":   PN = "2"  !CDS_PN = "2";
BODY = "Q_RES","I104": LOCATION = "R4754" #&CDS_LOCATION = "R4754" &SEC = "1" #&CDS_SEC = "1";
"A":   PN = "1"  !CDS_PN = "1";
"B":   PN = "2"  !CDS_PN = "2";
BODY = "Q_RES","I105": LOCATION = "R4756" #&CDS_LOCATION = "R4756" &SEC = "1" #&CDS_SEC = "1";
"A":   PN = "1"  !CDS_PN = "1";
"B":   PN = "2"  !CDS_PN = "2";
BODY = "Q_RES","I107": LOCATION = "R4758" #&CDS_LOCATION = "R4758" &SEC = "1" #&CDS_SEC = "1";
"A":   PN = "1"  !CDS_PN = "1";
"B":   PN = "2"  !CDS_PN = "2";
BODY = "74LVC1G08W57","I108": LOCATION = "U335" #&CDS_LOCATION = "U335" &SEC = "1" #&CDS_SEC = "1";
"A":   PN = "1"  !CDS_PN = "1";
"B":   PN = "2"  !CDS_PN = "2";
"GND":   PN = "3"  !CDS_PN = "3";
"VCC":   PN = "5"  !CDS_PN = "5";
"Y":   PN = "4"  !CDS_PN = "4";
BODY = "Q_CAP","I110": LOCATION = "C2377" #&CDS_LOCATION = "C2377" &SEC = "1" #&CDS_SEC = "1";
"A":   PN = "1"  !CDS_PN = "1";
"B":   PN = "2"  !CDS_PN = "2";
BODY = "Q_RES","I111": LOCATION = "R4759" #&CDS_LOCATION = "R4759" &SEC = "1" #&CDS_SEC = "1";
"A":   PN = "1"  !CDS_PN = "1";
"B":   PN = "2"  !CDS_PN = "2";
BODY = "Q_RES","I112": LOCATION = "R4757" #&CDS_LOCATION = "R4757" &SEC = "1" #&CDS_SEC = "1";
"A":   PN = "1"  !CDS_PN = "1";
"B":   PN = "2"  !CDS_PN = "2";
BODY = "Q_RES","I119": LOCATION = "R4763" #&CDS_LOCATION = "R4763" &SEC = "1" #&CDS_SEC = "1";
"A":   PN = "1"  !CDS_PN = "1";
"B":   PN = "2"  !CDS_PN = "2";
DRAWING = "@s9s_mb_2u_lib.s9s_mb_2u(sch_1):page146";
BODY = "Q_RES","I5": LOCATION = "R3168" #&CDS_LOCATION = "R3168" &SEC = "1" #&CDS_SEC = "1";
"A":   PN = "1"  !CDS_PN = "1";
"B":   PN = "2"  !CDS_PN = "2";
BODY = "Q_RES","I20": LOCATION = "R3167" #&CDS_LOCATION = "R3167" &SEC = "1" #&CDS_SEC = "1";
"A":   PN = "1"  !CDS_PN = "1";
"B":   PN = "2"  !CDS_PN = "2";
BODY = "Q_RES","I23": LOCATION = "R3166" #&CDS_LOCATION = "R3166" &SEC = "1" #&CDS_SEC = "1";
"A":   PN = "1"  !CDS_PN = "1";
"B":   PN = "2"  !CDS_PN = "2";
BODY = "Q_RES","I25": LOCATION = "R3163" #&CDS_LOCATION = "R3163" &SEC = "1" #&CDS_SEC = "1";
"A":   PN = "1"  !CDS_PN = "1";
"B":   PN = "2"  !CDS_PN = "2";
BODY = "Q_RES","I26": LOCATION = "R3162" #&CDS_LOCATION = "R3162" &SEC = "1" #&CDS_SEC = "1";
"A":   PN = "1"  !CDS_PN = "1";
"B":   PN = "2"  !CDS_PN = "2";
BODY = "Q_RES","I31": LOCATION = "R3171" #&CDS_LOCATION = "R3171" &SEC = "1" #&CDS_SEC = "1";
"A":   PN = "1"  !CDS_PN = "1";
"B":   PN = "2"  !CDS_PN = "2";
BODY = "Q_RES","I32": LOCATION = "R3170" #&CDS_LOCATION = "R3170" &SEC = "1" #&CDS_SEC = "1";
"A":   PN = "1"  !CDS_PN = "1";
"B":   PN = "2"  !CDS_PN = "2";
BODY = "Q_RES","I33": LOCATION = "R3169" #&CDS_LOCATION = "R3169" &SEC = "1" #&CDS_SEC = "1";
"A":   PN = "1"  !CDS_PN = "1";
"B":   PN = "2"  !CDS_PN = "2";
BODY = "Q_RES","I36": LOCATION = "R3172" #&CDS_LOCATION = "R3172" &SEC = "1" #&CDS_SEC = "1";
"A":   PN = "1"  !CDS_PN = "1";
"B":   PN = "2"  !CDS_PN = "2";
BODY = "Q_RES","I37": LOCATION = "R3165" #&CDS_LOCATION = "R3165" &SEC = "1" #&CDS_SEC = "1";
"A":   PN = "1"  !CDS_PN = "1";
"B":   PN = "2"  !CDS_PN = "2";
BODY = "Q_RES","I38": LOCATION = "R3164" #&CDS_LOCATION = "R3164" &SEC = "1" #&CDS_SEC = "1";
"A":   PN = "1"  !CDS_PN = "1";
"B":   PN = "2"  !CDS_PN = "2";
BODY = "Q_RES","I43": #LOCATION = "R413" !CDS_LOCATION = "R413" &SEC = "1" #&CDS_SEC = "1";
"A":   PN = "1"  !CDS_PN = "1";
"B":   PN = "2"  !CDS_PN = "2";
BODY = "Q_RES","I147": LOCATION = "R3178" #&CDS_LOCATION = "R3178" &SEC = "1" #&CDS_SEC = "1";
"A":   PN = "1"  !CDS_PN = "1";
"B":   PN = "2"  !CDS_PN = "2";
BODY = "Q_RES","I148": LOCATION = "R3177" #&CDS_LOCATION = "R3177" &SEC = "1" #&CDS_SEC = "1";
"A":   PN = "1"  !CDS_PN = "1";
"B":   PN = "2"  !CDS_PN = "2";
BODY = "Q_RES","I152": LOCATION = "R3180" #&CDS_LOCATION = "R3180" &SEC = "1" #&CDS_SEC = "1";
"A":   PN = "1"  !CDS_PN = "1";
"B":   PN = "2"  !CDS_PN = "2";
BODY = "Q_RES","I165": LOCATION = "R3173" #&CDS_LOCATION = "R3173" &SEC = "1" #&CDS_SEC = "1";
"A":   PN = "1"  !CDS_PN = "1";
"B":   PN = "2"  !CDS_PN = "2";
BODY = "Q_CAP","I166": LOCATION = "C1829" #&CDS_LOCATION = "C1829" &SEC = "1" #&CDS_SEC = "1";
"A":   PN = "1"  !CDS_PN = "1";
"B":   PN = "2"  !CDS_PN = "2";
BODY = "Q_CAP","I167": LOCATION = "C1830" #&CDS_LOCATION = "C1830" &SEC = "1" #&CDS_SEC = "1";
"A":   PN = "1"  !CDS_PN = "1";
"B":   PN = "2"  !CDS_PN = "2";
BODY = "Q_CAP","I168": LOCATION = "C1831" #&CDS_LOCATION = "C1831" &SEC = "1" #&CDS_SEC = "1";
"A":   PN = "1"  !CDS_PN = "1";
"B":   PN = "2"  !CDS_PN = "2";
BODY = "Q_CAP","I169": LOCATION = "C1833" #&CDS_LOCATION = "C1833" &SEC = "1" #&CDS_SEC = "1";
"A":   PN = "1"  !CDS_PN = "1";
"B":   PN = "2"  !CDS_PN = "2";
BODY = "Q_CAP","I171": LOCATION = "C1834" #&CDS_LOCATION = "C1834" &SEC = "1" #&CDS_SEC = "1";
"A":   PN = "1"  !CDS_PN = "1";
"B":   PN = "2"  !CDS_PN = "2";
BODY = "Q_CAP","I173": LOCATION = "C1835" #&CDS_LOCATION = "C1835" &SEC = "1" #&CDS_SEC = "1";
"A":   PN = "1"  !CDS_PN = "1";
"B":   PN = "2"  !CDS_PN = "2";
BODY = "Q_CAP","I174": LOCATION = "C1836" #&CDS_LOCATION = "C1836" &SEC = "1" #&CDS_SEC = "1";
"A":   PN = "1"  !CDS_PN = "1";
"B":   PN = "2"  !CDS_PN = "2";
BODY = "Q_CAP","I175": LOCATION = "C1837" #&CDS_LOCATION = "C1837" &SEC = "1" #&CDS_SEC = "1";
"A":   PN = "1"  !CDS_PN = "1";
"B":   PN = "2"  !CDS_PN = "2";
BODY = "Q_CAP","I177": LOCATION = "C1838" #&CDS_LOCATION = "C1838" &SEC = "1" #&CDS_SEC = "1";
"A":   PN = "1"  !CDS_PN = "1";
"B":   PN = "2"  !CDS_PN = "2";
BODY = "Q_CAP","I179": LOCATION = "C1832" #&CDS_LOCATION = "C1832" &SEC = "1" #&CDS_SEC = "1";
"A":   PN = "1"  !CDS_PN = "1";
"B":   PN = "2"  !CDS_PN = "2";
BODY = "Q_CAP","I180": LOCATION = "C1839" #&CDS_LOCATION = "C1839" &SEC = "1" #&CDS_SEC = "1";
"A":   PN = "1"  !CDS_PN = "1";
"B":   PN = "2"  !CDS_PN = "2";
BODY = "SCONN168_ME1016810202011","I303": #LOCATION = "J35" !CDS_LOCATION = "J35" &SEC = "1" #&CDS_SEC = "1";
"+3.3V_EDGE":   PN = "B11"  !CDS_PN = "B11";
"+12V_EDGE_B1":   PN = "B1"  !CDS_PN = "B1";
"+12V_EDGE_B2":   PN = "B2"  !CDS_PN = "B2";
"+12V_EDGE_B3":   PN = "B3"  !CDS_PN = "B3";
"+12V_EDGE_B4":   PN = "B4"  !CDS_PN = "B4";
"+12V_EDGE_B5":   PN = "B5"  !CDS_PN = "B5";
"+12V_EDGE_B6":   PN = "B6"  !CDS_PN = "B6";
"AUX_PWR_EN":   PN = "B12"  !CDS_PN = "B12";
"BIF0#":   PN = "B7"  !CDS_PN = "B7";
"BIF1#":   PN = "B8"  !CDS_PN = "B8";
"BIF2#":   PN = "B9"  !CDS_PN = "B9";
"CLK":   PN = "OB6"  !CDS_PN = "OB6";
"DATA_IN":   PN = "OB4"  !CDS_PN = "OB4";
"DATA_OUT":   PN = "OB5"  !CDS_PN = "OB5";
"G1":   PN = "G1"  !CDS_PN = "G1";
"G2":   PN = "G2"  !CDS_PN = "G2";
"G3":   PN = "G3"  !CDS_PN = "G3";
"G4":   PN = "G4"  !CDS_PN = "G4";
"G5":   PN = "G5"  !CDS_PN = "G5";
"GND_A1":   PN = "A1"  !CDS_PN = "A1";
"GND_A2":   PN = "A2"  !CDS_PN = "A2";
"GND_A3":   PN = "A3"  !CDS_PN = "A3";
"GND_A4":   PN = "A4"  !CDS_PN = "A4";
"GND_A5":   PN = "A5"  !CDS_PN = "A5";
"GND_A6":   PN = "A6"  !CDS_PN = "A6";
"GND_A13":   PN = "A13"  !CDS_PN = "A13";
"GND_A16":   PN = "A16"  !CDS_PN = "A16";
"GND_A19":   PN = "A19"  !CDS_PN = "A19";
"GND_A22":   PN = "A22"  !CDS_PN = "A22";
"GND_A25":   PN = "A25"  !CDS_PN = "A25";
"GND_A28":   PN = "A28"  !CDS_PN = "A28";
"GND_A29":   PN = "A29"  !CDS_PN = "A29";
"GND_A32":   PN = "A32"  !CDS_PN = "A32";
"GND_A35":   PN = "A35"  !CDS_PN = "A35";
"GND_A38":   PN = "A38"  !CDS_PN = "A38";
"GND_A41":   PN = "A41"  !CDS_PN = "A41";
"GND_A43":   PN = "A43"  !CDS_PN = "A43";
"GND_A46":   PN = "A46"  !CDS_PN = "A46";
"GND_A49":   PN = "A49"  !CDS_PN = "A49";
"GND_A52":   PN = "A52"  !CDS_PN = "A52";
"GND_A55":   PN = "A55"  !CDS_PN = "A55";
"GND_A58":   PN = "A58"  !CDS_PN = "A58";
"GND_A61":   PN = "A61"  !CDS_PN = "A61";
"GND_A64":   PN = "A64"  !CDS_PN = "A64";
"GND_A67":   PN = "A67"  !CDS_PN = "A67";
"GND_B13":   PN = "B13"  !CDS_PN = "B13";
"GND_B16":   PN = "B16"  !CDS_PN = "B16";
"GND_B19":   PN = "B19"  !CDS_PN = "B19";
"GND_B22":   PN = "B22"  !CDS_PN = "B22";
"GND_B25":   PN = "B25"  !CDS_PN = "B25";
"GND_B28":   PN = "B28"  !CDS_PN = "B28";
"GND_B29":   PN = "B29"  !CDS_PN = "B29";
"GND_B32":   PN = "B32"  !CDS_PN = "B32";
"GND_B35":   PN = "B35"  !CDS_PN = "B35";
"GND_B38":   PN = "B38"  !CDS_PN = "B38";
"GND_B41":   PN = "B41"  !CDS_PN = "B41";
"GND_B43":   PN = "B43"  !CDS_PN = "B43";
"GND_B46":   PN = "B46"  !CDS_PN = "B46";
"GND_B49":   PN = "B49"  !CDS_PN = "B49";
"GND_B52":   PN = "B52"  !CDS_PN = "B52";
"GND_B55":   PN = "B55"  !CDS_PN = "B55";
"GND_B58":   PN = "B58"  !CDS_PN = "B58";
"GND_B61":   PN = "B61"  !CDS_PN = "B61";
"GND_B64":   PN = "B64"  !CDS_PN = "B64";
"GND_B67":   PN = "B67"  !CDS_PN = "B67";
"GND_OA10":   PN = "OA10"  !CDS_PN = "OA10";
"GND_OA13":   PN = "OA13"  !CDS_PN = "OA13";
"GND_OB10":   PN = "OB10"  !CDS_PN = "OB10";
"GND_OB13":   PN = "OB13"  !CDS_PN = "OB13";
"LD#":   PN = "OB3"  !CDS_PN = "OB3";
"MAIN_PWR_EN":   PN = "OB2"  !CDS_PN = "OB2";
"NIC_PWR_GOOD":   PN = "OB1"  !CDS_PN = "OB1";
"PERN0":   PN = "A17"  !CDS_PN = "A17";
"PERN1":   PN = "A20"  !CDS_PN = "A20";
"PERN2":   PN = "A23"  !CDS_PN = "A23";
"PERN3":   PN = "A26"  !CDS_PN = "A26";
"PERN4":   PN = "A30"  !CDS_PN = "A30";
"PERN5":   PN = "A33"  !CDS_PN = "A33";
"PERN6":   PN = "A36"  !CDS_PN = "A36";
"PERN7":   PN = "A39"  !CDS_PN = "A39";
"PERN8":   PN = "A44"  !CDS_PN = "A44";
"PERN9":   PN = "A47"  !CDS_PN = "A47";
"PERN10":   PN = "A50"  !CDS_PN = "A50";
"PERN11":   PN = "A53"  !CDS_PN = "A53";
"PERN12":   PN = "A56"  !CDS_PN = "A56";
"PERN13":   PN = "A59"  !CDS_PN = "A59";
"PERN14":   PN = "A62"  !CDS_PN = "A62";
"PERN15":   PN = "A65"  !CDS_PN = "A65";
"PERP0":   PN = "A18"  !CDS_PN = "A18";
"PERP1":   PN = "A21"  !CDS_PN = "A21";
"PERP2":   PN = "A24"  !CDS_PN = "A24";
"PERP3":   PN = "A27"  !CDS_PN = "A27";
"PERP4":   PN = "A31"  !CDS_PN = "A31";
"PERP5":   PN = "A34"  !CDS_PN = "A34";
"PERP6":   PN = "A37"  !CDS_PN = "A37";
"PERP7":   PN = "A40"  !CDS_PN = "A40";
"PERP8":   PN = "A45"  !CDS_PN = "A45";
"PERP9":   PN = "A48"  !CDS_PN = "A48";
"PERP10":   PN = "A51"  !CDS_PN = "A51";
"PERP11":   PN = "A54"  !CDS_PN = "A54";
"PERP12":   PN = "A57"  !CDS_PN = "A57";
"PERP13":   PN = "A60"  !CDS_PN = "A60";
"PERP14":   PN = "A63"  !CDS_PN = "A63";
"PERP15":   PN = "A66"  !CDS_PN = "A66";
"PERST0#":   PN = "B10"  !CDS_PN = "B10";
"PERST1#":   PN = "A11"  !CDS_PN = "A11";
"PERST2#":   PN = "OA1"  !CDS_PN = "OA1";
"PERST3#":   PN = "OA2"  !CDS_PN = "OA2";
"PETN0":   PN = "B17"  !CDS_PN = "B17";
"PETN1":   PN = "B20"  !CDS_PN = "B20";
"PETN2":   PN = "B23"  !CDS_PN = "B23";
"PETN3":   PN = "B26"  !CDS_PN = "B26";
"PETN4":   PN = "B30"  !CDS_PN = "B30";
"PETN5":   PN = "B33"  !CDS_PN = "B33";
"PETN6":   PN = "B36"  !CDS_PN = "B36";
"PETN7":   PN = "B39"  !CDS_PN = "B39";
"PETN8":   PN = "B44"  !CDS_PN = "B44";
"PETN9":   PN = "B47"  !CDS_PN = "B47";
"PETN10":   PN = "B50"  !CDS_PN = "B50";
"PETN11":   PN = "B53"  !CDS_PN = "B53";
"PETN12":   PN = "B56"  !CDS_PN = "B56";
"PETN13":   PN = "B59"  !CDS_PN = "B59";
"PETN14":   PN = "B62"  !CDS_PN = "B62";
"PETN15":   PN = "B65"  !CDS_PN = "B65";
"PETP0":   PN = "B18"  !CDS_PN = "B18";
"PETP1":   PN = "B21"  !CDS_PN = "B21";
"PETP2":   PN = "B24"  !CDS_PN = "B24";
"PETP3":   PN = "B27"  !CDS_PN = "B27";
"PETP4":   PN = "B31"  !CDS_PN = "B31";
"PETP5":   PN = "B34"  !CDS_PN = "B34";
"PETP6":   PN = "B37"  !CDS_PN = "B37";
"PETP7":   PN = "B40"  !CDS_PN = "B40";
"PETP8":   PN = "B45"  !CDS_PN = "B45";
"PETP9":   PN = "B48"  !CDS_PN = "B48";
"PETP10":   PN = "B51"  !CDS_PN = "B51";
"PETP11":   PN = "B54"  !CDS_PN = "B54";
"PETP12":   PN = "B57"  !CDS_PN = "B57";
"PETP13":   PN = "B60"  !CDS_PN = "B60";
"PETP14":   PN = "B63"  !CDS_PN = "B63";
"PETP15":   PN = "B66"  !CDS_PN = "B66";
"PRSNTA#":   PN = "A10"  !CDS_PN = "A10";
"PRSNTB0#":   PN = "B42"  !CDS_PN = "B42";
"PRSNTB1#":   PN = "A42"  !CDS_PN = "A42";
"PRSNTB2#":   PN = "A12"  !CDS_PN = "A12";
"PRSNTB3#":   PN = "B70"  !CDS_PN = "B70";
"PWRBRK0#":   PN = "A70"  !CDS_PN = "A70";
"RBT_ARB_IN":   PN = "OA4"  !CDS_PN = "OA4";
"RBT_ARB_OUT":   PN = "OA5"  !CDS_PN = "OA5";
"RBT_CLK_IN":   PN = "OA14"  !CDS_PN = "OA14";
"RBT_CRS_DV":   PN = "OB14"  !CDS_PN = "OB14";
"RBT_RXD0":   PN = "OB9"  !CDS_PN = "OB9";
"RBT_RXD1":   PN = "OB8"  !CDS_PN = "OB8";
"RBT_TX_EN":   PN = "OA7"  !CDS_PN = "OA7";
"RBT_TXD0":   PN = "OA9"  !CDS_PN = "OA9";
"RBT_TXD1":   PN = "OA8"  !CDS_PN = "OA8";
"REFCLKN0":   PN = "B14"  !CDS_PN = "B14";
"REFCLKN1":   PN = "A14"  !CDS_PN = "A14";
"REFCLKN2":   PN = "OB11"  !CDS_PN = "OB11";
"REFCLKN3":   PN = "OA11"  !CDS_PN = "OA11";
"REFCLKP0":   PN = "B15"  !CDS_PN = "B15";
"REFCLKP1":   PN = "A15"  !CDS_PN = "A15";
"REFCLKP2":   PN = "OB12"  !CDS_PN = "OB12";
"REFCLKP3":   PN = "OA12"  !CDS_PN = "OA12";
"RFU1_NC_B68":   PN = "B68"  !CDS_PN = "B68";
"RFU1_NC_B69":   PN = "B69"  !CDS_PN = "B69";
"SLOT_ID0":   PN = "OB7"  !CDS_PN = "OB7";
"SLOT_ID1":   PN = "OA6"  !CDS_PN = "OA6";
"SMCLK":   PN = "A7"  !CDS_PN = "A7";
"SMDAT":   PN = "A8"  !CDS_PN = "A8";
"SMRST#":   PN = "A9"  !CDS_PN = "A9";
"USB_DATN":   PN = "A68"  !CDS_PN = "A68";
"USB_DATP":   PN = "A69"  !CDS_PN = "A69";
"WAKE#":   PN = "OA3"  !CDS_PN = "OA3";
BODY = "Q_RES","I333": #LOCATION = "R3174" !CDS_LOCATION = "R3174" &SEC = "1" #&CDS_SEC = "1";
"A":   PN = "1"  !CDS_PN = "1";
"B":   PN = "2"  !CDS_PN = "2";
BODY = "Q_RES","I334": #LOCATION = "R3175" !CDS_LOCATION = "R3175" &SEC = "1" #&CDS_SEC = "1";
"A":   PN = "1"  !CDS_PN = "1";
"B":   PN = "2"  !CDS_PN = "2";
BODY = "Q_RES","I336": #LOCATION = "R3176" !CDS_LOCATION = "R3176" &SEC = "1" #&CDS_SEC = "1";
"A":   PN = "1"  !CDS_PN = "1";
"B":   PN = "2"  !CDS_PN = "2";
BODY = "Q_RES","I338": #LOCATION = "R3229" !CDS_LOCATION = "R3229" &SEC = "1" #&CDS_SEC = "1";
"A":   PN = "1"  !CDS_PN = "1";
"B":   PN = "2"  !CDS_PN = "2";
BODY = "Q_RES","I339": #LOCATION = "R3228" !CDS_LOCATION = "R3228" &SEC = "1" #&CDS_SEC = "1";
"A":   PN = "1"  !CDS_PN = "1";
"B":   PN = "2"  !CDS_PN = "2";
DRAWING = "@s9s_mb_2u_lib.s9s_mb_2u(sch_1):page156";
BODY = "Q_RES","I6": LOCATION = "R3182" #&CDS_LOCATION = "R3182" &SEC = "1" #&CDS_SEC = "1";
"A":   PN = "1"  !CDS_PN = "1";
"B":   PN = "2"  !CDS_PN = "2";
BODY = "Q_RES","I7": LOCATION = "R3183" #&CDS_LOCATION = "R3183" &SEC = "1" #&CDS_SEC = "1";
"A":   PN = "1"  !CDS_PN = "1";
"B":   PN = "2"  !CDS_PN = "2";
BODY = "Q_CAP","I12": LOCATION = "C1821" #&CDS_LOCATION = "C1821" &SEC = "1" #&CDS_SEC = "1";
"A":   PN = "1"  !CDS_PN = "1";
"B":   PN = "2"  !CDS_PN = "2";
BODY = "Q_RES","I24": LOCATION = "R3185" #&CDS_LOCATION = "R3185" &SEC = "1" #&CDS_SEC = "1";
"A":   PN = "1"  !CDS_PN = "1";
"B":   PN = "2"  !CDS_PN = "2";
BODY = "Q_CAP","I27": LOCATION = "C1822" #&CDS_LOCATION = "C1822" &SEC = "1" #&CDS_SEC = "1";
"A":   PN = "1"  !CDS_PN = "1";
"B":   PN = "2"  !CDS_PN = "2";
BODY = "Q_RES","I28": LOCATION = "R3184" #&CDS_LOCATION = "R3184" &SEC = "1" #&CDS_SEC = "1";
"A":   PN = "1"  !CDS_PN = "1";
"B":   PN = "2"  !CDS_PN = "2";
BODY = "74LVC1G07GV","I31": LOCATION = "U218" #&CDS_LOCATION = "U218" &SEC = "1" #&CDS_SEC = "1";
"A":   PN = "2"  !CDS_PN = "2";
"GND":   PN = "3"  !CDS_PN = "3";
"NC1":   PN = "1"  !CDS_PN = "1";
"VCC":   PN = "5"  !CDS_PN = "5";
"Y":   PN = "4"  !CDS_PN = "4";
BODY = "Q_CAP","I33": LOCATION = "C1823" #&CDS_LOCATION = "C1823" &SEC = "1" #&CDS_SEC = "1";
"A":   PN = "1"  !CDS_PN = "1";
"B":   PN = "2"  !CDS_PN = "2";
BODY = "74LVC1G17GW","I35": LOCATION = "U207" #&CDS_LOCATION = "U207" #SEC = "1" !CDS_SEC = "1";
"A":   PN = "2"  !CDS_PN = "2";
"GND":   PN = "3"  !CDS_PN = "3";
"NC":   PN = "1"  !CDS_PN = "1";
"VCC":   PN = "5"  !CDS_PN = "5";
"Y":   PN = "4"  !CDS_PN = "4";
BODY = "Q_RES","I38": LOCATION = "R3189" #&CDS_LOCATION = "R3189" &SEC = "1" #&CDS_SEC = "1";
"A":   PN = "1"  !CDS_PN = "1";
"B":   PN = "2"  !CDS_PN = "2";
BODY = "Q_RES","I39": LOCATION = "R3188" #&CDS_LOCATION = "R3188" &SEC = "1" #&CDS_SEC = "1";
"A":   PN = "1"  !CDS_PN = "1";
"B":   PN = "2"  !CDS_PN = "2";
BODY = "Q_RES","I40": LOCATION = "R3187" #&CDS_LOCATION = "R3187" &SEC = "1" #&CDS_SEC = "1";
"A":   PN = "1"  !CDS_PN = "1";
"B":   PN = "2"  !CDS_PN = "2";
BODY = "Q_RES","I41": LOCATION = "R3186" #&CDS_LOCATION = "R3186" &SEC = "1" #&CDS_SEC = "1";
"A":   PN = "1"  !CDS_PN = "1";
"B":   PN = "2"  !CDS_PN = "2";
BODY = "Q_RES","I42": LOCATION = "R3190" #&CDS_LOCATION = "R3190" &SEC = "1" #&CDS_SEC = "1";
"A":   PN = "1"  !CDS_PN = "1";
"B":   PN = "2"  !CDS_PN = "2";
BODY = "Q_RES","I44": LOCATION = "R3191" #&CDS_LOCATION = "R3191" &SEC = "1" #&CDS_SEC = "1";
"A":   PN = "1"  !CDS_PN = "1";
"B":   PN = "2"  !CDS_PN = "2";
BODY = "Q_CAP","I47": LOCATION = "C1824" #&CDS_LOCATION = "C1824" &SEC = "1" #&CDS_SEC = "1";
"A":   PN = "1"  !CDS_PN = "1";
"B":   PN = "2"  !CDS_PN = "2";
BODY = "Q_RES","I55": LOCATION = "R3193" #&CDS_LOCATION = "R3193" &SEC = "1" #&CDS_SEC = "1";
"A":   PN = "1"  !CDS_PN = "1";
"B":   PN = "2"  !CDS_PN = "2";
BODY = "Q_RES","I59": LOCATION = "R3192" #&CDS_LOCATION = "R3192" &SEC = "1" #&CDS_SEC = "1";
"A":   PN = "1"  !CDS_PN = "1";
"B":   PN = "2"  !CDS_PN = "2";
BODY = "74LVC1G07GV","I61": LOCATION = "U219" #&CDS_LOCATION = "U219" &SEC = "1" #&CDS_SEC = "1";
"A":   PN = "2"  !CDS_PN = "2";
"GND":   PN = "3"  !CDS_PN = "3";
"NC1":   PN = "1"  !CDS_PN = "1";
"VCC":   PN = "5"  !CDS_PN = "5";
"Y":   PN = "4"  !CDS_PN = "4";
BODY = "Q_CAP","I65": LOCATION = "C1841" #&CDS_LOCATION = "C1841" &SEC = "1" #&CDS_SEC = "1";
"A":   PN = "1"  !CDS_PN = "1";
"B":   PN = "2"  !CDS_PN = "2";
BODY = "Q_RES","I70": LOCATION = "R3236" #&CDS_LOCATION = "R3236" &SEC = "1" #&CDS_SEC = "1";
"A":   PN = "1"  !CDS_PN = "1";
"B":   PN = "2"  !CDS_PN = "2";
BODY = "Q_RES","I72": LOCATION = "R3235" #&CDS_LOCATION = "R3235" &SEC = "1" #&CDS_SEC = "1";
"A":   PN = "1"  !CDS_PN = "1";
"B":   PN = "2"  !CDS_PN = "2";
BODY = "74LVC1G126SE7","I74": #LOCATION = "U225" !CDS_LOCATION = "U225" &SEC = "1" #&CDS_SEC = "1";
"A":   PN = "2"  !CDS_PN = "2";
"GND":   PN = "3"  !CDS_PN = "3";
"OE":   PN = "1"  !CDS_PN = "1";
"VCC":   PN = "5"  !CDS_PN = "5";
"Y":   PN = "4"  !CDS_PN = "4";
BODY = "Q_RES","I75": LOCATION = "R3234" #&CDS_LOCATION = "R3234" &SEC = "1" #&CDS_SEC = "1";
"A":   PN = "1"  !CDS_PN = "1";
"B":   PN = "2"  !CDS_PN = "2";
BODY = "74LVC1G126SE7","I79": #LOCATION = "U217" !CDS_LOCATION = "U217" &SEC = "1" #&CDS_SEC = "1";
"A":   PN = "2"  !CDS_PN = "2";
"GND":   PN = "3"  !CDS_PN = "3";
"OE":   PN = "1"  !CDS_PN = "1";
"VCC":   PN = "5"  !CDS_PN = "5";
"Y":   PN = "4"  !CDS_PN = "4";
BODY = "Q_CAP","I81": LOCATION = "C2345" #&CDS_LOCATION = "C2345" &SEC = "1" #&CDS_SEC = "1";
"A":   PN = "1"  !CDS_PN = "1";
"B":   PN = "2"  !CDS_PN = "2";
BODY = "Q_RES","I90": LOCATION = "R4602" #&CDS_LOCATION = "R4602" &SEC = "1" #&CDS_SEC = "1";
"A":   PN = "1"  !CDS_PN = "1";
"B":   PN = "2"  !CDS_PN = "2";
BODY = "74LVC1G66GV","I92": #LOCATION = "U321" !CDS_LOCATION = "U321" &SEC = "1" #&CDS_SEC = "1";
"E":   PN = "4"  !CDS_PN = "4";
"GND":   PN = "3"  !CDS_PN = "3";
"VCC":   PN = "5"  !CDS_PN = "5";
"Y":   PN = "1"  !CDS_PN = "1";
"Z":   PN = "2"  !CDS_PN = "2";
DRAWING = "@s9s_mb_2u_lib.s9s_mb_2u(sch_1):page307";
BODY = "Q_RES","I12": LOCATION = "R3206" #&CDS_LOCATION = "R3206" &SEC = "1" #&CDS_SEC = "1";
"A":   PN = "1"  !CDS_PN = "1";
"B":   PN = "2"  !CDS_PN = "2";
BODY = "Q_RES","I15": LOCATION = "R3207" #&CDS_LOCATION = "R3207" &SEC = "1" #&CDS_SEC = "1";
"A":   PN = "1"  !CDS_PN = "1";
"B":   PN = "2"  !CDS_PN = "2";
BODY = "Q_CAP","I17": LOCATION = "C1825" #&CDS_LOCATION = "C1825" &SEC = "1" #&CDS_SEC = "1";
"A":   PN = "1"  !CDS_PN = "1";
"B":   PN = "2"  !CDS_PN = "2";
BODY = "74CBTLV3126PW","I32": LOCATION = "U222" #&CDS_LOCATION = "U222" &SEC = "1" #&CDS_SEC = "1";
"1A":   PN = "2"  !CDS_PN = "2";
"1B":   PN = "3"  !CDS_PN = "3";
"1OE":   PN = "1"  !CDS_PN = "1";
"2A":   PN = "5"  !CDS_PN = "5";
"2B":   PN = "6"  !CDS_PN = "6";
"2OE":   PN = "4"  !CDS_PN = "4";
"3A":   PN = "9"  !CDS_PN = "9";
"3B":   PN = "8"  !CDS_PN = "8";
"3OE":   PN = "10"  !CDS_PN = "10";
"4A":   PN = "12"  !CDS_PN = "12";
"4B":   PN = "11"  !CDS_PN = "11";
"4OE":   PN = "13"  !CDS_PN = "13";
"GND":   PN = "7"  !CDS_PN = "7";
"VCC":   PN = "14"  !CDS_PN = "14";
BODY = "Q_CAP","I33": LOCATION = "C1826" #&CDS_LOCATION = "C1826" &SEC = "1" #&CDS_SEC = "1";
"A":   PN = "1"  !CDS_PN = "1";
"B":   PN = "2"  !CDS_PN = "2";
BODY = "Q_RES","I37": LOCATION = "R3208" #&CDS_LOCATION = "R3208" &SEC = "1" #&CDS_SEC = "1";
"A":   PN = "1"  !CDS_PN = "1";
"B":   PN = "2"  !CDS_PN = "2";
BODY = "Q_RES","I38": LOCATION = "R3216" #&CDS_LOCATION = "R3216" &SEC = "1" #&CDS_SEC = "1";
"A":   PN = "1"  !CDS_PN = "1";
"B":   PN = "2"  !CDS_PN = "2";
BODY = "Q_RES","I40": LOCATION = "R3217" #&CDS_LOCATION = "R3217" &SEC = "1" #&CDS_SEC = "1";
"A":   PN = "1"  !CDS_PN = "1";
"B":   PN = "2"  !CDS_PN = "2";
BODY = "Q_RES","I56": LOCATION = "R3215" #&CDS_LOCATION = "R3215" &SEC = "1" #&CDS_SEC = "1";
"A":   PN = "1"  !CDS_PN = "1";
"B":   PN = "2"  !CDS_PN = "2";
BODY = "Q_RES","I60": LOCATION = "R3214" #&CDS_LOCATION = "R3214" &SEC = "1" #&CDS_SEC = "1";
"A":   PN = "1"  !CDS_PN = "1";
"B":   PN = "2"  !CDS_PN = "2";
BODY = "Q_RES","I61": LOCATION = "R3213" #&CDS_LOCATION = "R3213" &SEC = "1" #&CDS_SEC = "1";
"A":   PN = "1"  !CDS_PN = "1";
"B":   PN = "2"  !CDS_PN = "2";
BODY = "Q_RES","I62": LOCATION = "R3212" #&CDS_LOCATION = "R3212" &SEC = "1" #&CDS_SEC = "1";
"A":   PN = "1"  !CDS_PN = "1";
"B":   PN = "2"  !CDS_PN = "2";
BODY = "Q_RES","I63": LOCATION = "R3211" #&CDS_LOCATION = "R3211" &SEC = "1" #&CDS_SEC = "1";
"A":   PN = "1"  !CDS_PN = "1";
"B":   PN = "2"  !CDS_PN = "2";
BODY = "Q_RES","I64": LOCATION = "R3209" #&CDS_LOCATION = "R3209" &SEC = "1" #&CDS_SEC = "1";
"A":   PN = "1"  !CDS_PN = "1";
"B":   PN = "2"  !CDS_PN = "2";
BODY = "Q_RES","I65": LOCATION = "R3210" #&CDS_LOCATION = "R3210" &SEC = "1" #&CDS_SEC = "1";
"A":   PN = "1"  !CDS_PN = "1";
"B":   PN = "2"  !CDS_PN = "2";
BODY = "Q_CAP","I77": LOCATION = "C1827" #&CDS_LOCATION = "C1827" &SEC = "1" #&CDS_SEC = "1";
"A":   PN = "1"  !CDS_PN = "1";
"B":   PN = "2"  !CDS_PN = "2";
BODY = "74CBTLV3126PW","I78": LOCATION = "U223" #&CDS_LOCATION = "U223" &SEC = "1" #&CDS_SEC = "1";
"1A":   PN = "2"  !CDS_PN = "2";
"1B":   PN = "3"  !CDS_PN = "3";
"1OE":   PN = "1"  !CDS_PN = "1";
"2A":   PN = "5"  !CDS_PN = "5";
"2B":   PN = "6"  !CDS_PN = "6";
"2OE":   PN = "4"  !CDS_PN = "4";
"3A":   PN = "9"  !CDS_PN = "9";
"3B":   PN = "8"  !CDS_PN = "8";
"3OE":   PN = "10"  !CDS_PN = "10";
"4A":   PN = "12"  !CDS_PN = "12";
"4B":   PN = "11"  !CDS_PN = "11";
"4OE":   PN = "13"  !CDS_PN = "13";
"GND":   PN = "7"  !CDS_PN = "7";
"VCC":   PN = "14"  !CDS_PN = "14";
BODY = "Q_RES","I79": LOCATION = "R3244" #&CDS_LOCATION = "R3244" &SEC = "1" #&CDS_SEC = "1";
"A":   PN = "1"  !CDS_PN = "1";
"B":   PN = "2"  !CDS_PN = "2";
BODY = "74LVC1G126SE7","I80": LOCATION = "U286" #&CDS_LOCATION = "U286" &SEC = "1" #&CDS_SEC = "1";
"A":   PN = "2"  !CDS_PN = "2";
"GND":   PN = "3"  !CDS_PN = "3";
"OE":   PN = "1"  !CDS_PN = "1";
"VCC":   PN = "5"  !CDS_PN = "5";
"Y":   PN = "4"  !CDS_PN = "4";
BODY = "Q_RES","I81": LOCATION = "R3203" #&CDS_LOCATION = "R3203" &SEC = "1" #&CDS_SEC = "1";
"A":   PN = "1"  !CDS_PN = "1";
"B":   PN = "2"  !CDS_PN = "2";
BODY = "Q_RES","I85": #LOCATION = "R3205" !CDS_LOCATION = "R3205" &SEC = "1" #&CDS_SEC = "1";
"A":   PN = "1"  !CDS_PN = "1";
"B":   PN = "2"  !CDS_PN = "2";
DRAWING = "@s9s_mb_2u_lib.s9s_mb_2u(sch_1):page216";
BODY = "PCA9617ADP","I5": LOCATION = "U235" #&CDS_LOCATION = "U235" &SEC = "1" #&CDS_SEC = "1";
"EN":   PN = "5"  !CDS_PN = "5";
"GND":   PN = "4"  !CDS_PN = "4";
"SCLA":   PN = "2"  !CDS_PN = "2";
"SCLB":   PN = "7"  !CDS_PN = "7";
"SDAA":   PN = "3"  !CDS_PN = "3";
"SDAB":   PN = "6"  !CDS_PN = "6";
"VCCA":   PN = "1"  !CDS_PN = "1";
"VCCB":   PN = "8"  !CDS_PN = "8";
BODY = "Q_RES","I7": LOCATION = "R3264" #&CDS_LOCATION = "R3264" &SEC = "1" #&CDS_SEC = "1";
"A":   PN = "1"  !CDS_PN = "1";
"B":   PN = "2"  !CDS_PN = "2";
BODY = "Q_CAP","I10": LOCATION = "C1859" #&CDS_LOCATION = "C1859" &SEC = "1" #&CDS_SEC = "1";
"A":   PN = "1"  !CDS_PN = "1";
"B":   PN = "2"  !CDS_PN = "2";
BODY = "Q_CAP","I11": LOCATION = "C1861" #&CDS_LOCATION = "C1861" &SEC = "1" #&CDS_SEC = "1";
"A":   PN = "1"  !CDS_PN = "1";
"B":   PN = "2"  !CDS_PN = "2";
BODY = "Q_CAP","I17": LOCATION = "C1860" #&CDS_LOCATION = "C1860" &SEC = "1" #&CDS_SEC = "1";
"A":   PN = "1"  !CDS_PN = "1";
"B":   PN = "2"  !CDS_PN = "2";
BODY = "Q_RES","I21": LOCATION = "R3263" #&CDS_LOCATION = "R3263" &SEC = "1" #&CDS_SEC = "1";
"A":   PN = "1"  !CDS_PN = "1";
"B":   PN = "2"  !CDS_PN = "2";
BODY = "Q_CAP","I23": LOCATION = "C1862" #&CDS_LOCATION = "C1862" &SEC = "1" #&CDS_SEC = "1";
"A":   PN = "1"  !CDS_PN = "1";
"B":   PN = "2"  !CDS_PN = "2";
BODY = "PCA9617ADP","I28": LOCATION = "U236" #&CDS_LOCATION = "U236" &SEC = "1" #&CDS_SEC = "1";
"EN":   PN = "5"  !CDS_PN = "5";
"GND":   PN = "4"  !CDS_PN = "4";
"SCLA":   PN = "2"  !CDS_PN = "2";
"SCLB":   PN = "7"  !CDS_PN = "7";
"SDAA":   PN = "3"  !CDS_PN = "3";
"SDAB":   PN = "6"  !CDS_PN = "6";
"VCCA":   PN = "1"  !CDS_PN = "1";
"VCCB":   PN = "8"  !CDS_PN = "8";
BODY = "Q_RES","I30": LOCATION = "R3501" #&CDS_LOCATION = "R3501" &SEC = "1" #&CDS_SEC = "1";
"A":   PN = "1"  !CDS_PN = "1";
"B":   PN = "2"  !CDS_PN = "2";
BODY = "Q_RES","I31": LOCATION = "R3500" #&CDS_LOCATION = "R3500" &SEC = "1" #&CDS_SEC = "1";
"A":   PN = "1"  !CDS_PN = "1";
"B":   PN = "2"  !CDS_PN = "2";
BODY = "Q_RES","I33": LOCATION = "R3520" #&CDS_LOCATION = "R3520" &SEC = "1" #&CDS_SEC = "1";
"A":   PN = "1"  !CDS_PN = "1";
"B":   PN = "2"  !CDS_PN = "2";
BODY = "Q_RES","I34": LOCATION = "R3519" #&CDS_LOCATION = "R3519" &SEC = "1" #&CDS_SEC = "1";
"A":   PN = "1"  !CDS_PN = "1";
"B":   PN = "2"  !CDS_PN = "2";
DRAWING = "@s9s_mb_2u_lib.s9s_mb_2u(sch_1):page136";
BODY = "Q_RES","I16": LOCATION = "R3277" #&CDS_LOCATION = "R3277" &SEC = "1" #&CDS_SEC = "1";
"A":   PN = "1"  !CDS_PN = "1";
"B":   PN = "2"  !CDS_PN = "2";
BODY = "Q_RES","I23": LOCATION = "R3279" #&CDS_LOCATION = "R3279" &SEC = "1" #&CDS_SEC = "1";
"A":   PN = "1"  !CDS_PN = "1";
"B":   PN = "2"  !CDS_PN = "2";
BODY = "Q_RES","I25": LOCATION = "R3281" #&CDS_LOCATION = "R3281" &SEC = "1" #&CDS_SEC = "1";
"A":   PN = "1"  !CDS_PN = "1";
"B":   PN = "2"  !CDS_PN = "2";
BODY = "Q_CAP","I48": LOCATION = "C1867" #&CDS_LOCATION = "C1867" &SEC = "1" #&CDS_SEC = "1";
"A":   PN = "1"  !CDS_PN = "1";
"B":   PN = "2"  !CDS_PN = "2";
BODY = "Q_RES","I68": LOCATION = "R3290" #&CDS_LOCATION = "R3290" &SEC = "1" #&CDS_SEC = "1";
"A":   PN = "1"  !CDS_PN = "1";
"B":   PN = "2"  !CDS_PN = "2";
BODY = "Q_RES","I69": LOCATION = "R3289" #&CDS_LOCATION = "R3289" &SEC = "1" #&CDS_SEC = "1";
"A":   PN = "1"  !CDS_PN = "1";
"B":   PN = "2"  !CDS_PN = "2";
BODY = "Q_RES","I73": LOCATION = "R4537" #&CDS_LOCATION = "R4537" &SEC = "1" #&CDS_SEC = "1";
"A":   PN = "1"  !CDS_PN = "1";
"B":   PN = "2"  !CDS_PN = "2";
BODY = "Q_RES","I88": LOCATION = "R3293" #&CDS_LOCATION = "R3293" &SEC = "1" #&CDS_SEC = "1";
"A":   PN = "1"  !CDS_PN = "1";
"B":   PN = "2"  !CDS_PN = "2";
BODY = "Q_RES","I2": LOCATION = "R3268" #&CDS_LOCATION = "R3268" &SEC = "1" #&CDS_SEC = "1";
"A":   PN = "1"  !CDS_PN = "1";
"B":   PN = "2"  !CDS_PN = "2";
BODY = "Q_RES","I4": LOCATION = "R3272" #&CDS_LOCATION = "R3272" &SEC = "1" #&CDS_SEC = "1";
"A":   PN = "1"  !CDS_PN = "1";
"B":   PN = "2"  !CDS_PN = "2";
BODY = "Q_RES","I6": LOCATION = "R3274" #&CDS_LOCATION = "R3274" &SEC = "1" #&CDS_SEC = "1";
"A":   PN = "1"  !CDS_PN = "1";
"B":   PN = "2"  !CDS_PN = "2";
BODY = "Q_RES","I8": LOCATION = "R3278" #&CDS_LOCATION = "R3278" &SEC = "1" #&CDS_SEC = "1";
"A":   PN = "1"  !CDS_PN = "1";
"B":   PN = "2"  !CDS_PN = "2";
BODY = "Q_RES","I9": LOCATION = "R3271" #&CDS_LOCATION = "R3271" &SEC = "1" #&CDS_SEC = "1";
"A":   PN = "1"  !CDS_PN = "1";
"B":   PN = "2"  !CDS_PN = "2";
BODY = "Q_RES","I12": LOCATION = "R3267" #&CDS_LOCATION = "R3267" &SEC = "1" #&CDS_SEC = "1";
"A":   PN = "1"  !CDS_PN = "1";
"B":   PN = "2"  !CDS_PN = "2";
BODY = "Q_RES","I14": LOCATION = "R3270" #&CDS_LOCATION = "R3270" &SEC = "1" #&CDS_SEC = "1";
"A":   PN = "1"  !CDS_PN = "1";
"B":   PN = "2"  !CDS_PN = "2";
BODY = "Q_RES","I15": LOCATION = "R3269" #&CDS_LOCATION = "R3269" &SEC = "1" #&CDS_SEC = "1";
"A":   PN = "1"  !CDS_PN = "1";
"B":   PN = "2"  !CDS_PN = "2";
BODY = "Q_RES","I18": LOCATION = "R3273" #&CDS_LOCATION = "R3273" &SEC = "1" #&CDS_SEC = "1";
"A":   PN = "1"  !CDS_PN = "1";
"B":   PN = "2"  !CDS_PN = "2";
BODY = "Q_RES","I20": LOCATION = "R3276" #&CDS_LOCATION = "R3276" &SEC = "1" #&CDS_SEC = "1";
"A":   PN = "1"  !CDS_PN = "1";
"B":   PN = "2"  !CDS_PN = "2";
BODY = "Q_RES","I21": LOCATION = "R3275" #&CDS_LOCATION = "R3275" &SEC = "1" #&CDS_SEC = "1";
"A":   PN = "1"  !CDS_PN = "1";
"B":   PN = "2"  !CDS_PN = "2";
BODY = "Q_RES","I27": LOCATION = "R3282" #&CDS_LOCATION = "R3282" &SEC = "1" #&CDS_SEC = "1";
"A":   PN = "1"  !CDS_PN = "1";
"B":   PN = "2"  !CDS_PN = "2";
BODY = "Q_RES","I32": LOCATION = "R3280" #&CDS_LOCATION = "R3280" &SEC = "1" #&CDS_SEC = "1";
"A":   PN = "1"  !CDS_PN = "1";
"B":   PN = "2"  !CDS_PN = "2";
BODY = "Q_CAP","I49": LOCATION = "C1863" #&CDS_LOCATION = "C1863" &SEC = "1" #&CDS_SEC = "1";
"A":   PN = "1"  !CDS_PN = "1";
"B":   PN = "2"  !CDS_PN = "2";
BODY = "PI3EQX12902AZLEX","I50": LOCATION = "U237" #&CDS_LOCATION = "U237" &SEC = "1" #&CDS_SEC = "1";
"AIN":   PN = "3"  !CDS_PN = "3";
"AIP":   PN = "2"  !CDS_PN = "2";
"AON":   PN = "23"  !CDS_PN = "23";
"AOP":   PN = "24"  !CDS_PN = "24";
"BIN":   PN = "18"  !CDS_PN = "18";
"BIP":   PN = "17"  !CDS_PN = "17";
"BON":   PN = "8"  !CDS_PN = "8";
"BOP":   PN = "9"  !CDS_PN = "9";
"EN#":   PN = "11"  !CDS_PN = "11";
"EQA0":   PN = "21"  !CDS_PN = "21";
"EQA1":   PN = "26"  !CDS_PN = "26";
"EQB0":   PN = "20"  !CDS_PN = "20";
"EQB1":   PN = "15"  !CDS_PN = "15";
"FGA":   PN = "27"  !CDS_PN = "27";
"FGB":   PN = "14"  !CDS_PN = "14";
"GND1":   PN = "4"  !CDS_PN = "4";
"GND2":   PN = "6"  !CDS_PN = "6";
"GND3":   PN = "7"  !CDS_PN = "7";
"GND4":   PN = "13"  !CDS_PN = "13";
"GND5":   PN = "19"  !CDS_PN = "19";
"GND6":   PN = "22"  !CDS_PN = "22";
"GND7":   PN = "28"  !CDS_PN = "28";
"GND_TH":   PN = "TH"  !CDS_PN = "TH";
"MODE":   PN = "30"  !CDS_PN = "30";
"SWA":   PN = "29"  !CDS_PN = "29";
"SWB":   PN = "12"  !CDS_PN = "12";
"TEST#":   PN = "5"  !CDS_PN = "5";
"VDD1":   PN = "1"  !CDS_PN = "1";
"VDD2":   PN = "10"  !CDS_PN = "10";
"VDD3":   PN = "16"  !CDS_PN = "16";
"VDD4":   PN = "25"  !CDS_PN = "25";
BODY = "Q_CAP","I51": LOCATION = "C1864" #&CDS_LOCATION = "C1864" &SEC = "1" #&CDS_SEC = "1";
"A":   PN = "1"  !CDS_PN = "1";
"B":   PN = "2"  !CDS_PN = "2";
BODY = "Q_CAP","I52": LOCATION = "C1865" #&CDS_LOCATION = "C1865" &SEC = "1" #&CDS_SEC = "1";
"A":   PN = "1"  !CDS_PN = "1";
"B":   PN = "2"  !CDS_PN = "2";
BODY = "Q_CAP","I53": LOCATION = "C1866" #&CDS_LOCATION = "C1866" &SEC = "1" #&CDS_SEC = "1";
"A":   PN = "1"  !CDS_PN = "1";
"B":   PN = "2"  !CDS_PN = "2";
BODY = "Q_RES","I56": LOCATION = "R3284" #&CDS_LOCATION = "R3284" &SEC = "1" #&CDS_SEC = "1";
"A":   PN = "1"  !CDS_PN = "1";
"B":   PN = "2"  !CDS_PN = "2";
BODY = "Q_RES","I57": LOCATION = "R3283" #&CDS_LOCATION = "R3283" &SEC = "1" #&CDS_SEC = "1";
"A":   PN = "1"  !CDS_PN = "1";
"B":   PN = "2"  !CDS_PN = "2";
BODY = "Q_RES","I61": LOCATION = "R3285" #&CDS_LOCATION = "R3285" &SEC = "1" #&CDS_SEC = "1";
"A":   PN = "1"  !CDS_PN = "1";
"B":   PN = "2"  !CDS_PN = "2";
BODY = "Q_RES","I63": LOCATION = "R3287" #&CDS_LOCATION = "R3287" &SEC = "1" #&CDS_SEC = "1";
"A":   PN = "1"  !CDS_PN = "1";
"B":   PN = "2"  !CDS_PN = "2";
BODY = "Q_RES","I64": LOCATION = "R3286" #&CDS_LOCATION = "R3286" &SEC = "1" #&CDS_SEC = "1";
"A":   PN = "1"  !CDS_PN = "1";
"B":   PN = "2"  !CDS_PN = "2";
BODY = "Q_RES","I66": LOCATION = "R3288" #&CDS_LOCATION = "R3288" &SEC = "1" #&CDS_SEC = "1";
"A":   PN = "1"  !CDS_PN = "1";
"B":   PN = "2"  !CDS_PN = "2";
BODY = "Q_RES","I82": LOCATION = "R3291" #&CDS_LOCATION = "R3291" &SEC = "1" #&CDS_SEC = "1";
"A":   PN = "1"  !CDS_PN = "1";
"B":   PN = "2"  !CDS_PN = "2";
BODY = "Q_RES","I84": LOCATION = "R3265" #&CDS_LOCATION = "R3265" &SEC = "1" #&CDS_SEC = "1";
"A":   PN = "1"  !CDS_PN = "1";
"B":   PN = "2"  !CDS_PN = "2";
BODY = "Q_RES","I85": LOCATION = "R3292" #&CDS_LOCATION = "R3292" &SEC = "1" #&CDS_SEC = "1";
"A":   PN = "1"  !CDS_PN = "1";
"B":   PN = "2"  !CDS_PN = "2";
BODY = "Q_RES","I89": LOCATION = "R3266" #&CDS_LOCATION = "R3266" &SEC = "1" #&CDS_SEC = "1";
"A":   PN = "1"  !CDS_PN = "1";
"B":   PN = "2"  !CDS_PN = "2";
DRAWING = "@s9s_mb_2u_lib.s9s_mb_2u(sch_1):page170";
BODY = "74LVC2G08DP","I1": LOCATION = "U241" #&CDS_LOCATION = "U241" &SEC = "1" #&CDS_SEC = "1";
"1A":   PN = "1"  !CDS_PN = "1";
"1B":   PN = "2"  !CDS_PN = "2";
"1Y":   PN = "7"  !CDS_PN = "7";
"GND":   PN = "4"  !CDS_PN = "4";
"VCC":   PN = "8"  !CDS_PN = "8";
BODY = "74LVC2G08DP","I2": LOCATION = "U241" #&CDS_LOCATION = "U241" &SEC = "2" #&CDS_SEC = "2";
"2A":   PN = "5"  !CDS_PN = "5";
"2B":   PN = "6"  !CDS_PN = "6";
"2Y":   PN = "3"  !CDS_PN = "3";
BODY = "74LVC2G08DP","I11": LOCATION = "U240" #&CDS_LOCATION = "U240" &SEC = "1" #&CDS_SEC = "1";
"1A":   PN = "1"  !CDS_PN = "1";
"1B":   PN = "2"  !CDS_PN = "2";
"1Y":   PN = "7"  !CDS_PN = "7";
"GND":   PN = "4"  !CDS_PN = "4";
"VCC":   PN = "8"  !CDS_PN = "8";
BODY = "74LVC2G08DP","I12": LOCATION = "U240" #&CDS_LOCATION = "U240" &SEC = "2" #&CDS_SEC = "2";
"2A":   PN = "5"  !CDS_PN = "5";
"2B":   PN = "6"  !CDS_PN = "6";
"2Y":   PN = "3"  !CDS_PN = "3";
BODY = "74LVC2G08DP","I13": LOCATION = "U242" #&CDS_LOCATION = "U242" &SEC = "1" #&CDS_SEC = "1";
"1A":   PN = "1"  !CDS_PN = "1";
"1B":   PN = "2"  !CDS_PN = "2";
"1Y":   PN = "7"  !CDS_PN = "7";
"GND":   PN = "4"  !CDS_PN = "4";
"VCC":   PN = "8"  !CDS_PN = "8";
BODY = "74LVC2G08DP","I14": LOCATION = "U242" #&CDS_LOCATION = "U242" &SEC = "2" #&CDS_SEC = "2";
"2A":   PN = "5"  !CDS_PN = "5";
"2B":   PN = "6"  !CDS_PN = "6";
"2Y":   PN = "3"  !CDS_PN = "3";
BODY = "NC7SB3157","I15": LOCATION = "U243" #&CDS_LOCATION = "U243" &SEC = "1" #&CDS_SEC = "1";
"A":   PN = "4"  !CDS_PN = "4";
"B0":   PN = "3"  !CDS_PN = "3";
"B1":   PN = "1"  !CDS_PN = "1";
"GND":   PN = "2"  !CDS_PN = "2";
"S":   PN = "6"  !CDS_PN = "6";
"VCC":   PN = "5"  !CDS_PN = "5";
BODY = "NC7SB3157","I16": LOCATION = "U244" #&CDS_LOCATION = "U244" &SEC = "1" #&CDS_SEC = "1";
"A":   PN = "4"  !CDS_PN = "4";
"B0":   PN = "3"  !CDS_PN = "3";
"B1":   PN = "1"  !CDS_PN = "1";
"GND":   PN = "2"  !CDS_PN = "2";
"S":   PN = "6"  !CDS_PN = "6";
"VCC":   PN = "5"  !CDS_PN = "5";
BODY = "NC7SB3157","I17": LOCATION = "U246" #&CDS_LOCATION = "U246" &SEC = "1" #&CDS_SEC = "1";
"A":   PN = "4"  !CDS_PN = "4";
"B0":   PN = "3"  !CDS_PN = "3";
"B1":   PN = "1"  !CDS_PN = "1";
"GND":   PN = "2"  !CDS_PN = "2";
"S":   PN = "6"  !CDS_PN = "6";
"VCC":   PN = "5"  !CDS_PN = "5";
BODY = "NC7SB3157","I18": LOCATION = "U245" #&CDS_LOCATION = "U245" &SEC = "1" #&CDS_SEC = "1";
"A":   PN = "4"  !CDS_PN = "4";
"B0":   PN = "3"  !CDS_PN = "3";
"B1":   PN = "1"  !CDS_PN = "1";
"GND":   PN = "2"  !CDS_PN = "2";
"S":   PN = "6"  !CDS_PN = "6";
"VCC":   PN = "5"  !CDS_PN = "5";
BODY = "Q_CAP","I21": LOCATION = "C1875" #&CDS_LOCATION = "C1875" &SEC = "1" #&CDS_SEC = "1";
"A":   PN = "1"  !CDS_PN = "1";
"B":   PN = "2"  !CDS_PN = "2";
BODY = "Q_CAP","I22": LOCATION = "C1874" #&CDS_LOCATION = "C1874" &SEC = "1" #&CDS_SEC = "1";
"A":   PN = "1"  !CDS_PN = "1";
"B":   PN = "2"  !CDS_PN = "2";
BODY = "Q_CAP","I27": LOCATION = "C1880" #&CDS_LOCATION = "C1880" &SEC = "1" #&CDS_SEC = "1";
"A":   PN = "1"  !CDS_PN = "1";
"B":   PN = "2"  !CDS_PN = "2";
BODY = "Q_CAP","I31": LOCATION = "C1879" #&CDS_LOCATION = "C1879" &SEC = "1" #&CDS_SEC = "1";
"A":   PN = "1"  !CDS_PN = "1";
"B":   PN = "2"  !CDS_PN = "2";
BODY = "Q_CAP","I34": LOCATION = "C1877" #&CDS_LOCATION = "C1877" &SEC = "1" #&CDS_SEC = "1";
"A":   PN = "1"  !CDS_PN = "1";
"B":   PN = "2"  !CDS_PN = "2";
BODY = "Q_CAP","I37": LOCATION = "C1878" #&CDS_LOCATION = "C1878" &SEC = "1" #&CDS_SEC = "1";
"A":   PN = "1"  !CDS_PN = "1";
"B":   PN = "2"  !CDS_PN = "2";
BODY = "Q_CAP","I41": LOCATION = "C1876" #&CDS_LOCATION = "C1876" &SEC = "1" #&CDS_SEC = "1";
"A":   PN = "1"  !CDS_PN = "1";
"B":   PN = "2"  !CDS_PN = "2";
BODY = "Q_RES","I44": LOCATION = "R3303" #&CDS_LOCATION = "R3303" &SEC = "1" #&CDS_SEC = "1";
"A":   PN = "1"  !CDS_PN = "1";
"B":   PN = "2"  !CDS_PN = "2";
BODY = "Q_RES","I45": LOCATION = "R3304" #&CDS_LOCATION = "R3304" &SEC = "1" #&CDS_SEC = "1";
"A":   PN = "1"  !CDS_PN = "1";
"B":   PN = "2"  !CDS_PN = "2";
BODY = "Q_RES","I46": LOCATION = "R3308" #&CDS_LOCATION = "R3308" &SEC = "1" #&CDS_SEC = "1";
"A":   PN = "1"  !CDS_PN = "1";
"B":   PN = "2"  !CDS_PN = "2";
BODY = "Q_RES","I47": LOCATION = "R3306" #&CDS_LOCATION = "R3306" &SEC = "1" #&CDS_SEC = "1";
"A":   PN = "1"  !CDS_PN = "1";
"B":   PN = "2"  !CDS_PN = "2";
BODY = "Q_RES","I50": LOCATION = "R3305" #&CDS_LOCATION = "R3305" &SEC = "1" #&CDS_SEC = "1";
"A":   PN = "1"  !CDS_PN = "1";
"B":   PN = "2"  !CDS_PN = "2";
BODY = "Q_RES","I52": LOCATION = "R3307" #&CDS_LOCATION = "R3307" &SEC = "1" #&CDS_SEC = "1";
"A":   PN = "1"  !CDS_PN = "1";
"B":   PN = "2"  !CDS_PN = "2";
DRAWING = "@s9s_mb_2u_lib.s9s_mb_2u(sch_1):page189";
BODY = "Q_RES","I86": LOCATION = "R2133" #&CDS_LOCATION = "R2133" &SEC = "1" #&CDS_SEC = "1";
"A":   PN = "1"  !CDS_PN = "1";
"B":   PN = "2"  !CDS_PN = "2";
BODY = "Q_RES","I87": LOCATION = "R1324" #&CDS_LOCATION = "R1324" &SEC = "1" #&CDS_SEC = "1";
"A":   PN = "1"  !CDS_PN = "1";
"B":   PN = "2"  !CDS_PN = "2";
BODY = "Q_RES","I88": LOCATION = "R1317" #&CDS_LOCATION = "R1317" &SEC = "1" #&CDS_SEC = "1";
"A":   PN = "1"  !CDS_PN = "1";
"B":   PN = "2"  !CDS_PN = "2";
BODY = "Q_RES","I89": LOCATION = "R1320" #&CDS_LOCATION = "R1320" &SEC = "1" #&CDS_SEC = "1";
"A":   PN = "1"  !CDS_PN = "1";
"B":   PN = "2"  !CDS_PN = "2";
BODY = "Q_RES","I93": LOCATION = "R1325" #&CDS_LOCATION = "R1325" &SEC = "1" #&CDS_SEC = "1";
"A":   PN = "1"  !CDS_PN = "1";
"B":   PN = "2"  !CDS_PN = "2";
BODY = "Q_RES","I100": LOCATION = "R1339" #&CDS_LOCATION = "R1339" &SEC = "1" #&CDS_SEC = "1";
"A":   PN = "1"  !CDS_PN = "1";
"B":   PN = "2"  !CDS_PN = "2";
BODY = "Q_RES","I106": LOCATION = "R1341" #&CDS_LOCATION = "R1341" &SEC = "1" #&CDS_SEC = "1";
"A":   PN = "1"  !CDS_PN = "1";
"B":   PN = "2"  !CDS_PN = "2";
BODY = "Q_RES","I107": LOCATION = "R1338" #&CDS_LOCATION = "R1338" &SEC = "1" #&CDS_SEC = "1";
"A":   PN = "1"  !CDS_PN = "1";
"B":   PN = "2"  !CDS_PN = "2";
BODY = "Q_RES","I109": LOCATION = "R2134" #&CDS_LOCATION = "R2134" &SEC = "1" #&CDS_SEC = "1";
"A":   PN = "1"  !CDS_PN = "1";
"B":   PN = "2"  !CDS_PN = "2";
BODY = "Q_RES","I113": LOCATION = "R1343" #&CDS_LOCATION = "R1343" &SEC = "1" #&CDS_SEC = "1";
"A":   PN = "1"  !CDS_PN = "1";
"B":   PN = "2"  !CDS_PN = "2";
BODY = "Q_RES","I114": LOCATION = "R1342" #&CDS_LOCATION = "R1342" &SEC = "1" #&CDS_SEC = "1";
"A":   PN = "1"  !CDS_PN = "1";
"B":   PN = "2"  !CDS_PN = "2";
BODY = "SW_PUSHBUTTON4P_24","I122": LOCATION = "SW5" #&CDS_LOCATION = "SW5" &SEC = "1" #&CDS_SEC = "1";
"1":   PN = "1"  !CDS_PN = "1";
"2":   PN = "2"  !CDS_PN = "2";
"3":   PN = "3"  !CDS_PN = "3";
"4":   PN = "4"  !CDS_PN = "4";
BODY = "Q_RES","I123": LOCATION = "R1333" #&CDS_LOCATION = "R1333" &SEC = "1" #&CDS_SEC = "1";
"A":   PN = "1"  !CDS_PN = "1";
"B":   PN = "2"  !CDS_PN = "2";
BODY = "Q_RES","I127": LOCATION = "R1340" #&CDS_LOCATION = "R1340" &SEC = "1" #&CDS_SEC = "1";
"A":   PN = "1"  !CDS_PN = "1";
"B":   PN = "2"  !CDS_PN = "2";
BODY = "Q_CAP","I128": LOCATION = "C1177" #&CDS_LOCATION = "C1177" &SEC = "1" #&CDS_SEC = "1";
"A":   PN = "1"  !CDS_PN = "1";
"B":   PN = "2"  !CDS_PN = "2";
BODY = "Q_RES","I132": LOCATION = "R3039" #&CDS_LOCATION = "R3039" &SEC = "1" #&CDS_SEC = "1";
"A":   PN = "1"  !CDS_PN = "1";
"B":   PN = "2"  !CDS_PN = "2";
BODY = "Q_RES","I133": LOCATION = "R1335" #&CDS_LOCATION = "R1335" &SEC = "1" #&CDS_SEC = "1";
"A":   PN = "1"  !CDS_PN = "1";
"B":   PN = "2"  !CDS_PN = "2";
BODY = "CONN14_210HP207GBR1","I134": #LOCATION = "J104" !CDS_LOCATION = "J104" &SEC = "1" #&CDS_SEC = "1";
"1":   PN = "1"  !CDS_PN = "1";
"2":   PN = "2"  !CDS_PN = "2";
"3":   PN = "3"  !CDS_PN = "3";
"4":   PN = "4"  !CDS_PN = "4";
"5":   PN = "5"  !CDS_PN = "5";
"6":   PN = "6"  !CDS_PN = "6";
"7":   PN = "7"  !CDS_PN = "7";
"8":   PN = "8"  !CDS_PN = "8";
"9":   PN = "9"  !CDS_PN = "9";
"10":   PN = "10"  !CDS_PN = "10";
"11":   PN = "11"  !CDS_PN = "11";
"12":   PN = "12"  !CDS_PN = "12";
"13":   PN = "13"  !CDS_PN = "13";
"14":   PN = "14"  !CDS_PN = "14";
DRAWING = "@s9s_mb_2u_lib.s9s_mb_2u(sch_1):page201";
BODY = "Q_CAP","I16": LOCATION = "C1883" #&CDS_LOCATION = "C1883" &SEC = "1" #&CDS_SEC = "1";
"A":   PN = "1"  !CDS_PN = "1";
"B":   PN = "2"  !CDS_PN = "2";
BODY = "Q_CAP","I18": LOCATION = "C1886" #&CDS_LOCATION = "C1886" &SEC = "1" #&CDS_SEC = "1";
"A":   PN = "1"  !CDS_PN = "1";
"B":   PN = "2"  !CDS_PN = "2";
BODY = "Q_CAP","I19": LOCATION = "C1889" #&CDS_LOCATION = "C1889" &SEC = "1" #&CDS_SEC = "1";
"A":   PN = "1"  !CDS_PN = "1";
"B":   PN = "2"  !CDS_PN = "2";
BODY = "Q_RES","I69": LOCATION = "R3335" #&CDS_LOCATION = "R3335" &SEC = "1" #&CDS_SEC = "1";
"A":   PN = "1"  !CDS_PN = "1";
"B":   PN = "2"  !CDS_PN = "2";
BODY = "Q_RES","I74": LOCATION = "R3336" #&CDS_LOCATION = "R3336" &SEC = "1" #&CDS_SEC = "1";
"A":   PN = "1"  !CDS_PN = "1";
"B":   PN = "2"  !CDS_PN = "2";
BODY = "Q_RES","I75": LOCATION = "R3337" #&CDS_LOCATION = "R3337" &SEC = "1" #&CDS_SEC = "1";
"A":   PN = "1"  !CDS_PN = "1";
"B":   PN = "2"  !CDS_PN = "2";
BODY = "Q_RES","I76": LOCATION = "R3338" #&CDS_LOCATION = "R3338" &SEC = "1" #&CDS_SEC = "1";
"A":   PN = "1"  !CDS_PN = "1";
"B":   PN = "2"  !CDS_PN = "2";
BODY = "Q_CAP","I80": LOCATION = "C1882" #&CDS_LOCATION = "C1882" &SEC = "1" #&CDS_SEC = "1";
"A":   PN = "1"  !CDS_PN = "1";
"B":   PN = "2"  !CDS_PN = "2";
BODY = "Q_RES","I84": LOCATION = "R3326" #&CDS_LOCATION = "R3326" &SEC = "1" #&CDS_SEC = "1";
"A":   PN = "1"  !CDS_PN = "1";
"B":   PN = "2"  !CDS_PN = "2";
BODY = "Q_RES","I85": LOCATION = "R3327" #&CDS_LOCATION = "R3327" &SEC = "1" #&CDS_SEC = "1";
"A":   PN = "1"  !CDS_PN = "1";
"B":   PN = "2"  !CDS_PN = "2";
BODY = "Q_RES","I102": LOCATION = "R4077" #&CDS_LOCATION = "R4077" &SEC = "1" #&CDS_SEC = "1";
"A":   PN = "1"  !CDS_PN = "1";
"B":   PN = "2"  !CDS_PN = "2";
BODY = "Q_CAP","I103": LOCATION = "C1884" #&CDS_LOCATION = "C1884" &SEC = "1" #&CDS_SEC = "1";
"A":   PN = "1"  !CDS_PN = "1";
"B":   PN = "2"  !CDS_PN = "2";
BODY = "Q_CAP","I104": LOCATION = "C2257" #&CDS_LOCATION = "C2257" &SEC = "1" #&CDS_SEC = "1";
"A":   PN = "1"  !CDS_PN = "1";
"B":   PN = "2"  !CDS_PN = "2";
BODY = "Q_CAP","I105": LOCATION = "C2258" #&CDS_LOCATION = "C2258" &SEC = "1" #&CDS_SEC = "1";
"A":   PN = "1"  !CDS_PN = "1";
"B":   PN = "2"  !CDS_PN = "2";
BODY = "Q_CAP","I106": LOCATION = "C2259" #&CDS_LOCATION = "C2259" &SEC = "1" #&CDS_SEC = "1";
"A":   PN = "1"  !CDS_PN = "1";
"B":   PN = "2"  !CDS_PN = "2";
BODY = "Q_RES","I127": LOCATION = "R4078" #&CDS_LOCATION = "R4078" &SEC = "1" #&CDS_SEC = "1";
"A":   PN = "1"  !CDS_PN = "1";
"B":   PN = "2"  !CDS_PN = "2";
BODY = "Q_RES","I128": LOCATION = "R4079" #&CDS_LOCATION = "R4079" &SEC = "1" #&CDS_SEC = "1";
"A":   PN = "1"  !CDS_PN = "1";
"B":   PN = "2"  !CDS_PN = "2";
BODY = "Q_RES","I134": LOCATION = "R4082" #&CDS_LOCATION = "R4082" &SEC = "1" #&CDS_SEC = "1";
"A":   PN = "1"  !CDS_PN = "1";
"B":   PN = "2"  !CDS_PN = "2";
BODY = "Q_RES","I135": LOCATION = "R4081" #&CDS_LOCATION = "R4081" &SEC = "1" #&CDS_SEC = "1";
"A":   PN = "1"  !CDS_PN = "1";
"B":   PN = "2"  !CDS_PN = "2";
BODY = "Q_RES","I142": LOCATION = "R4080" #&CDS_LOCATION = "R4080" &SEC = "1" #&CDS_SEC = "1";
"A":   PN = "1"  !CDS_PN = "1";
"B":   PN = "2"  !CDS_PN = "2";
BODY = "Q_RES","I146": LOCATION = "R4076" #&CDS_LOCATION = "R4076" &SEC = "1" #&CDS_SEC = "1";
"A":   PN = "1"  !CDS_PN = "1";
"B":   PN = "2"  !CDS_PN = "2";
BODY = "Q_RES","I147": LOCATION = "R4075" #&CDS_LOCATION = "R4075" &SEC = "1" #&CDS_SEC = "1";
"A":   PN = "1"  !CDS_PN = "1";
"B":   PN = "2"  !CDS_PN = "2";
BODY = "Q_INDUCTOR","I155": #LOCATION = "L17" !CDS_LOCATION = "L17" &SEC = "1" #&CDS_SEC = "1";
"1":   PN = "1"  !CDS_PN = "1";
"2":   PN = "2"  !CDS_PN = "2";
BODY = "Q_RES","I157": LOCATION = "R3322" #&CDS_LOCATION = "R3322" &SEC = "1" #&CDS_SEC = "1";
"A":   PN = "1"  !CDS_PN = "1";
"B":   PN = "2"  !CDS_PN = "2";
BODY = "74LVC1G32GW","I158": #LOCATION = "U248" !CDS_LOCATION = "U248" &SEC = "1" #&CDS_SEC = "1";
"GND":   PN = "3"  !CDS_PN = "3";
"I0":   PN = "1"  !CDS_PN = "1";
"I1":   PN = "2"  !CDS_PN = "2";
"O":   PN = "4"  !CDS_PN = "4";
"VCC":   PN = "5"  !CDS_PN = "5";
BODY = "Q_XTAL_4P_13BI_24GND","I159": #LOCATION = "Y3" !CDS_LOCATION = "Y3" &SEC = "1" #&CDS_SEC = "1";
"G1":   PN = "2"  !CDS_PN = "2";
"G2":   PN = "4"  !CDS_PN = "4";
"X1":   PN = "1"  !CDS_PN = "1";
"X2":   PN = "3"  !CDS_PN = "3";
BODY = "Q_RES","I160": LOCATION = "R4501" #&CDS_LOCATION = "R4501" &SEC = "1" #&CDS_SEC = "1";
"A":   PN = "1"  !CDS_PN = "1";
"B":   PN = "2"  !CDS_PN = "2";
BODY = "Q_RES","I161": LOCATION = "R4514" #&CDS_LOCATION = "R4514" &SEC = "1" #&CDS_SEC = "1";
"A":   PN = "1"  !CDS_PN = "1";
"B":   PN = "2"  !CDS_PN = "2";
BODY = "Q_RES","I163": LOCATION = "R4521" #&CDS_LOCATION = "R4521" &SEC = "1" #&CDS_SEC = "1";
"A":   PN = "1"  !CDS_PN = "1";
"B":   PN = "2"  !CDS_PN = "2";
BODY = "Q_CAP","I165": #LOCATION = "C2255" !CDS_LOCATION = "C2255" &SEC = "1" #&CDS_SEC = "1";
"A":   PN = "1"  !CDS_PN = "1";
"B":   PN = "2"  !CDS_PN = "2";
BODY = "Q_CAP","I166": #LOCATION = "C2256" !CDS_LOCATION = "C2256" &SEC = "1" #&CDS_SEC = "1";
"A":   PN = "1"  !CDS_PN = "1";
"B":   PN = "2"  !CDS_PN = "2";
BODY = "9FGL0251DKILFT","I167": #LOCATION = "U247" !CDS_LOCATION = "U247" &SEC = "1" #&CDS_SEC = "1";
"^CKPWRGD_PD#":   PN = "22"  !CDS_PN = "22";
"^VSS_EN_TRI":   PN = "23"  !CDS_PN = "23";
"DIF0":   PN = "13"  !CDS_PN = "13";
"DIF0#":   PN = "14"  !CDS_PN = "14";
"DIF1":   PN = "17"  !CDS_PN = "17";
"DIF1#":   PN = "18"  !CDS_PN = "18";
"GND_10":   PN = "10"  !CDS_PN = "10";
"GND_21":   PN = "21"  !CDS_PN = "21";
"GNDA":   PN = "15"  !CDS_PN = "15";
"GNDDIG":   PN = "6"  !CDS_PN = "6";
"GNDREF":   PN = "5"  !CDS_PN = "5";
"GNDXTAL":   PN = "24"  !CDS_PN = "24";
"SCLK_3.3":   PN = "8"  !CDS_PN = "8";
"SDATA_3.3":   PN = "9"  !CDS_PN = "9";
"TH_GND":   PN = "25"  !CDS_PN = "25";
"VDD3.3_11":   PN = "11"  !CDS_PN = "11";
"VDD3.3_20":   PN = "20"  !CDS_PN = "20";
"VDDA3.3":   PN = "16"  !CDS_PN = "16";
"VDDDIG3.3":   PN = "7"  !CDS_PN = "7";
"VDDXTAL3.3":   PN = "3"  !CDS_PN = "3";
"VOE0#":   PN = "12"  !CDS_PN = "12";
"VOE1#":   PN = "19"  !CDS_PN = "19";
"VSADR||REF3.3":   PN = "4"  !CDS_PN = "4";
"X2":   PN = "2"  !CDS_PN = "2";
"XIN||CLKIN_25":   PN = "1"  !CDS_PN = "1";
DRAWING = "@s9s_mb_2u_lib.s9s_mb_2u(sch_1):page317";
BODY = "CONN112_10137002101LF","I38": #LOCATION = "J107" !CDS_LOCATION = "J107" &SEC = "1" #&CDS_SEC = "1";
"A5":   PN = "A5"  !CDS_PN = "A5";
"A6":   PN = "A6"  !CDS_PN = "A6";
"A7":   PN = "A7"  !CDS_PN = "A7";
"A8":   PN = "A8"  !CDS_PN = "A8";
"B5":   PN = "B5"  !CDS_PN = "B5";
"B6":   PN = "B6"  !CDS_PN = "B6";
"B7":   PN = "B7"  !CDS_PN = "B7";
"B8":   PN = "B8"  !CDS_PN = "B8";
"C5":   PN = "C5"  !CDS_PN = "C5";
"C6":   PN = "C6"  !CDS_PN = "C6";
"C7":   PN = "C7"  !CDS_PN = "C7";
"C8":   PN = "C8"  !CDS_PN = "C8";
"D5":   PN = "D5"  !CDS_PN = "D5";
"D6":   PN = "D6"  !CDS_PN = "D6";
"D7":   PN = "D7"  !CDS_PN = "D7";
"D8":   PN = "D8"  !CDS_PN = "D8";
"E5":   PN = "E5"  !CDS_PN = "E5";
"E6":   PN = "E6"  !CDS_PN = "E6";
"E7":   PN = "E7"  !CDS_PN = "E7";
"E8":   PN = "E8"  !CDS_PN = "E8";
"F5":   PN = "F5"  !CDS_PN = "F5";
"F6":   PN = "F6"  !CDS_PN = "F6";
"F7":   PN = "F7"  !CDS_PN = "F7";
"F8":   PN = "F8"  !CDS_PN = "F8";
"G5":   PN = "G5"  !CDS_PN = "G5";
"G6":   PN = "G6"  !CDS_PN = "G6";
"G7":   PN = "G7"  !CDS_PN = "G7";
"G8":   PN = "G8"  !CDS_PN = "G8";
"H5":   PN = "H5"  !CDS_PN = "H5";
"H6":   PN = "H6"  !CDS_PN = "H6";
"H7":   PN = "H7"  !CDS_PN = "H7";
"H8":   PN = "H8"  !CDS_PN = "H8";
"I5":   PN = "I5"  !CDS_PN = "I5";
"I6":   PN = "I6"  !CDS_PN = "I6";
"I7":   PN = "I7"  !CDS_PN = "I7";
"I8":   PN = "I8"  !CDS_PN = "I8";
"J5":   PN = "J5"  !CDS_PN = "J5";
"J6":   PN = "J6"  !CDS_PN = "J6";
"J7":   PN = "J7"  !CDS_PN = "J7";
"J8":   PN = "J8"  !CDS_PN = "J8";
"K5":   PN = "K5"  !CDS_PN = "K5";
"K6":   PN = "K6"  !CDS_PN = "K6";
"K7":   PN = "K7"  !CDS_PN = "K7";
"K8":   PN = "K8"  !CDS_PN = "K8";
"L5":   PN = "L5"  !CDS_PN = "L5";
"L6":   PN = "L6"  !CDS_PN = "L6";
"L7":   PN = "L7"  !CDS_PN = "L7";
"L8":   PN = "L8"  !CDS_PN = "L8";
"M5":   PN = "M5"  !CDS_PN = "M5";
"M6":   PN = "M6"  !CDS_PN = "M6";
"M7":   PN = "M7"  !CDS_PN = "M7";
"M8":   PN = "M8"  !CDS_PN = "M8";
"N5":   PN = "N5"  !CDS_PN = "N5";
"N6":   PN = "N6"  !CDS_PN = "N6";
"N7":   PN = "N7"  !CDS_PN = "N7";
"N8":   PN = "N8"  !CDS_PN = "N8";
BODY = "CONN112_10137002101LF","I58": #LOCATION = "J107" !CDS_LOCATION = "J107" &SEC = "2" #&CDS_SEC = "2";
"A1":   PN = "A1"  !CDS_PN = "A1";
"A2":   PN = "A2"  !CDS_PN = "A2";
"A3":   PN = "A3"  !CDS_PN = "A3";
"A4":   PN = "A4"  !CDS_PN = "A4";
"B1":   PN = "B1"  !CDS_PN = "B1";
"B2":   PN = "B2"  !CDS_PN = "B2";
"B3":   PN = "B3"  !CDS_PN = "B3";
"B4":   PN = "B4"  !CDS_PN = "B4";
"C1":   PN = "C1"  !CDS_PN = "C1";
"C2":   PN = "C2"  !CDS_PN = "C2";
"C3":   PN = "C3"  !CDS_PN = "C3";
"C4":   PN = "C4"  !CDS_PN = "C4";
"D1":   PN = "D1"  !CDS_PN = "D1";
"D2":   PN = "D2"  !CDS_PN = "D2";
"D3":   PN = "D3"  !CDS_PN = "D3";
"D4":   PN = "D4"  !CDS_PN = "D4";
"E1":   PN = "E1"  !CDS_PN = "E1";
"E2":   PN = "E2"  !CDS_PN = "E2";
"E3":   PN = "E3"  !CDS_PN = "E3";
"E4":   PN = "E4"  !CDS_PN = "E4";
"F1":   PN = "F1"  !CDS_PN = "F1";
"F2":   PN = "F2"  !CDS_PN = "F2";
"F3":   PN = "F3"  !CDS_PN = "F3";
"F4":   PN = "F4"  !CDS_PN = "F4";
"G1":   PN = "G1"  !CDS_PN = "G1";
"G2":   PN = "G2"  !CDS_PN = "G2";
"G3":   PN = "G3"  !CDS_PN = "G3";
"G4":   PN = "G4"  !CDS_PN = "G4";
"H1":   PN = "H1"  !CDS_PN = "H1";
"H2":   PN = "H2"  !CDS_PN = "H2";
"H3":   PN = "H3"  !CDS_PN = "H3";
"H4":   PN = "H4"  !CDS_PN = "H4";
"I1":   PN = "I1"  !CDS_PN = "I1";
"I2":   PN = "I2"  !CDS_PN = "I2";
"I3":   PN = "I3"  !CDS_PN = "I3";
"I4":   PN = "I4"  !CDS_PN = "I4";
"J1":   PN = "J1"  !CDS_PN = "J1";
"J2":   PN = "J2"  !CDS_PN = "J2";
"J3":   PN = "J3"  !CDS_PN = "J3";
"J4":   PN = "J4"  !CDS_PN = "J4";
"K1":   PN = "K1"  !CDS_PN = "K1";
"K2":   PN = "K2"  !CDS_PN = "K2";
"K3":   PN = "K3"  !CDS_PN = "K3";
"K4":   PN = "K4"  !CDS_PN = "K4";
"L1":   PN = "L1"  !CDS_PN = "L1";
"L2":   PN = "L2"  !CDS_PN = "L2";
"L3":   PN = "L3"  !CDS_PN = "L3";
"L4":   PN = "L4"  !CDS_PN = "L4";
"M1":   PN = "M1"  !CDS_PN = "M1";
"M2":   PN = "M2"  !CDS_PN = "M2";
"M3":   PN = "M3"  !CDS_PN = "M3";
"M4":   PN = "M4"  !CDS_PN = "M4";
"N1":   PN = "N1"  !CDS_PN = "N1";
"N2":   PN = "N2"  !CDS_PN = "N2";
"N3":   PN = "N3"  !CDS_PN = "N3";
"N4":   PN = "N4"  !CDS_PN = "N4";
DRAWING = "@s9s_mb_2u_lib.s9s_mb_2u(sch_1):page320";
BODY = "CONN112_10137002101LF","I57": #LOCATION = "J108" !CDS_LOCATION = "J108" &SEC = "2" #&CDS_SEC = "2";
"A1":   PN = "A1"  !CDS_PN = "A1";
"A2":   PN = "A2"  !CDS_PN = "A2";
"A3":   PN = "A3"  !CDS_PN = "A3";
"A4":   PN = "A4"  !CDS_PN = "A4";
"B1":   PN = "B1"  !CDS_PN = "B1";
"B2":   PN = "B2"  !CDS_PN = "B2";
"B3":   PN = "B3"  !CDS_PN = "B3";
"B4":   PN = "B4"  !CDS_PN = "B4";
"C1":   PN = "C1"  !CDS_PN = "C1";
"C2":   PN = "C2"  !CDS_PN = "C2";
"C3":   PN = "C3"  !CDS_PN = "C3";
"C4":   PN = "C4"  !CDS_PN = "C4";
"D1":   PN = "D1"  !CDS_PN = "D1";
"D2":   PN = "D2"  !CDS_PN = "D2";
"D3":   PN = "D3"  !CDS_PN = "D3";
"D4":   PN = "D4"  !CDS_PN = "D4";
"E1":   PN = "E1"  !CDS_PN = "E1";
"E2":   PN = "E2"  !CDS_PN = "E2";
"E3":   PN = "E3"  !CDS_PN = "E3";
"E4":   PN = "E4"  !CDS_PN = "E4";
"F1":   PN = "F1"  !CDS_PN = "F1";
"F2":   PN = "F2"  !CDS_PN = "F2";
"F3":   PN = "F3"  !CDS_PN = "F3";
"F4":   PN = "F4"  !CDS_PN = "F4";
"G1":   PN = "G1"  !CDS_PN = "G1";
"G2":   PN = "G2"  !CDS_PN = "G2";
"G3":   PN = "G3"  !CDS_PN = "G3";
"G4":   PN = "G4"  !CDS_PN = "G4";
"H1":   PN = "H1"  !CDS_PN = "H1";
"H2":   PN = "H2"  !CDS_PN = "H2";
"H3":   PN = "H3"  !CDS_PN = "H3";
"H4":   PN = "H4"  !CDS_PN = "H4";
"I1":   PN = "I1"  !CDS_PN = "I1";
"I2":   PN = "I2"  !CDS_PN = "I2";
"I3":   PN = "I3"  !CDS_PN = "I3";
"I4":   PN = "I4"  !CDS_PN = "I4";
"J1":   PN = "J1"  !CDS_PN = "J1";
"J2":   PN = "J2"  !CDS_PN = "J2";
"J3":   PN = "J3"  !CDS_PN = "J3";
"J4":   PN = "J4"  !CDS_PN = "J4";
"K1":   PN = "K1"  !CDS_PN = "K1";
"K2":   PN = "K2"  !CDS_PN = "K2";
"K3":   PN = "K3"  !CDS_PN = "K3";
"K4":   PN = "K4"  !CDS_PN = "K4";
"L1":   PN = "L1"  !CDS_PN = "L1";
"L2":   PN = "L2"  !CDS_PN = "L2";
"L3":   PN = "L3"  !CDS_PN = "L3";
"L4":   PN = "L4"  !CDS_PN = "L4";
"M1":   PN = "M1"  !CDS_PN = "M1";
"M2":   PN = "M2"  !CDS_PN = "M2";
"M3":   PN = "M3"  !CDS_PN = "M3";
"M4":   PN = "M4"  !CDS_PN = "M4";
"N1":   PN = "N1"  !CDS_PN = "N1";
"N2":   PN = "N2"  !CDS_PN = "N2";
"N3":   PN = "N3"  !CDS_PN = "N3";
"N4":   PN = "N4"  !CDS_PN = "N4";
BODY = "CONN112_10137002101LF","I76": #LOCATION = "J108" !CDS_LOCATION = "J108" &SEC = "1" #&CDS_SEC = "1";
"A5":   PN = "A5"  !CDS_PN = "A5";
"A6":   PN = "A6"  !CDS_PN = "A6";
"A7":   PN = "A7"  !CDS_PN = "A7";
"A8":   PN = "A8"  !CDS_PN = "A8";
"B5":   PN = "B5"  !CDS_PN = "B5";
"B6":   PN = "B6"  !CDS_PN = "B6";
"B7":   PN = "B7"  !CDS_PN = "B7";
"B8":   PN = "B8"  !CDS_PN = "B8";
"C5":   PN = "C5"  !CDS_PN = "C5";
"C6":   PN = "C6"  !CDS_PN = "C6";
"C7":   PN = "C7"  !CDS_PN = "C7";
"C8":   PN = "C8"  !CDS_PN = "C8";
"D5":   PN = "D5"  !CDS_PN = "D5";
"D6":   PN = "D6"  !CDS_PN = "D6";
"D7":   PN = "D7"  !CDS_PN = "D7";
"D8":   PN = "D8"  !CDS_PN = "D8";
"E5":   PN = "E5"  !CDS_PN = "E5";
"E6":   PN = "E6"  !CDS_PN = "E6";
"E7":   PN = "E7"  !CDS_PN = "E7";
"E8":   PN = "E8"  !CDS_PN = "E8";
"F5":   PN = "F5"  !CDS_PN = "F5";
"F6":   PN = "F6"  !CDS_PN = "F6";
"F7":   PN = "F7"  !CDS_PN = "F7";
"F8":   PN = "F8"  !CDS_PN = "F8";
"G5":   PN = "G5"  !CDS_PN = "G5";
"G6":   PN = "G6"  !CDS_PN = "G6";
"G7":   PN = "G7"  !CDS_PN = "G7";
"G8":   PN = "G8"  !CDS_PN = "G8";
"H5":   PN = "H5"  !CDS_PN = "H5";
"H6":   PN = "H6"  !CDS_PN = "H6";
"H7":   PN = "H7"  !CDS_PN = "H7";
"H8":   PN = "H8"  !CDS_PN = "H8";
"I5":   PN = "I5"  !CDS_PN = "I5";
"I6":   PN = "I6"  !CDS_PN = "I6";
"I7":   PN = "I7"  !CDS_PN = "I7";
"I8":   PN = "I8"  !CDS_PN = "I8";
"J5":   PN = "J5"  !CDS_PN = "J5";
"J6":   PN = "J6"  !CDS_PN = "J6";
"J7":   PN = "J7"  !CDS_PN = "J7";
"J8":   PN = "J8"  !CDS_PN = "J8";
"K5":   PN = "K5"  !CDS_PN = "K5";
"K6":   PN = "K6"  !CDS_PN = "K6";
"K7":   PN = "K7"  !CDS_PN = "K7";
"K8":   PN = "K8"  !CDS_PN = "K8";
"L5":   PN = "L5"  !CDS_PN = "L5";
"L6":   PN = "L6"  !CDS_PN = "L6";
"L7":   PN = "L7"  !CDS_PN = "L7";
"L8":   PN = "L8"  !CDS_PN = "L8";
"M5":   PN = "M5"  !CDS_PN = "M5";
"M6":   PN = "M6"  !CDS_PN = "M6";
"M7":   PN = "M7"  !CDS_PN = "M7";
"M8":   PN = "M8"  !CDS_PN = "M8";
"N5":   PN = "N5"  !CDS_PN = "N5";
"N6":   PN = "N6"  !CDS_PN = "N6";
"N7":   PN = "N7"  !CDS_PN = "N7";
"N8":   PN = "N8"  !CDS_PN = "N8";
DRAWING = "@s9s_mb_2u_lib.s9s_mb_2u(sch_1):page318";
BODY = "CONN112_10137002101LF","I16": #LOCATION = "J110" !CDS_LOCATION = "J110" &SEC = "1" #&CDS_SEC = "1";
"A5":   PN = "A5"  !CDS_PN = "A5";
"A6":   PN = "A6"  !CDS_PN = "A6";
"A7":   PN = "A7"  !CDS_PN = "A7";
"A8":   PN = "A8"  !CDS_PN = "A8";
"B5":   PN = "B5"  !CDS_PN = "B5";
"B6":   PN = "B6"  !CDS_PN = "B6";
"B7":   PN = "B7"  !CDS_PN = "B7";
"B8":   PN = "B8"  !CDS_PN = "B8";
"C5":   PN = "C5"  !CDS_PN = "C5";
"C6":   PN = "C6"  !CDS_PN = "C6";
"C7":   PN = "C7"  !CDS_PN = "C7";
"C8":   PN = "C8"  !CDS_PN = "C8";
"D5":   PN = "D5"  !CDS_PN = "D5";
"D6":   PN = "D6"  !CDS_PN = "D6";
"D7":   PN = "D7"  !CDS_PN = "D7";
"D8":   PN = "D8"  !CDS_PN = "D8";
"E5":   PN = "E5"  !CDS_PN = "E5";
"E6":   PN = "E6"  !CDS_PN = "E6";
"E7":   PN = "E7"  !CDS_PN = "E7";
"E8":   PN = "E8"  !CDS_PN = "E8";
"F5":   PN = "F5"  !CDS_PN = "F5";
"F6":   PN = "F6"  !CDS_PN = "F6";
"F7":   PN = "F7"  !CDS_PN = "F7";
"F8":   PN = "F8"  !CDS_PN = "F8";
"G5":   PN = "G5"  !CDS_PN = "G5";
"G6":   PN = "G6"  !CDS_PN = "G6";
"G7":   PN = "G7"  !CDS_PN = "G7";
"G8":   PN = "G8"  !CDS_PN = "G8";
"H5":   PN = "H5"  !CDS_PN = "H5";
"H6":   PN = "H6"  !CDS_PN = "H6";
"H7":   PN = "H7"  !CDS_PN = "H7";
"H8":   PN = "H8"  !CDS_PN = "H8";
"I5":   PN = "I5"  !CDS_PN = "I5";
"I6":   PN = "I6"  !CDS_PN = "I6";
"I7":   PN = "I7"  !CDS_PN = "I7";
"I8":   PN = "I8"  !CDS_PN = "I8";
"J5":   PN = "J5"  !CDS_PN = "J5";
"J6":   PN = "J6"  !CDS_PN = "J6";
"J7":   PN = "J7"  !CDS_PN = "J7";
"J8":   PN = "J8"  !CDS_PN = "J8";
"K5":   PN = "K5"  !CDS_PN = "K5";
"K6":   PN = "K6"  !CDS_PN = "K6";
"K7":   PN = "K7"  !CDS_PN = "K7";
"K8":   PN = "K8"  !CDS_PN = "K8";
"L5":   PN = "L5"  !CDS_PN = "L5";
"L6":   PN = "L6"  !CDS_PN = "L6";
"L7":   PN = "L7"  !CDS_PN = "L7";
"L8":   PN = "L8"  !CDS_PN = "L8";
"M5":   PN = "M5"  !CDS_PN = "M5";
"M6":   PN = "M6"  !CDS_PN = "M6";
"M7":   PN = "M7"  !CDS_PN = "M7";
"M8":   PN = "M8"  !CDS_PN = "M8";
"N5":   PN = "N5"  !CDS_PN = "N5";
"N6":   PN = "N6"  !CDS_PN = "N6";
"N7":   PN = "N7"  !CDS_PN = "N7";
"N8":   PN = "N8"  !CDS_PN = "N8";
BODY = "CONN112_10137002101LF","I54": #LOCATION = "J110" !CDS_LOCATION = "J110" &SEC = "2" #&CDS_SEC = "2";
"A1":   PN = "A1"  !CDS_PN = "A1";
"A2":   PN = "A2"  !CDS_PN = "A2";
"A3":   PN = "A3"  !CDS_PN = "A3";
"A4":   PN = "A4"  !CDS_PN = "A4";
"B1":   PN = "B1"  !CDS_PN = "B1";
"B2":   PN = "B2"  !CDS_PN = "B2";
"B3":   PN = "B3"  !CDS_PN = "B3";
"B4":   PN = "B4"  !CDS_PN = "B4";
"C1":   PN = "C1"  !CDS_PN = "C1";
"C2":   PN = "C2"  !CDS_PN = "C2";
"C3":   PN = "C3"  !CDS_PN = "C3";
"C4":   PN = "C4"  !CDS_PN = "C4";
"D1":   PN = "D1"  !CDS_PN = "D1";
"D2":   PN = "D2"  !CDS_PN = "D2";
"D3":   PN = "D3"  !CDS_PN = "D3";
"D4":   PN = "D4"  !CDS_PN = "D4";
"E1":   PN = "E1"  !CDS_PN = "E1";
"E2":   PN = "E2"  !CDS_PN = "E2";
"E3":   PN = "E3"  !CDS_PN = "E3";
"E4":   PN = "E4"  !CDS_PN = "E4";
"F1":   PN = "F1"  !CDS_PN = "F1";
"F2":   PN = "F2"  !CDS_PN = "F2";
"F3":   PN = "F3"  !CDS_PN = "F3";
"F4":   PN = "F4"  !CDS_PN = "F4";
"G1":   PN = "G1"  !CDS_PN = "G1";
"G2":   PN = "G2"  !CDS_PN = "G2";
"G3":   PN = "G3"  !CDS_PN = "G3";
"G4":   PN = "G4"  !CDS_PN = "G4";
"H1":   PN = "H1"  !CDS_PN = "H1";
"H2":   PN = "H2"  !CDS_PN = "H2";
"H3":   PN = "H3"  !CDS_PN = "H3";
"H4":   PN = "H4"  !CDS_PN = "H4";
"I1":   PN = "I1"  !CDS_PN = "I1";
"I2":   PN = "I2"  !CDS_PN = "I2";
"I3":   PN = "I3"  !CDS_PN = "I3";
"I4":   PN = "I4"  !CDS_PN = "I4";
"J1":   PN = "J1"  !CDS_PN = "J1";
"J2":   PN = "J2"  !CDS_PN = "J2";
"J3":   PN = "J3"  !CDS_PN = "J3";
"J4":   PN = "J4"  !CDS_PN = "J4";
"K1":   PN = "K1"  !CDS_PN = "K1";
"K2":   PN = "K2"  !CDS_PN = "K2";
"K3":   PN = "K3"  !CDS_PN = "K3";
"K4":   PN = "K4"  !CDS_PN = "K4";
"L1":   PN = "L1"  !CDS_PN = "L1";
"L2":   PN = "L2"  !CDS_PN = "L2";
"L3":   PN = "L3"  !CDS_PN = "L3";
"L4":   PN = "L4"  !CDS_PN = "L4";
"M1":   PN = "M1"  !CDS_PN = "M1";
"M2":   PN = "M2"  !CDS_PN = "M2";
"M3":   PN = "M3"  !CDS_PN = "M3";
"M4":   PN = "M4"  !CDS_PN = "M4";
"N1":   PN = "N1"  !CDS_PN = "N1";
"N2":   PN = "N2"  !CDS_PN = "N2";
"N3":   PN = "N3"  !CDS_PN = "N3";
"N4":   PN = "N4"  !CDS_PN = "N4";
DRAWING = "@s9s_mb_2u_lib.s9s_mb_2u(sch_1):page319";
BODY = "CONN112_10137002101LF","I53": #LOCATION = "J109" !CDS_LOCATION = "J109" &SEC = "2" #&CDS_SEC = "2";
"A1":   PN = "A1"  !CDS_PN = "A1";
"A2":   PN = "A2"  !CDS_PN = "A2";
"A3":   PN = "A3"  !CDS_PN = "A3";
"A4":   PN = "A4"  !CDS_PN = "A4";
"B1":   PN = "B1"  !CDS_PN = "B1";
"B2":   PN = "B2"  !CDS_PN = "B2";
"B3":   PN = "B3"  !CDS_PN = "B3";
"B4":   PN = "B4"  !CDS_PN = "B4";
"C1":   PN = "C1"  !CDS_PN = "C1";
"C2":   PN = "C2"  !CDS_PN = "C2";
"C3":   PN = "C3"  !CDS_PN = "C3";
"C4":   PN = "C4"  !CDS_PN = "C4";
"D1":   PN = "D1"  !CDS_PN = "D1";
"D2":   PN = "D2"  !CDS_PN = "D2";
"D3":   PN = "D3"  !CDS_PN = "D3";
"D4":   PN = "D4"  !CDS_PN = "D4";
"E1":   PN = "E1"  !CDS_PN = "E1";
"E2":   PN = "E2"  !CDS_PN = "E2";
"E3":   PN = "E3"  !CDS_PN = "E3";
"E4":   PN = "E4"  !CDS_PN = "E4";
"F1":   PN = "F1"  !CDS_PN = "F1";
"F2":   PN = "F2"  !CDS_PN = "F2";
"F3":   PN = "F3"  !CDS_PN = "F3";
"F4":   PN = "F4"  !CDS_PN = "F4";
"G1":   PN = "G1"  !CDS_PN = "G1";
"G2":   PN = "G2"  !CDS_PN = "G2";
"G3":   PN = "G3"  !CDS_PN = "G3";
"G4":   PN = "G4"  !CDS_PN = "G4";
"H1":   PN = "H1"  !CDS_PN = "H1";
"H2":   PN = "H2"  !CDS_PN = "H2";
"H3":   PN = "H3"  !CDS_PN = "H3";
"H4":   PN = "H4"  !CDS_PN = "H4";
"I1":   PN = "I1"  !CDS_PN = "I1";
"I2":   PN = "I2"  !CDS_PN = "I2";
"I3":   PN = "I3"  !CDS_PN = "I3";
"I4":   PN = "I4"  !CDS_PN = "I4";
"J1":   PN = "J1"  !CDS_PN = "J1";
"J2":   PN = "J2"  !CDS_PN = "J2";
"J3":   PN = "J3"  !CDS_PN = "J3";
"J4":   PN = "J4"  !CDS_PN = "J4";
"K1":   PN = "K1"  !CDS_PN = "K1";
"K2":   PN = "K2"  !CDS_PN = "K2";
"K3":   PN = "K3"  !CDS_PN = "K3";
"K4":   PN = "K4"  !CDS_PN = "K4";
"L1":   PN = "L1"  !CDS_PN = "L1";
"L2":   PN = "L2"  !CDS_PN = "L2";
"L3":   PN = "L3"  !CDS_PN = "L3";
"L4":   PN = "L4"  !CDS_PN = "L4";
"M1":   PN = "M1"  !CDS_PN = "M1";
"M2":   PN = "M2"  !CDS_PN = "M2";
"M3":   PN = "M3"  !CDS_PN = "M3";
"M4":   PN = "M4"  !CDS_PN = "M4";
"N1":   PN = "N1"  !CDS_PN = "N1";
"N2":   PN = "N2"  !CDS_PN = "N2";
"N3":   PN = "N3"  !CDS_PN = "N3";
"N4":   PN = "N4"  !CDS_PN = "N4";
BODY = "CONN112_10137002101LF","I76": #LOCATION = "J109" !CDS_LOCATION = "J109" &SEC = "1" #&CDS_SEC = "1";
"A5":   PN = "A5"  !CDS_PN = "A5";
"A6":   PN = "A6"  !CDS_PN = "A6";
"A7":   PN = "A7"  !CDS_PN = "A7";
"A8":   PN = "A8"  !CDS_PN = "A8";
"B5":   PN = "B5"  !CDS_PN = "B5";
"B6":   PN = "B6"  !CDS_PN = "B6";
"B7":   PN = "B7"  !CDS_PN = "B7";
"B8":   PN = "B8"  !CDS_PN = "B8";
"C5":   PN = "C5"  !CDS_PN = "C5";
"C6":   PN = "C6"  !CDS_PN = "C6";
"C7":   PN = "C7"  !CDS_PN = "C7";
"C8":   PN = "C8"  !CDS_PN = "C8";
"D5":   PN = "D5"  !CDS_PN = "D5";
"D6":   PN = "D6"  !CDS_PN = "D6";
"D7":   PN = "D7"  !CDS_PN = "D7";
"D8":   PN = "D8"  !CDS_PN = "D8";
"E5":   PN = "E5"  !CDS_PN = "E5";
"E6":   PN = "E6"  !CDS_PN = "E6";
"E7":   PN = "E7"  !CDS_PN = "E7";
"E8":   PN = "E8"  !CDS_PN = "E8";
"F5":   PN = "F5"  !CDS_PN = "F5";
"F6":   PN = "F6"  !CDS_PN = "F6";
"F7":   PN = "F7"  !CDS_PN = "F7";
"F8":   PN = "F8"  !CDS_PN = "F8";
"G5":   PN = "G5"  !CDS_PN = "G5";
"G6":   PN = "G6"  !CDS_PN = "G6";
"G7":   PN = "G7"  !CDS_PN = "G7";
"G8":   PN = "G8"  !CDS_PN = "G8";
"H5":   PN = "H5"  !CDS_PN = "H5";
"H6":   PN = "H6"  !CDS_PN = "H6";
"H7":   PN = "H7"  !CDS_PN = "H7";
"H8":   PN = "H8"  !CDS_PN = "H8";
"I5":   PN = "I5"  !CDS_PN = "I5";
"I6":   PN = "I6"  !CDS_PN = "I6";
"I7":   PN = "I7"  !CDS_PN = "I7";
"I8":   PN = "I8"  !CDS_PN = "I8";
"J5":   PN = "J5"  !CDS_PN = "J5";
"J6":   PN = "J6"  !CDS_PN = "J6";
"J7":   PN = "J7"  !CDS_PN = "J7";
"J8":   PN = "J8"  !CDS_PN = "J8";
"K5":   PN = "K5"  !CDS_PN = "K5";
"K6":   PN = "K6"  !CDS_PN = "K6";
"K7":   PN = "K7"  !CDS_PN = "K7";
"K8":   PN = "K8"  !CDS_PN = "K8";
"L5":   PN = "L5"  !CDS_PN = "L5";
"L6":   PN = "L6"  !CDS_PN = "L6";
"L7":   PN = "L7"  !CDS_PN = "L7";
"L8":   PN = "L8"  !CDS_PN = "L8";
"M5":   PN = "M5"  !CDS_PN = "M5";
"M6":   PN = "M6"  !CDS_PN = "M6";
"M7":   PN = "M7"  !CDS_PN = "M7";
"M8":   PN = "M8"  !CDS_PN = "M8";
"N5":   PN = "N5"  !CDS_PN = "N5";
"N6":   PN = "N6"  !CDS_PN = "N6";
"N7":   PN = "N7"  !CDS_PN = "N7";
"N8":   PN = "N8"  !CDS_PN = "N8";
DRAWING = "@s9s_mb_2u_lib.s9s_mb_2u(sch_1):page313";
BODY = "LCMXO3LF9400C5BG484C","I1": LOCATION = "U249" #&CDS_LOCATION = "U249" &SEC = "7" #&CDS_SEC = "7";
"PR2A||R_GPLLT_FB":   PN = "C21"  !CDS_PN = "C21";
"PR2B||R_GPLLC_FB":   PN = "C22"  !CDS_PN = "C22";
"PR2C":   PN = "F17"  !CDS_PN = "F17";
"PR2D":   PN = "G16"  !CDS_PN = "G16";
"PR3A||R_GPLLT_IN":   PN = "D22"  !CDS_PN = "D22";
"PR3B||R_GPLLC_IN":   PN = "D21"  !CDS_PN = "D21";
"PR3C":   PN = "D19"  !CDS_PN = "D19";
"PR3D":   PN = "D20"  !CDS_PN = "D20";
"PR4A":   PN = "E22"  !CDS_PN = "E22";
"PR4B":   PN = "E21"  !CDS_PN = "E21";
"PR4C":   PN = "E19"  !CDS_PN = "E19";
"PR4D":   PN = "E20"  !CDS_PN = "E20";
"PR5A":   PN = "F22"  !CDS_PN = "F22";
"PR5B":   PN = "G22"  !CDS_PN = "G22";
"PR5C":   PN = "F18"  !CDS_PN = "F18";
"PR5D":   PN = "F19"  !CDS_PN = "F19";
"PR6A":   PN = "G21"  !CDS_PN = "G21";
"PR6B":   PN = "G20"  !CDS_PN = "G20";
"PR6C":   PN = "G19"  !CDS_PN = "G19";
"PR6D":   PN = "G18"  !CDS_PN = "G18";
"PR7A":   PN = "H22"  !CDS_PN = "H22";
"PR7B":   PN = "H21"  !CDS_PN = "H21";
"PR7C":   PN = "G17"  !CDS_PN = "G17";
"PR7D":   PN = "H20"  !CDS_PN = "H20";
"PR10A":   PN = "H19"  !CDS_PN = "H19";
"PR10B":   PN = "H18"  !CDS_PN = "H18";
"PR10C":   PN = "H17"  !CDS_PN = "H17";
"PR10D":   PN = "H16"  !CDS_PN = "H16";
"PR11A":   PN = "J16"  !CDS_PN = "J16";
"PR11B":   PN = "J17"  !CDS_PN = "J17";
"PR11C":   PN = "J18"  !CDS_PN = "J18";
"PR11D":   PN = "J19"  !CDS_PN = "J19";
"PR12A":   PN = "J21"  !CDS_PN = "J21";
"PR12B":   PN = "J22"  !CDS_PN = "J22";
"PR12C":   PN = "J20"  !CDS_PN = "J20";
"PR12D":   PN = "K20"  !CDS_PN = "K20";
"PR13A":   PN = "K19"  !CDS_PN = "K19";
"PR13B":   PN = "K18"  !CDS_PN = "K18";
"PR13C":   PN = "K17"  !CDS_PN = "K17";
"PR13D":   PN = "K16"  !CDS_PN = "K16";
"PR14A":   PN = "L17"  !CDS_PN = "L17";
"PR14B":   PN = "L16"  !CDS_PN = "L16";
"PR14C":   PN = "L19"  !CDS_PN = "L19";
"PR14D":   PN = "L20"  !CDS_PN = "L20";
"PR16A":   PN = "K22"  !CDS_PN = "K22";
"PR16B":   PN = "L21"  !CDS_PN = "L21";
"PR16C":   PN = "L22"  !CDS_PN = "L22";
"PR16D":   PN = "M17"  !CDS_PN = "M17";
"PR17A||PCLKT1_0":   PN = "M22"  !CDS_PN = "M22";
"PR17B||PCLKC1_0":   PN = "M21"  !CDS_PN = "M21";
"PR17C":   PN = "M20"  !CDS_PN = "M20";
"PR17D":   PN = "M19"  !CDS_PN = "M19";
"PR18A":   PN = "M16"  !CDS_PN = "M16";
"PR18B":   PN = "N16"  !CDS_PN = "N16";
"PR18C":   PN = "N17"  !CDS_PN = "N17";
"PR18D":   PN = "N18"  !CDS_PN = "N18";
"PR19A":   PN = "N22"  !CDS_PN = "N22";
"PR19B":   PN = "P21"  !CDS_PN = "P21";
"PR19C":   PN = "N20"  !CDS_PN = "N20";
"PR19D":   PN = "N19"  !CDS_PN = "N19";
"PR20A":   PN = "R22"  !CDS_PN = "R22";
"PR20B":   PN = "R21"  !CDS_PN = "R21";
"PR20C":   PN = "P22"  !CDS_PN = "P22";
"PR20D":   PN = "P20"  !CDS_PN = "P20";
"PR21A":   PN = "T22"  !CDS_PN = "T22";
"PR21B":   PN = "T21"  !CDS_PN = "T21";
"PR21C":   PN = "P19"  !CDS_PN = "P19";
"PR21D":   PN = "P18"  !CDS_PN = "P18";
"PR24A":   PN = "P17"  !CDS_PN = "P17";
"PR24B":   PN = "P16"  !CDS_PN = "P16";
"PR24C":   PN = "U22"  !CDS_PN = "U22";
"PR24D":   PN = "U21"  !CDS_PN = "U21";
"PR25A":   PN = "V22"  !CDS_PN = "V22";
"PR25B":   PN = "W22"  !CDS_PN = "W22";
"PR25C":   PN = "R20"  !CDS_PN = "R20";
"PR25D":   PN = "R19"  !CDS_PN = "R19";
"PR26A":   PN = "R18"  !CDS_PN = "R18";
"PR26B":   PN = "R17"  !CDS_PN = "R17";
"PR26C":   PN = "R16"  !CDS_PN = "R16";
"PR26D":   PN = "T20"  !CDS_PN = "T20";
"PR27A":   PN = "T19"  !CDS_PN = "T19";
"PR27B":   PN = "T18"  !CDS_PN = "T18";
"PR27C":   PN = "T17"  !CDS_PN = "T17";
"PR27D":   PN = "U20"  !CDS_PN = "U20";
"PR28A":   PN = "Y22"  !CDS_PN = "Y22";
"PR28B":   PN = "W21"  !CDS_PN = "W21";
"PR28C":   PN = "U19"  !CDS_PN = "U19";
"PR28D":   PN = "U18"  !CDS_PN = "U18";
"PR29A":   PN = "AA22"  !CDS_PN = "AA22";
"PR29B":   PN = "Y21"  !CDS_PN = "Y21";
"PR29C":   PN = "U17"  !CDS_PN = "U17";
"PR29D":   PN = "V19"  !CDS_PN = "V19";
"PR30A":   PN = "V18"  !CDS_PN = "V18";
"PR30B":   PN = "W20"  !CDS_PN = "W20";
"PR30C":   PN = "W19"  !CDS_PN = "W19";
"PR30D":   PN = "Y20"  !CDS_PN = "Y20";
BODY = "Q_RES","I83": LOCATION = "R2412" #&CDS_LOCATION = "R2412" &SEC = "1" #&CDS_SEC = "1";
"A":   PN = "1"  !CDS_PN = "1";
"B":   PN = "2"  !CDS_PN = "2";
BODY = "Q_RES","I84": LOCATION = "R2452" #&CDS_LOCATION = "R2452" &SEC = "1" #&CDS_SEC = "1";
"A":   PN = "1"  !CDS_PN = "1";
"B":   PN = "2"  !CDS_PN = "2";
BODY = "Q_RES","I85": LOCATION = "R3047" #&CDS_LOCATION = "R3047" &SEC = "1" #&CDS_SEC = "1";
"A":   PN = "1"  !CDS_PN = "1";
"B":   PN = "2"  !CDS_PN = "2";
BODY = "Q_RES","I86": LOCATION = "R3048" #&CDS_LOCATION = "R3048" &SEC = "1" #&CDS_SEC = "1";
"A":   PN = "1"  !CDS_PN = "1";
"B":   PN = "2"  !CDS_PN = "2";
BODY = "Q_RES","I115": LOCATION = "R1100" #&CDS_LOCATION = "R1100" &SEC = "1" #&CDS_SEC = "1";
"A":   PN = "1"  !CDS_PN = "1";
"B":   PN = "2"  !CDS_PN = "2";
BODY = "Q_CAP","I126": LOCATION = "C1320" #&CDS_LOCATION = "C1320" &SEC = "1" #&CDS_SEC = "1";
"A":   PN = "1"  !CDS_PN = "1";
"B":   PN = "2"  !CDS_PN = "2";
BODY = "Q_OSC4P","I127": LOCATION = "OSC2" #&CDS_LOCATION = "OSC2" &SEC = "1" #&CDS_SEC = "1";
"GND":   PN = "2"  !CDS_PN = "2";
"OE":   PN = "1"  !CDS_PN = "1";
"OUT":   PN = "3"  !CDS_PN = "3";
"VDD":   PN = "4"  !CDS_PN = "4";
BODY = "Q_RES","I129": LOCATION = "R1099" #&CDS_LOCATION = "R1099" &SEC = "1" #&CDS_SEC = "1";
"A":   PN = "1"  !CDS_PN = "1";
"B":   PN = "2"  !CDS_PN = "2";
BODY = "Q_RES","I147": LOCATION = "R4259" #&CDS_LOCATION = "R4259" &SEC = "1" #&CDS_SEC = "1";
"A":   PN = "1"  !CDS_PN = "1";
"B":   PN = "2"  !CDS_PN = "2";
BODY = "Q_RES","I159": LOCATION = "R4599" #&CDS_LOCATION = "R4599" &SEC = "1" #&CDS_SEC = "1";
"A":   PN = "1"  !CDS_PN = "1";
"B":   PN = "2"  !CDS_PN = "2";
BODY = "Q_RES","I160": LOCATION = "R4600" #&CDS_LOCATION = "R4600" &SEC = "1" #&CDS_SEC = "1";
"A":   PN = "1"  !CDS_PN = "1";
"B":   PN = "2"  !CDS_PN = "2";
BODY = "Q_RES","I166": LOCATION = "R4088" #&CDS_LOCATION = "R4088" &SEC = "1" #&CDS_SEC = "1";
"A":   PN = "1"  !CDS_PN = "1";
"B":   PN = "2"  !CDS_PN = "2";
BODY = "Q_RES","I167": LOCATION = "R1833" #&CDS_LOCATION = "R1833" &SEC = "1" #&CDS_SEC = "1";
"A":   PN = "1"  !CDS_PN = "1";
"B":   PN = "2"  !CDS_PN = "2";
BODY = "Q_RES","I175": LOCATION = "R3066" #&CDS_LOCATION = "R3066" &SEC = "1" #&CDS_SEC = "1";
"A":   PN = "1"  !CDS_PN = "1";
"B":   PN = "2"  !CDS_PN = "2";
BODY = "Q_RES","I176": LOCATION = "R3067" #&CDS_LOCATION = "R3067" &SEC = "1" #&CDS_SEC = "1";
"A":   PN = "1"  !CDS_PN = "1";
"B":   PN = "2"  !CDS_PN = "2";
BODY = "Q_RES","I180": LOCATION = "R4606" #&CDS_LOCATION = "R4606" &SEC = "1" #&CDS_SEC = "1";
"A":   PN = "1"  !CDS_PN = "1";
"B":   PN = "2"  !CDS_PN = "2";
BODY = "Q_RES","I183": LOCATION = "R4607" #&CDS_LOCATION = "R4607" &SEC = "1" #&CDS_SEC = "1";
"A":   PN = "1"  !CDS_PN = "1";
"B":   PN = "2"  !CDS_PN = "2";
BODY = "Q_RES","I190": LOCATION = "R4608" #&CDS_LOCATION = "R4608" &SEC = "1" #&CDS_SEC = "1";
"A":   PN = "1"  !CDS_PN = "1";
"B":   PN = "2"  !CDS_PN = "2";
BODY = "Q_RES","I194": LOCATION = "R4609" #&CDS_LOCATION = "R4609" &SEC = "1" #&CDS_SEC = "1";
"A":   PN = "1"  !CDS_PN = "1";
"B":   PN = "2"  !CDS_PN = "2";
BODY = "Q_RES","I200": LOCATION = "R4610" #&CDS_LOCATION = "R4610" &SEC = "1" #&CDS_SEC = "1";
"A":   PN = "1"  !CDS_PN = "1";
"B":   PN = "2"  !CDS_PN = "2";
BODY = "Q_RES","I206": LOCATION = "R4611" #&CDS_LOCATION = "R4611" &SEC = "1" #&CDS_SEC = "1";
"A":   PN = "1"  !CDS_PN = "1";
"B":   PN = "2"  !CDS_PN = "2";
BODY = "Q_RES","I211": LOCATION = "R4612" #&CDS_LOCATION = "R4612" &SEC = "1" #&CDS_SEC = "1";
"A":   PN = "1"  !CDS_PN = "1";
"B":   PN = "2"  !CDS_PN = "2";
DRAWING = "@s9s_mb_2u_lib.s9s_mb_2u(sch_1):page314";
BODY = "MOSFET_NCH_DUAL","I49": #LOCATION = "Q50" !CDS_LOCATION = "Q50" &SEC = "2" #&CDS_SEC = "2";
"D2":   PN = "3"  !CDS_PN = "3";
"G2":   PN = "5"  !CDS_PN = "5";
"S2":   PN = "4"  !CDS_PN = "4";
BODY = "Q_RES","I111": #LOCATION = "R3043" !CDS_LOCATION = "R3043" &SEC = "1" #&CDS_SEC = "1";
"A":   PN = "1"  !CDS_PN = "1";
"B":   PN = "2"  !CDS_PN = "2";
BODY = "Q_RES","I115": #LOCATION = "R2662" !CDS_LOCATION = "R2662" &SEC = "1" #&CDS_SEC = "1";
"A":   PN = "1"  !CDS_PN = "1";
"B":   PN = "2"  !CDS_PN = "2";
BODY = "Q_RES","I14": LOCATION = "R4697" #&CDS_LOCATION = "R4697" &SEC = "1" #&CDS_SEC = "1";
"A":   PN = "1"  !CDS_PN = "1";
"B":   PN = "2"  !CDS_PN = "2";
BODY = "Q_RES","I15": #LOCATION = "R3486" !CDS_LOCATION = "R3486" &SEC = "1" #&CDS_SEC = "1";
"A":   PN = "1"  !CDS_PN = "1";
"B":   PN = "2"  !CDS_PN = "2";
BODY = "Q_RES","I16": #LOCATION = "R3505" !CDS_LOCATION = "R3505" &SEC = "1" #&CDS_SEC = "1";
"A":   PN = "1"  !CDS_PN = "1";
"B":   PN = "2"  !CDS_PN = "2";
BODY = "Q_RES","I17": #LOCATION = "R3484" !CDS_LOCATION = "R3484" &SEC = "1" #&CDS_SEC = "1";
"A":   PN = "1"  !CDS_PN = "1";
"B":   PN = "2"  !CDS_PN = "2";
BODY = "Q_RES","I18": #LOCATION = "R3485" !CDS_LOCATION = "R3485" &SEC = "1" #&CDS_SEC = "1";
"A":   PN = "1"  !CDS_PN = "1";
"B":   PN = "2"  !CDS_PN = "2";
BODY = "Q_RES","I19": #LOCATION = "R3482" !CDS_LOCATION = "R3482" &SEC = "1" #&CDS_SEC = "1";
"A":   PN = "1"  !CDS_PN = "1";
"B":   PN = "2"  !CDS_PN = "2";
BODY = "Q_RES","I20": #LOCATION = "R3483" !CDS_LOCATION = "R3483" &SEC = "1" #&CDS_SEC = "1";
"A":   PN = "1"  !CDS_PN = "1";
"B":   PN = "2"  !CDS_PN = "2";
BODY = "Q_RES","I21": #LOCATION = "R3480" !CDS_LOCATION = "R3480" &SEC = "1" #&CDS_SEC = "1";
"A":   PN = "1"  !CDS_PN = "1";
"B":   PN = "2"  !CDS_PN = "2";
BODY = "Q_RES","I22": #LOCATION = "R3481" !CDS_LOCATION = "R3481" &SEC = "1" #&CDS_SEC = "1";
"A":   PN = "1"  !CDS_PN = "1";
"B":   PN = "2"  !CDS_PN = "2";
BODY = "Q_RES","I23": #LOCATION = "R3478" !CDS_LOCATION = "R3478" &SEC = "1" #&CDS_SEC = "1";
"A":   PN = "1"  !CDS_PN = "1";
"B":   PN = "2"  !CDS_PN = "2";
BODY = "Q_RES","I24": #LOCATION = "R3479" !CDS_LOCATION = "R3479" &SEC = "1" #&CDS_SEC = "1";
"A":   PN = "1"  !CDS_PN = "1";
"B":   PN = "2"  !CDS_PN = "2";
BODY = "Q_RES","I25": #LOCATION = "R3476" !CDS_LOCATION = "R3476" &SEC = "1" #&CDS_SEC = "1";
"A":   PN = "1"  !CDS_PN = "1";
"B":   PN = "2"  !CDS_PN = "2";
BODY = "Q_RES","I26": #LOCATION = "R3477" !CDS_LOCATION = "R3477" &SEC = "1" #&CDS_SEC = "1";
"A":   PN = "1"  !CDS_PN = "1";
"B":   PN = "2"  !CDS_PN = "2";
BODY = "Q_RES","I41": LOCATION = "R2343" #&CDS_LOCATION = "R2343" &SEC = "1" #&CDS_SEC = "1";
"A":   PN = "1"  !CDS_PN = "1";
"B":   PN = "2"  !CDS_PN = "2";
BODY = "MOSFET_NCH_DUAL","I43": #LOCATION = "Q50" !CDS_LOCATION = "Q50" &SEC = "1" #&CDS_SEC = "1";
"D1":   PN = "6"  !CDS_PN = "6";
"G1":   PN = "2"  !CDS_PN = "2";
"S1":   PN = "1"  !CDS_PN = "1";
BODY = "Q_RES","I45": LOCATION = "R2344" #&CDS_LOCATION = "R2344" &SEC = "1" #&CDS_SEC = "1";
"A":   PN = "1"  !CDS_PN = "1";
"B":   PN = "2"  !CDS_PN = "2";
BODY = "Q_RES","I47": LOCATION = "R1681" #&CDS_LOCATION = "R1681" &SEC = "1" #&CDS_SEC = "1";
"A":   PN = "1"  !CDS_PN = "1";
"B":   PN = "2"  !CDS_PN = "2";
BODY = "Q_RES","I51": LOCATION = "R2346" #&CDS_LOCATION = "R2346" &SEC = "1" #&CDS_SEC = "1";
"A":   PN = "1"  !CDS_PN = "1";
"B":   PN = "2"  !CDS_PN = "2";
BODY = "Q_RES","I107": #LOCATION = "R2847" !CDS_LOCATION = "R2847" &SEC = "1" #&CDS_SEC = "1";
"A":   PN = "1"  !CDS_PN = "1";
"B":   PN = "2"  !CDS_PN = "2";
BODY = "Q_RES","I108": #LOCATION = "R3324" !CDS_LOCATION = "R3324" &SEC = "1" #&CDS_SEC = "1";
"A":   PN = "1"  !CDS_PN = "1";
"B":   PN = "2"  !CDS_PN = "2";
BODY = "Q_RES","I109": #LOCATION = "R1606" !CDS_LOCATION = "R1606" &SEC = "1" #&CDS_SEC = "1";
"A":   PN = "1"  !CDS_PN = "1";
"B":   PN = "2"  !CDS_PN = "2";
BODY = "Q_RES","I110": #LOCATION = "R3230" !CDS_LOCATION = "R3230" &SEC = "1" #&CDS_SEC = "1";
"A":   PN = "1"  !CDS_PN = "1";
"B":   PN = "2"  !CDS_PN = "2";
BODY = "Q_RES","I112": #LOCATION = "R2844" !CDS_LOCATION = "R2844" &SEC = "1" #&CDS_SEC = "1";
"A":   PN = "1"  !CDS_PN = "1";
"B":   PN = "2"  !CDS_PN = "2";
BODY = "Q_RES","I113": #LOCATION = "R2664" !CDS_LOCATION = "R2664" &SEC = "1" #&CDS_SEC = "1";
"A":   PN = "1"  !CDS_PN = "1";
"B":   PN = "2"  !CDS_PN = "2";
BODY = "Q_RES","I114": #LOCATION = "R2663" !CDS_LOCATION = "R2663" &SEC = "1" #&CDS_SEC = "1";
"A":   PN = "1"  !CDS_PN = "1";
"B":   PN = "2"  !CDS_PN = "2";
BODY = "Q_RES","I135": #LOCATION = "R2661" !CDS_LOCATION = "R2661" &SEC = "1" #&CDS_SEC = "1";
"A":   PN = "1"  !CDS_PN = "1";
"B":   PN = "2"  !CDS_PN = "2";
BODY = "Q_RES","I136": #LOCATION = "R2845" !CDS_LOCATION = "R2845" &SEC = "1" #&CDS_SEC = "1";
"A":   PN = "1"  !CDS_PN = "1";
"B":   PN = "2"  !CDS_PN = "2";
BODY = "Q_RES","I137": LOCATION = "R2071" #&CDS_LOCATION = "R2071" &SEC = "1" #&CDS_SEC = "1";
"A":   PN = "1"  !CDS_PN = "1";
"B":   PN = "2"  !CDS_PN = "2";
BODY = "Q_RES","I138": LOCATION = "R1853" #&CDS_LOCATION = "R1853" &SEC = "1" #&CDS_SEC = "1";
"A":   PN = "1"  !CDS_PN = "1";
"B":   PN = "2"  !CDS_PN = "2";
BODY = "Q_RES","I139": LOCATION = "R1547" #&CDS_LOCATION = "R1547" &SEC = "1" #&CDS_SEC = "1";
"A":   PN = "1"  !CDS_PN = "1";
"B":   PN = "2"  !CDS_PN = "2";
BODY = "Q_RES","I140": LOCATION = "R4625" #&CDS_LOCATION = "R4625" &SEC = "1" #&CDS_SEC = "1";
"A":   PN = "1"  !CDS_PN = "1";
"B":   PN = "2"  !CDS_PN = "2";
BODY = "Q_RES","I141": LOCATION = "R4495" #&CDS_LOCATION = "R4495" &SEC = "1" #&CDS_SEC = "1";
"A":   PN = "1"  !CDS_PN = "1";
"B":   PN = "2"  !CDS_PN = "2";
BODY = "Q_RES","I179": LOCATION = "R1551" #&CDS_LOCATION = "R1551" &SEC = "1" #&CDS_SEC = "1";
"A":   PN = "1"  !CDS_PN = "1";
"B":   PN = "2"  !CDS_PN = "2";
BODY = "Q_RES","I106": #LOCATION = "R2939" !CDS_LOCATION = "R2939" &SEC = "1" #&CDS_SEC = "1";
"A":   PN = "1"  !CDS_PN = "1";
"B":   PN = "2"  !CDS_PN = "2";
BODY = "Q_RES","I134": #LOCATION = "R2846" !CDS_LOCATION = "R2846" &SEC = "1" #&CDS_SEC = "1";
"A":   PN = "1"  !CDS_PN = "1";
"B":   PN = "2"  !CDS_PN = "2";
BODY = "Q_RES","I178": LOCATION = "R1467" #&CDS_LOCATION = "R1467" &SEC = "1" #&CDS_SEC = "1";
"A":   PN = "1"  !CDS_PN = "1";
"B":   PN = "2"  !CDS_PN = "2";
BODY = "LCMXO3LF9400C5BG484C","I188": LOCATION = "U249" #&CDS_LOCATION = "U249" &SEC = "3" #&CDS_SEC = "3";
"PT9A||L_GPLLT":   PN = "B1"  !CDS_PN = "B1";
"PT9B||L_GPLLC":   PN = "A2"  !CDS_PN = "A2";
"PT9C":   PN = "E6"  !CDS_PN = "E6";
"PT9D":   PN = "F7"  !CDS_PN = "F7";
"PT10A":   PN = "B2"  !CDS_PN = "B2";
"PT10B":   PN = "A3"  !CDS_PN = "A3";
"PT10C":   PN = "C3"  !CDS_PN = "C3";
"PT10D":   PN = "C4"  !CDS_PN = "C4";
"PT11A":   PN = "B3"  !CDS_PN = "B3";
"PT11B":   PN = "A4"  !CDS_PN = "A4";
"PT11C":   PN = "F8"  !CDS_PN = "F8";
"PT11D":   PN = "G8"  !CDS_PN = "G8";
"PT12A":   PN = "B4"  !CDS_PN = "B4";
"PT12B":   PN = "A5"  !CDS_PN = "A5";
"PT12C":   PN = "D5"  !CDS_PN = "D5";
"PT12D":   PN = "C5"  !CDS_PN = "C5";
"PT13A":   PN = "B5"  !CDS_PN = "B5";
"PT13B":   PN = "A6"  !CDS_PN = "A6";
"PT13C":   PN = "D6"  !CDS_PN = "D6";
"PT13D":   PN = "E7"  !CDS_PN = "E7";
"PT14A":   PN = "B6"  !CDS_PN = "B6";
"PT14B":   PN = "A7"  !CDS_PN = "A7";
"PT14C":   PN = "C6"  !CDS_PN = "C6";
"PT14D":   PN = "D7"  !CDS_PN = "D7";
"PT15A":   PN = "C8"  !CDS_PN = "C8";
"PT15B":   PN = "D8"  !CDS_PN = "D8";
"PT20A":   PN = "B8"  !CDS_PN = "B8";
"PT20B":   PN = "A8"  !CDS_PN = "A8";
"PT20C":   PN = "C9"  !CDS_PN = "C9";
"PT20D":   PN = "D9"  !CDS_PN = "D9";
"PT21A":   PN = "B9"  !CDS_PN = "B9";
"PT21B":   PN = "A9"  !CDS_PN = "A9";
"PT21C":   PN = "F9"  !CDS_PN = "F9";
"PT21D":   PN = "G9"  !CDS_PN = "G9";
"PT22A":   PN = "F10"  !CDS_PN = "F10";
"PT22B":   PN = "E10"  !CDS_PN = "E10";
"PT23A||PCLKT0_1":   PN = "B10"  !CDS_PN = "B10";
"PT23B||PCLKC0_1":   PN = "A10"  !CDS_PN = "A10";
"PT23C":   PN = "G11"  !CDS_PN = "G11";
"PT23D":   PN = "F11"  !CDS_PN = "F11";
"PT24A":   PN = "B11"  !CDS_PN = "B11";
"PT24B":   PN = "A11"  !CDS_PN = "A11";
"PT24C":   PN = "E11"  !CDS_PN = "E11";
"PT24D":   PN = "D11"  !CDS_PN = "D11";
"PT27A":   PN = "D12"  !CDS_PN = "D12";
"PT27B":   PN = "E12"  !CDS_PN = "E12";
"PT27C||SCL||PCLKT0_0":   PN = "B12"  !CDS_PN = "B12";
"PT27D||SDA||PCLKC0_0":   PN = "A12"  !CDS_PN = "A12";
"PT28A":   PN = "G12"  !CDS_PN = "G12";
"PT28B":   PN = "F12"  !CDS_PN = "F12";
"PT28C":   PN = "E13"  !CDS_PN = "E13";
"PT28D":   PN = "F13"  !CDS_PN = "F13";
"PT29A":   PN = "A13"  !CDS_PN = "A13";
"PT29B":   PN = "B13"  !CDS_PN = "B13";
"PT29C":   PN = "C13"  !CDS_PN = "C13";
"PT29D":   PN = "D13"  !CDS_PN = "D13";
"PT30A":   PN = "A14"  !CDS_PN = "A14";
"PT30B":   PN = "B14"  !CDS_PN = "B14";
"PT30C":   PN = "C14"  !CDS_PN = "C14";
"PT30D":   PN = "D14"  !CDS_PN = "D14";
"PT31A":   PN = "G14"  !CDS_PN = "G14";
"PT31B":   PN = "F14"  !CDS_PN = "F14";
"PT38A":   PN = "A15"  !CDS_PN = "A15";
"PT38B":   PN = "B15"  !CDS_PN = "B15";
"PT38C":   PN = "C15"  !CDS_PN = "C15";
"PT38D":   PN = "D15"  !CDS_PN = "D15";
"PT39A":   PN = "A16"  !CDS_PN = "A16";
"PT39B":   PN = "B17"  !CDS_PN = "B17";
"PT39C":   PN = "C17"  !CDS_PN = "C17";
"PT39D":   PN = "D16"  !CDS_PN = "D16";
"PT40A":   PN = "A17"  !CDS_PN = "A17";
"PT40B":   PN = "B18"  !CDS_PN = "B18";
"PT40C":   PN = "E16"  !CDS_PN = "E16";
"PT40D":   PN = "D17"  !CDS_PN = "D17";
"PT41A":   PN = "A18"  !CDS_PN = "A18";
"PT41B":   PN = "B19"  !CDS_PN = "B19";
"PT41C":   PN = "C18"  !CDS_PN = "C18";
"PT41D":   PN = "D18"  !CDS_PN = "D18";
"PT42A":   PN = "A19"  !CDS_PN = "A19";
"PT42B":   PN = "B20"  !CDS_PN = "B20";
"PT42C":   PN = "F15"  !CDS_PN = "F15";
"PT42D":   PN = "G15"  !CDS_PN = "G15";
"PT43A||R_GPLLT":   PN = "A20"  !CDS_PN = "A20";
"PT43B||R_GPLLC":   PN = "B21"  !CDS_PN = "B21";
"PT43C":   PN = "C19"  !CDS_PN = "C19";
"PT43D":   PN = "C20"  !CDS_PN = "C20";
"PT44A||R_GPLLT":   PN = "A21"  !CDS_PN = "A21";
"PT44B||R_GPLLC":   PN = "B22"  !CDS_PN = "B22";
BODY = "Q_RES","I197": #LOCATION = "R4714" !CDS_LOCATION = "R4714" &SEC = "1" #&CDS_SEC = "1";
"A":   PN = "1"  !CDS_PN = "1";
"B":   PN = "2"  !CDS_PN = "2";
BODY = "Q_RES","I198": #LOCATION = "R4715" !CDS_LOCATION = "R4715" &SEC = "1" #&CDS_SEC = "1";
"A":   PN = "1"  !CDS_PN = "1";
"B":   PN = "2"  !CDS_PN = "2";
DRAWING = "@s9s_mb_2u_lib.s9s_mb_2u(sch_1):page312";
BODY = "LCMXO3LF9400C5BG484C","I1": LOCATION = "U249" #&CDS_LOCATION = "U249" &SEC = "2" #&CDS_SEC = "2";
"PB5A":   PN = "AA2"  !CDS_PN = "AA2";
"PB5B":   PN = "AB2"  !CDS_PN = "AB2";
"PB5C":   PN = "V6"  !CDS_PN = "V6";
"PB5D":   PN = "U6"  !CDS_PN = "U6";
"PB7A||CSSPIN":   PN = "AA3"  !CDS_PN = "AA3";
"PB7B":   PN = "AB3"  !CDS_PN = "AB3";
"PB7C":   PN = "Y4"  !CDS_PN = "Y4";
"PB7D":   PN = "W5"  !CDS_PN = "W5";
"PB8A":   PN = "AA4"  !CDS_PN = "AA4";
"PB8B":   PN = "AB4"  !CDS_PN = "AB4";
"PB8C":   PN = "U7"  !CDS_PN = "U7";
"PB8D":   PN = "T8"  !CDS_PN = "T8";
"PB10A":   PN = "AA5"  !CDS_PN = "AA5";
"PB10B":   PN = "AB5"  !CDS_PN = "AB5";
"PB10C":   PN = "Y5"  !CDS_PN = "Y5";
"PB10D":   PN = "Y6"  !CDS_PN = "Y6";
"PB11A":   PN = "AA6"  !CDS_PN = "AA6";
"PB11B":   PN = "AB6"  !CDS_PN = "AB6";
"PB11C":   PN = "W6"  !CDS_PN = "W6";
"PB11D":   PN = "V7"  !CDS_PN = "V7";
"PB13A":   PN = "AA7"  !CDS_PN = "AA7";
"PB13B":   PN = "AB7"  !CDS_PN = "AB7";
"PB13C":   PN = "V8"  !CDS_PN = "V8";
"PB13D":   PN = "U8"  !CDS_PN = "U8";
"PB16A||MCLK||CCLK":   PN = "T9"  !CDS_PN = "T9";
"PB16B||SO||SPISO":   PN = "U9"  !CDS_PN = "U9";
"PB16C":   PN = "V9"  !CDS_PN = "V9";
"PB16D":   PN = "W8"  !CDS_PN = "W8";
"PB18A":   PN = "AA8"  !CDS_PN = "AA8";
"PB18B":   PN = "AB8"  !CDS_PN = "AB8";
"PB18C":   PN = "Y8"  !CDS_PN = "Y8";
"PB18D":   PN = "W9"  !CDS_PN = "W9";
"PB19A":   PN = "AA9"  !CDS_PN = "AA9";
"PB19B":   PN = "AB9"  !CDS_PN = "AB9";
"PB19C":   PN = "T10"  !CDS_PN = "T10";
"PB19D":   PN = "U10"  !CDS_PN = "U10";
"PB21A":   PN = "V10"  !CDS_PN = "V10";
"PB21B":   PN = "W10"  !CDS_PN = "W10";
"PB21C":   PN = "Y9"  !CDS_PN = "Y9";
"PB21D":   PN = "Y10"  !CDS_PN = "Y10";
"PB22A||PCLKT2_0":   PN = "AA10"  !CDS_PN = "AA10";
"PB22B||PCLKC2_0":   PN = "AB10"  !CDS_PN = "AB10";
"PB22C":   PN = "T11"  !CDS_PN = "T11";
"PB22D":   PN = "U11"  !CDS_PN = "U11";
"PB24A":   PN = "AA11"  !CDS_PN = "AA11";
"PB24B":   PN = "AB11"  !CDS_PN = "AB11";
"PB24C":   PN = "V11"  !CDS_PN = "V11";
"PB24D":   PN = "Y11"  !CDS_PN = "Y11";
"PB27A":   PN = "Y12"  !CDS_PN = "Y12";
"PB27B":   PN = "T12"  !CDS_PN = "T12";
"PB27C":   PN = "U12"  !CDS_PN = "U12";
"PB27D":   PN = "V12"  !CDS_PN = "V12";
"PB29A||PCLKT2_1":   PN = "AB12"  !CDS_PN = "AB12";
"PB29B||PCLKC2_1":   PN = "AA12"  !CDS_PN = "AA12";
"PB29C":   PN = "V13"  !CDS_PN = "V13";
"PB29D":   PN = "U13"  !CDS_PN = "U13";
"PB30A":   PN = "AB13"  !CDS_PN = "AB13";
"PB30B":   PN = "AA13"  !CDS_PN = "AA13";
"PB30C":   PN = "Y13"  !CDS_PN = "Y13";
"PB30D":   PN = "W13"  !CDS_PN = "W13";
"PB32A":   PN = "T13"  !CDS_PN = "T13";
"PB32B":   PN = "T14"  !CDS_PN = "T14";
"PB32C":   PN = "U14"  !CDS_PN = "U14";
"PB32D":   PN = "V14"  !CDS_PN = "V14";
"PB33A":   PN = "AB14"  !CDS_PN = "AB14";
"PB33B":   PN = "AA14"  !CDS_PN = "AA14";
"PB33C":   PN = "Y14"  !CDS_PN = "Y14";
"PB33D":   PN = "W14"  !CDS_PN = "W14";
"PB35A":   PN = "AB15"  !CDS_PN = "AB15";
"PB35B":   PN = "AA15"  !CDS_PN = "AA15";
"PB35C":   PN = "Y15"  !CDS_PN = "Y15";
"PB35D":   PN = "W15"  !CDS_PN = "W15";
"PB38A":   PN = "AB16"  !CDS_PN = "AB16";
"PB38B":   PN = "AA16"  !CDS_PN = "AA16";
"PB38C":   PN = "V15"  !CDS_PN = "V15";
"PB38D":   PN = "U15"  !CDS_PN = "U15";
"PB40A":   PN = "AB17"  !CDS_PN = "AB17";
"PB40B":   PN = "AA17"  !CDS_PN = "AA17";
"PB40C":   PN = "Y17"  !CDS_PN = "Y17";
"PB40D":   PN = "V16"  !CDS_PN = "V16";
"PB41A":   PN = "AB18"  !CDS_PN = "AB18";
"PB41B":   PN = "AA18"  !CDS_PN = "AA18";
"PB41C":   PN = "Y18"  !CDS_PN = "Y18";
"PB41D":   PN = "W17"  !CDS_PN = "W17";
"PB43A":   PN = "AB19"  !CDS_PN = "AB19";
"PB43B":   PN = "AA19"  !CDS_PN = "AA19";
"PB43C":   PN = "T15"  !CDS_PN = "T15";
"PB43D":   PN = "U16"  !CDS_PN = "U16";
"PB44A":   PN = "AB20"  !CDS_PN = "AB20";
"PB44B":   PN = "AA20"  !CDS_PN = "AA20";
"PB44C":   PN = "Y19"  !CDS_PN = "Y19";
"PB44D":   PN = "W18"  !CDS_PN = "W18";
"PB46A||SN":   PN = "AB21"  !CDS_PN = "AB21";
"PB46B||SI||SISPI":   PN = "AA21"  !CDS_PN = "AA21";
"PB46C":   PN = "V17"  !CDS_PN = "V17";
"PB46D":   PN = "T16"  !CDS_PN = "T16";
BODY = "Q_RES","I3": LOCATION = "R1465" #&CDS_LOCATION = "R1465" &SEC = "1" #&CDS_SEC = "1";
"A":   PN = "1"  !CDS_PN = "1";
"B":   PN = "2"  !CDS_PN = "2";
BODY = "Q_RES","I5": LOCATION = "R1106" #&CDS_LOCATION = "R1106" &SEC = "1" #&CDS_SEC = "1";
"A":   PN = "1"  !CDS_PN = "1";
"B":   PN = "2"  !CDS_PN = "2";
BODY = "Q_RES","I38": LOCATION = "R1710" #&CDS_LOCATION = "R1710" &SEC = "1" #&CDS_SEC = "1";
"A":   PN = "1"  !CDS_PN = "1";
"B":   PN = "2"  !CDS_PN = "2";
BODY = "Q_CAP","I39": LOCATION = "C1325" #&CDS_LOCATION = "C1325" &SEC = "1" #&CDS_SEC = "1";
"A":   PN = "1"  !CDS_PN = "1";
"B":   PN = "2"  !CDS_PN = "2";
BODY = "Q_RES","I80": LOCATION = "R4056" #&CDS_LOCATION = "R4056" &SEC = "1" #&CDS_SEC = "1";
"A":   PN = "1"  !CDS_PN = "1";
"B":   PN = "2"  !CDS_PN = "2";
BODY = "Q_RES","I86": LOCATION = "R4086" #&CDS_LOCATION = "R4086" &SEC = "1" #&CDS_SEC = "1";
"A":   PN = "1"  !CDS_PN = "1";
"B":   PN = "2"  !CDS_PN = "2";
BODY = "Q_RES","I89": LOCATION = "R4143" #&CDS_LOCATION = "R4143" &SEC = "1" #&CDS_SEC = "1";
"A":   PN = "1"  !CDS_PN = "1";
"B":   PN = "2"  !CDS_PN = "2";
BODY = "Q_RES","I93": LOCATION = "R4144" #&CDS_LOCATION = "R4144" &SEC = "1" #&CDS_SEC = "1";
"A":   PN = "1"  !CDS_PN = "1";
"B":   PN = "2"  !CDS_PN = "2";
BODY = "Q_RES","I97": LOCATION = "R4145" #&CDS_LOCATION = "R4145" &SEC = "1" #&CDS_SEC = "1";
"A":   PN = "1"  !CDS_PN = "1";
"B":   PN = "2"  !CDS_PN = "2";
BODY = "Q_RES","I98": LOCATION = "R4146" #&CDS_LOCATION = "R4146" &SEC = "1" #&CDS_SEC = "1";
"A":   PN = "1"  !CDS_PN = "1";
"B":   PN = "2"  !CDS_PN = "2";
BODY = "Q_RES","I103": LOCATION = "R4148" #&CDS_LOCATION = "R4148" &SEC = "1" #&CDS_SEC = "1";
"A":   PN = "1"  !CDS_PN = "1";
"B":   PN = "2"  !CDS_PN = "2";
BODY = "Q_RES","I104": LOCATION = "R4147" #&CDS_LOCATION = "R4147" &SEC = "1" #&CDS_SEC = "1";
"A":   PN = "1"  !CDS_PN = "1";
"B":   PN = "2"  !CDS_PN = "2";
BODY = "Q_RES","I114": LOCATION = "R4157" #&CDS_LOCATION = "R4157" &SEC = "1" #&CDS_SEC = "1";
"A":   PN = "1"  !CDS_PN = "1";
"B":   PN = "2"  !CDS_PN = "2";
BODY = "Q_RES","I120": LOCATION = "R4170" #&CDS_LOCATION = "R4170" &SEC = "1" #&CDS_SEC = "1";
"A":   PN = "1"  !CDS_PN = "1";
"B":   PN = "2"  !CDS_PN = "2";
BODY = "Q_RES","I121": LOCATION = "R4171" #&CDS_LOCATION = "R4171" &SEC = "1" #&CDS_SEC = "1";
"A":   PN = "1"  !CDS_PN = "1";
"B":   PN = "2"  !CDS_PN = "2";
BODY = "Q_RES","I122": LOCATION = "R4172" #&CDS_LOCATION = "R4172" &SEC = "1" #&CDS_SEC = "1";
"A":   PN = "1"  !CDS_PN = "1";
"B":   PN = "2"  !CDS_PN = "2";
BODY = "Q_RES","I134": LOCATION = "R4174" #&CDS_LOCATION = "R4174" &SEC = "1" #&CDS_SEC = "1";
"A":   PN = "1"  !CDS_PN = "1";
"B":   PN = "2"  !CDS_PN = "2";
BODY = "Q_RES","I135": LOCATION = "R4175" #&CDS_LOCATION = "R4175" &SEC = "1" #&CDS_SEC = "1";
"A":   PN = "1"  !CDS_PN = "1";
"B":   PN = "2"  !CDS_PN = "2";
BODY = "Q_RES","I143": LOCATION = "R4556" #&CDS_LOCATION = "R4556" &SEC = "1" #&CDS_SEC = "1";
"A":   PN = "1"  !CDS_PN = "1";
"B":   PN = "2"  !CDS_PN = "2";
BODY = "Q_RES","I145": LOCATION = "R4557" #&CDS_LOCATION = "R4557" &SEC = "1" #&CDS_SEC = "1";
"A":   PN = "1"  !CDS_PN = "1";
"B":   PN = "2"  !CDS_PN = "2";
BODY = "Q_RES","I150": LOCATION = "R4558" #&CDS_LOCATION = "R4558" &SEC = "1" #&CDS_SEC = "1";
"A":   PN = "1"  !CDS_PN = "1";
"B":   PN = "2"  !CDS_PN = "2";
BODY = "Q_RES","I158": LOCATION = "R4563" #&CDS_LOCATION = "R4563" &SEC = "1" #&CDS_SEC = "1";
"A":   PN = "1"  !CDS_PN = "1";
"B":   PN = "2"  !CDS_PN = "2";
BODY = "Q_RES","I164": LOCATION = "R3045" #&CDS_LOCATION = "R3045" &SEC = "1" #&CDS_SEC = "1";
"A":   PN = "1"  !CDS_PN = "1";
"B":   PN = "2"  !CDS_PN = "2";
BODY = "Q_RES","I165": LOCATION = "R3046" #&CDS_LOCATION = "R3046" &SEC = "1" #&CDS_SEC = "1";
"A":   PN = "1"  !CDS_PN = "1";
"B":   PN = "2"  !CDS_PN = "2";
BODY = "Q_RES","I169": LOCATION = "R700" #&CDS_LOCATION = "R700" &SEC = "1" #&CDS_SEC = "1";
"A":   PN = "1"  !CDS_PN = "1";
"B":   PN = "2"  !CDS_PN = "2";
BODY = "Q_RES","I170": LOCATION = "R1944" #&CDS_LOCATION = "R1944" &SEC = "1" #&CDS_SEC = "1";
"A":   PN = "1"  !CDS_PN = "1";
"B":   PN = "2"  !CDS_PN = "2";
BODY = "Q_RES","I176": LOCATION = "R3049" #&CDS_LOCATION = "R3049" &SEC = "1" #&CDS_SEC = "1";
"A":   PN = "1"  !CDS_PN = "1";
"B":   PN = "2"  !CDS_PN = "2";
BODY = "Q_RES","I177": LOCATION = "R2155" #&CDS_LOCATION = "R2155" &SEC = "1" #&CDS_SEC = "1";
"A":   PN = "1"  !CDS_PN = "1";
"B":   PN = "2"  !CDS_PN = "2";
BODY = "Q_RES","I178": LOCATION = "R2792" #&CDS_LOCATION = "R2792" &SEC = "1" #&CDS_SEC = "1";
"A":   PN = "1"  !CDS_PN = "1";
"B":   PN = "2"  !CDS_PN = "2";
BODY = "Q_RES","I183": LOCATION = "R2347" #&CDS_LOCATION = "R2347" &SEC = "1" #&CDS_SEC = "1";
"A":   PN = "1"  !CDS_PN = "1";
"B":   PN = "2"  !CDS_PN = "2";
BODY = "Q_RES","I184": LOCATION = "R2348" #&CDS_LOCATION = "R2348" &SEC = "1" #&CDS_SEC = "1";
"A":   PN = "1"  !CDS_PN = "1";
"B":   PN = "2"  !CDS_PN = "2";
BODY = "CONN3_210HP1030BR1","I187": LOCATION = "JP15" #&CDS_LOCATION = "JP15" &SEC = "1" #&CDS_SEC = "1";
"1":   PN = "1"  !CDS_PN = "1";
"2":   PN = "2"  !CDS_PN = "2";
"3":   PN = "3"  !CDS_PN = "3";
BODY = "Q_RES","I190": LOCATION = "R1495" #&CDS_LOCATION = "R1495" &SEC = "1" #&CDS_SEC = "1";
"A":   PN = "1"  !CDS_PN = "1";
"B":   PN = "2"  !CDS_PN = "2";
BODY = "Q_RES","I191": LOCATION = "R1493" #&CDS_LOCATION = "R1493" &SEC = "1" #&CDS_SEC = "1";
"A":   PN = "1"  !CDS_PN = "1";
"B":   PN = "2"  !CDS_PN = "2";
BODY = "Q_RES","I213": LOCATION = "R4723" #&CDS_LOCATION = "R4723" &SEC = "1" #&CDS_SEC = "1";
"A":   PN = "1"  !CDS_PN = "1";
"B":   PN = "2"  !CDS_PN = "2";
BODY = "Q_RES","I217": #LOCATION = "R4057" !CDS_LOCATION = "R4057" &SEC = "1" #&CDS_SEC = "1";
"A":   PN = "1"  !CDS_PN = "1";
"B":   PN = "2"  !CDS_PN = "2";
DRAWING = "@s9s_mb_2u_lib.s9s_mb_2u(sch_1):page311";
BODY = "Q_RES","I4": LOCATION = "R1823" #&CDS_LOCATION = "R1823" &SEC = "1" #&CDS_SEC = "1";
"A":   PN = "1"  !CDS_PN = "1";
"B":   PN = "2"  !CDS_PN = "2";
BODY = "Q_RES","I29": LOCATION = "R3249" #&CDS_LOCATION = "R3249" &SEC = "1" #&CDS_SEC = "1";
"A":   PN = "1"  !CDS_PN = "1";
"B":   PN = "2"  !CDS_PN = "2";
BODY = "LCMXO3LF9400C5BG484C","I33": LOCATION = "U249" #&CDS_LOCATION = "U249" &SEC = "1" #&CDS_SEC = "1";
"PL2A":   PN = "D3"  !CDS_PN = "D3";
"PL2B":   PN = "D4"  !CDS_PN = "D4";
"PL2C":   PN = "F6"  !CDS_PN = "F6";
"PL2D":   PN = "G7"  !CDS_PN = "G7";
"PL3A||L_GPLLT_FB":   PN = "E4"  !CDS_PN = "E4";
"PL3B||L_GPLLC_FB":   PN = "F5"  !CDS_PN = "F5";
"PL3C":   PN = "G6"  !CDS_PN = "G6";
"PL3D":   PN = "H7"  !CDS_PN = "H7";
"PL4A||L_GPLLT_IN":   PN = "C1"  !CDS_PN = "C1";
"PL4B||L_GPLLC_IN":   PN = "D2"  !CDS_PN = "D2";
"PL4C":   PN = "G5"  !CDS_PN = "G5";
"PL4D":   PN = "H6"  !CDS_PN = "H6";
"PL5A":   PN = "D1"  !CDS_PN = "D1";
"PL5B":   PN = "E2"  !CDS_PN = "E2";
"PL5C":   PN = "E3"  !CDS_PN = "E3";
"PL5D":   PN = "F4"  !CDS_PN = "F4";
"PL6A":   PN = "E1"  !CDS_PN = "E1";
"PL6B":   PN = "F1"  !CDS_PN = "F1";
"PL6C":   PN = "G3"  !CDS_PN = "G3";
"PL6D":   PN = "G4"  !CDS_PN = "G4";
"PL7A||PCLKT5_0":   PN = "G2"  !CDS_PN = "G2";
"PL7B||PCLKC5_0":   PN = "G1"  !CDS_PN = "G1";
"PL7C":   PN = "H4"  !CDS_PN = "H4";
"PL7D":   PN = "H3"  !CDS_PN = "H3";
"PL10A":   PN = "H2"  !CDS_PN = "H2";
"PL10B":   PN = "H1"  !CDS_PN = "H1";
"PL10C":   PN = "J7"  !CDS_PN = "J7";
"PL10D":   PN = "J6"  !CDS_PN = "J6";
"PL11A":   PN = "H5"  !CDS_PN = "H5";
"PL11B":   PN = "J5"  !CDS_PN = "J5";
"PL11C":   PN = "J4"  !CDS_PN = "J4";
"PL11D":   PN = "J3"  !CDS_PN = "J3";
"PL12A":   PN = "J2"  !CDS_PN = "J2";
"PL12B":   PN = "J1"  !CDS_PN = "J1";
"PL12C":   PN = "K7"  !CDS_PN = "K7";
"PL12D":   PN = "K6"  !CDS_PN = "K6";
"PL13A":   PN = "L7"  !CDS_PN = "L7";
"PL13B":   PN = "K5"  !CDS_PN = "K5";
"PL13C":   PN = "K4"  !CDS_PN = "K4";
"PL13D":   PN = "K3"  !CDS_PN = "K3";
"PL14A":   PN = "K2"  !CDS_PN = "K2";
"PL14B":   PN = "K1"  !CDS_PN = "K1";
"PL14C":   PN = "L6"  !CDS_PN = "L6";
"PL14D":   PN = "L5"  !CDS_PN = "L5";
"PL16A||PCLKT4_0":   PN = "L1"  !CDS_PN = "L1";
"PL16B||PCLKC4_0":   PN = "M2"  !CDS_PN = "M2";
"PL16C":   PN = "L3"  !CDS_PN = "L3";
"PL16D":   PN = "L4"  !CDS_PN = "L4";
"PL17A":   PN = "M1"  !CDS_PN = "M1";
"PL17B":   PN = "N1"  !CDS_PN = "N1";
"PL17C":   PN = "M6"  !CDS_PN = "M6";
"PL17D":   PN = "M5"  !CDS_PN = "M5";
"PL18A":   PN = "N2"  !CDS_PN = "N2";
"PL18B":   PN = "P1"  !CDS_PN = "P1";
"PL18C":   PN = "N3"  !CDS_PN = "N3";
"PL18D":   PN = "N4"  !CDS_PN = "N4";
"PL19A":   PN = "P2"  !CDS_PN = "P2";
"PL19B":   PN = "R1"  !CDS_PN = "R1";
"PL19C":   PN = "P3"  !CDS_PN = "P3";
"PL19D":   PN = "M7"  !CDS_PN = "M7";
"PL20A":   PN = "P4"  !CDS_PN = "P4";
"PL20B":   PN = "N5"  !CDS_PN = "N5";
"PL20C":   PN = "N6"  !CDS_PN = "N6";
"PL20D":   PN = "N7"  !CDS_PN = "N7";
"PL21A":   PN = "R2"  !CDS_PN = "R2";
"PL21B":   PN = "T1"  !CDS_PN = "T1";
"PL21C":   PN = "P5"  !CDS_PN = "P5";
"PL21D":   PN = "P6"  !CDS_PN = "P6";
"PL24A":   PN = "R3"  !CDS_PN = "R3";
"PL24B":   PN = "R4"  !CDS_PN = "R4";
"PL24C":   PN = "R5"  !CDS_PN = "R5";
"PL24D":   PN = "P7"  !CDS_PN = "P7";
"PL25A":   PN = "T2"  !CDS_PN = "T2";
"PL25B":   PN = "U1"  !CDS_PN = "U1";
"PL25C":   PN = "R6"  !CDS_PN = "R6";
"PL25D":   PN = "R7"  !CDS_PN = "R7";
"PL26A":   PN = "T3"  !CDS_PN = "T3";
"PL26B":   PN = "T4"  !CDS_PN = "T4";
"PL26C":   PN = "T5"  !CDS_PN = "T5";
"PL26D":   PN = "T6"  !CDS_PN = "T6";
"PL27A||PCLKT3_0":   PN = "U2"  !CDS_PN = "U2";
"PL27B||PCLKC3_0":   PN = "V1"  !CDS_PN = "V1";
"PL27C":   PN = "U3"  !CDS_PN = "U3";
"PL27D":   PN = "U4"  !CDS_PN = "U4";
"PL28A":   PN = "W1"  !CDS_PN = "W1";
"PL28B":   PN = "W2"  !CDS_PN = "W2";
"PL28C":   PN = "V4"  !CDS_PN = "V4";
"PL28D":   PN = "U5"  !CDS_PN = "U5";
"PL29A":   PN = "Y1"  !CDS_PN = "Y1";
"PL29B":   PN = "AA1"  !CDS_PN = "AA1";
"PL29C":   PN = "W3"  !CDS_PN = "W3";
"PL29D":   PN = "Y2"  !CDS_PN = "Y2";
"PL30A":   PN = "Y3"  !CDS_PN = "Y3";
"PL30B":   PN = "W4"  !CDS_PN = "W4";
"PL30C":   PN = "V5"  !CDS_PN = "V5";
"PL30D":   PN = "T7"  !CDS_PN = "T7";
BODY = "LCMXO3LF9400C5BG484C","I70": LOCATION = "U249" #&CDS_LOCATION = "U249" &SEC = "4" #&CDS_SEC = "4";
"PT15C||TDO":   PN = "E8"  !CDS_PN = "E8";
"PT15D||TDI":   PN = "E9"  !CDS_PN = "E9";
"PT22C||TCK":   PN = "D10"  !CDS_PN = "D10";
"PT22D||TMS":   PN = "C10"  !CDS_PN = "C10";
"PT31C||JTAGENB":   PN = "E14"  !CDS_PN = "E14";
"PT31D||PROGRAMN":   PN = "E15"  !CDS_PN = "E15";
"PT44C||INITN":   PN = "F16"  !CDS_PN = "F16";
"PT44D||DONE":   PN = "E17"  !CDS_PN = "E17";
BODY = "Q_RES","I79": LOCATION = "R4751" #&CDS_LOCATION = "R4751" &SEC = "1" #&CDS_SEC = "1";
"A":   PN = "1"  !CDS_PN = "1";
"B":   PN = "2"  !CDS_PN = "2";
BODY = "Q_RES","I86": LOCATION = "R4760" #&CDS_LOCATION = "R4760" &SEC = "1" #&CDS_SEC = "1";
"A":   PN = "1"  !CDS_PN = "1";
"B":   PN = "2"  !CDS_PN = "2";
BODY = "Q_RES","I90": LOCATION = "R4765" #&CDS_LOCATION = "R4765" &SEC = "1" #&CDS_SEC = "1";
"A":   PN = "1"  !CDS_PN = "1";
"B":   PN = "2"  !CDS_PN = "2";
BODY = "Q_RES","I95": LOCATION = "R4771" #&CDS_LOCATION = "R4771" &SEC = "1" #&CDS_SEC = "1";
"A":   PN = "1"  !CDS_PN = "1";
"B":   PN = "2"  !CDS_PN = "2";
DRAWING = "@s9s_mb_2u_lib.s9s_mb_2u(sch_1):page202";
BODY = "LCMXO3LF9400C5BG484C","I1": LOCATION = "U249" #&CDS_LOCATION = "U249" &SEC = "6" #&CDS_SEC = "6";
"GND1":   PN = "A1"  !CDS_PN = "A1";
"GND2":   PN = "A22"  !CDS_PN = "A22";
"GND3":   PN = "B7"  !CDS_PN = "B7";
"GND4":   PN = "B16"  !CDS_PN = "B16";
"GND5":   PN = "C2"  !CDS_PN = "C2";
"GND6":   PN = "C11"  !CDS_PN = "C11";
"GND7":   PN = "E5"  !CDS_PN = "E5";
"GND8":   PN = "E18"  !CDS_PN = "E18";
"GND9":   PN = "F2"  !CDS_PN = "F2";
"GND10":   PN = "F21"  !CDS_PN = "F21";
"GND11":   PN = "H8"  !CDS_PN = "H8";
"GND12":   PN = "H10"  !CDS_PN = "H10";
"GND13":   PN = "H13"  !CDS_PN = "H13";
"GND14":   PN = "H15"  !CDS_PN = "H15";
"GND15":   PN = "J9"  !CDS_PN = "J9";
"GND16":   PN = "J10"  !CDS_PN = "J10";
"GND17":   PN = "J11"  !CDS_PN = "J11";
"GND18":   PN = "J12"  !CDS_PN = "J12";
"GND19":   PN = "J13"  !CDS_PN = "J13";
"GND20":   PN = "J14"  !CDS_PN = "J14";
"GND21":   PN = "K9"  !CDS_PN = "K9";
"GND22":   PN = "K14"  !CDS_PN = "K14";
"GND23":   PN = "K21"  !CDS_PN = "K21";
"GND24":   PN = "L2"  !CDS_PN = "L2";
"GND25":   PN = "L9"  !CDS_PN = "L9";
"GND26":   PN = "L10"  !CDS_PN = "L10";
"GND27":   PN = "L13"  !CDS_PN = "L13";
"GND28":   PN = "L14"  !CDS_PN = "L14";
"GND29":   PN = "L18"  !CDS_PN = "L18";
"GND30":   PN = "M4"  !CDS_PN = "M4";
"GND31":   PN = "M9"  !CDS_PN = "M9";
"GND32":   PN = "M10"  !CDS_PN = "M10";
"GND33":   PN = "M13"  !CDS_PN = "M13";
"GND34":   PN = "M14"  !CDS_PN = "M14";
"GND35":   PN = "N9"  !CDS_PN = "N9";
"GND36":   PN = "N14"  !CDS_PN = "N14";
"GND37":   PN = "N21"  !CDS_PN = "N21";
"GND38":   PN = "P9"  !CDS_PN = "P9";
"GND39":   PN = "P10"  !CDS_PN = "P10";
"GND40":   PN = "P11"  !CDS_PN = "P11";
"GND41":   PN = "P12"  !CDS_PN = "P12";
"GND42":   PN = "P13"  !CDS_PN = "P13";
"GND43":   PN = "P14"  !CDS_PN = "P14";
"GND44":   PN = "R8"  !CDS_PN = "R8";
"GND45":   PN = "R15"  !CDS_PN = "R15";
"GND46":   PN = "V2"  !CDS_PN = "V2";
"GND47":   PN = "V21"  !CDS_PN = "V21";
"GND48":   PN = "W12"  !CDS_PN = "W12";
"GND49":   PN = "Y7"  !CDS_PN = "Y7";
"GND50":   PN = "Y16"  !CDS_PN = "Y16";
"GND51":   PN = "AB1"  !CDS_PN = "AB1";
"GND52":   PN = "AB22"  !CDS_PN = "AB22";
BODY = "Q_CAP","I3": LOCATION = "C1154" #&CDS_LOCATION = "C1154" &SEC = "1" #&CDS_SEC = "1";
"A":   PN = "1"  !CDS_PN = "1";
"B":   PN = "2"  !CDS_PN = "2";
BODY = "Q_CAP","I5": LOCATION = "C1152" #&CDS_LOCATION = "C1152" &SEC = "1" #&CDS_SEC = "1";
"A":   PN = "1"  !CDS_PN = "1";
"B":   PN = "2"  !CDS_PN = "2";
BODY = "Q_CAP","I9": LOCATION = "C1932" #&CDS_LOCATION = "C1932" &SEC = "1" #&CDS_SEC = "1";
"A":   PN = "1"  !CDS_PN = "1";
"B":   PN = "2"  !CDS_PN = "2";
BODY = "Q_CAP","I12": LOCATION = "C1933" #&CDS_LOCATION = "C1933" &SEC = "1" #&CDS_SEC = "1";
"A":   PN = "1"  !CDS_PN = "1";
"B":   PN = "2"  !CDS_PN = "2";
BODY = "Q_CAP","I15": LOCATION = "C1146" #&CDS_LOCATION = "C1146" &SEC = "1" #&CDS_SEC = "1";
"A":   PN = "1"  !CDS_PN = "1";
"B":   PN = "2"  !CDS_PN = "2";
BODY = "Q_CAP","I18": LOCATION = "C1904" #&CDS_LOCATION = "C1904" &SEC = "1" #&CDS_SEC = "1";
"A":   PN = "1"  !CDS_PN = "1";
"B":   PN = "2"  !CDS_PN = "2";
BODY = "Q_CAP","I20": LOCATION = "C1898" #&CDS_LOCATION = "C1898" &SEC = "1" #&CDS_SEC = "1";
"A":   PN = "1"  !CDS_PN = "1";
"B":   PN = "2"  !CDS_PN = "2";
BODY = "Q_CAP","I21": LOCATION = "C1931" #&CDS_LOCATION = "C1931" &SEC = "1" #&CDS_SEC = "1";
"A":   PN = "1"  !CDS_PN = "1";
"B":   PN = "2"  !CDS_PN = "2";
BODY = "Q_CAP","I22": LOCATION = "C1928" #&CDS_LOCATION = "C1928" &SEC = "1" #&CDS_SEC = "1";
"A":   PN = "1"  !CDS_PN = "1";
"B":   PN = "2"  !CDS_PN = "2";
BODY = "Q_CAP","I23": LOCATION = "C1919" #&CDS_LOCATION = "C1919" &SEC = "1" #&CDS_SEC = "1";
"A":   PN = "1"  !CDS_PN = "1";
"B":   PN = "2"  !CDS_PN = "2";
BODY = "Q_CAP","I24": LOCATION = "C1916" #&CDS_LOCATION = "C1916" &SEC = "1" #&CDS_SEC = "1";
"A":   PN = "1"  !CDS_PN = "1";
"B":   PN = "2"  !CDS_PN = "2";
BODY = "Q_CAP","I25": LOCATION = "C1907" #&CDS_LOCATION = "C1907" &SEC = "1" #&CDS_SEC = "1";
"A":   PN = "1"  !CDS_PN = "1";
"B":   PN = "2"  !CDS_PN = "2";
BODY = "Q_CAP","I26": LOCATION = "C1903" #&CDS_LOCATION = "C1903" &SEC = "1" #&CDS_SEC = "1";
"A":   PN = "1"  !CDS_PN = "1";
"B":   PN = "2"  !CDS_PN = "2";
BODY = "Q_CAP","I27": LOCATION = "C1897" #&CDS_LOCATION = "C1897" &SEC = "1" #&CDS_SEC = "1";
"A":   PN = "1"  !CDS_PN = "1";
"B":   PN = "2"  !CDS_PN = "2";
BODY = "Q_CAP","I28": LOCATION = "C1912" #&CDS_LOCATION = "C1912" &SEC = "1" #&CDS_SEC = "1";
"A":   PN = "1"  !CDS_PN = "1";
"B":   PN = "2"  !CDS_PN = "2";
BODY = "Q_CAP","I29": LOCATION = "C1943" #&CDS_LOCATION = "C1943" &SEC = "1" #&CDS_SEC = "1";
"A":   PN = "1"  !CDS_PN = "1";
"B":   PN = "2"  !CDS_PN = "2";
BODY = "Q_CAP","I30": LOCATION = "C1936" #&CDS_LOCATION = "C1936" &SEC = "1" #&CDS_SEC = "1";
"A":   PN = "1"  !CDS_PN = "1";
"B":   PN = "2"  !CDS_PN = "2";
BODY = "Q_CAP","I33": LOCATION = "C1929" #&CDS_LOCATION = "C1929" &SEC = "1" #&CDS_SEC = "1";
"A":   PN = "1"  !CDS_PN = "1";
"B":   PN = "2"  !CDS_PN = "2";
BODY = "Q_CAP","I34": LOCATION = "C1926" #&CDS_LOCATION = "C1926" &SEC = "1" #&CDS_SEC = "1";
"A":   PN = "1"  !CDS_PN = "1";
"B":   PN = "2"  !CDS_PN = "2";
BODY = "Q_CAP","I35": LOCATION = "C1917" #&CDS_LOCATION = "C1917" &SEC = "1" #&CDS_SEC = "1";
"A":   PN = "1"  !CDS_PN = "1";
"B":   PN = "2"  !CDS_PN = "2";
BODY = "Q_CAP","I36": LOCATION = "C1914" #&CDS_LOCATION = "C1914" &SEC = "1" #&CDS_SEC = "1";
"A":   PN = "1"  !CDS_PN = "1";
"B":   PN = "2"  !CDS_PN = "2";
BODY = "Q_CAP","I37": LOCATION = "C1930" #&CDS_LOCATION = "C1930" &SEC = "1" #&CDS_SEC = "1";
"A":   PN = "1"  !CDS_PN = "1";
"B":   PN = "2"  !CDS_PN = "2";
BODY = "Q_CAP","I38": LOCATION = "C1927" #&CDS_LOCATION = "C1927" &SEC = "1" #&CDS_SEC = "1";
"A":   PN = "1"  !CDS_PN = "1";
"B":   PN = "2"  !CDS_PN = "2";
BODY = "Q_CAP","I39": LOCATION = "C1918" #&CDS_LOCATION = "C1918" &SEC = "1" #&CDS_SEC = "1";
"A":   PN = "1"  !CDS_PN = "1";
"B":   PN = "2"  !CDS_PN = "2";
BODY = "Q_CAP","I40": LOCATION = "C1915" #&CDS_LOCATION = "C1915" &SEC = "1" #&CDS_SEC = "1";
"A":   PN = "1"  !CDS_PN = "1";
"B":   PN = "2"  !CDS_PN = "2";
BODY = "Q_CAP","I41": LOCATION = "C1905" #&CDS_LOCATION = "C1905" &SEC = "1" #&CDS_SEC = "1";
"A":   PN = "1"  !CDS_PN = "1";
"B":   PN = "2"  !CDS_PN = "2";
BODY = "Q_CAP","I42": LOCATION = "C1901" #&CDS_LOCATION = "C1901" &SEC = "1" #&CDS_SEC = "1";
"A":   PN = "1"  !CDS_PN = "1";
"B":   PN = "2"  !CDS_PN = "2";
BODY = "Q_CAP","I43": LOCATION = "C1895" #&CDS_LOCATION = "C1895" &SEC = "1" #&CDS_SEC = "1";
"A":   PN = "1"  !CDS_PN = "1";
"B":   PN = "2"  !CDS_PN = "2";
BODY = "Q_CAP","I44": LOCATION = "C1910" #&CDS_LOCATION = "C1910" &SEC = "1" #&CDS_SEC = "1";
"A":   PN = "1"  !CDS_PN = "1";
"B":   PN = "2"  !CDS_PN = "2";
BODY = "Q_CAP","I45": LOCATION = "C1906" #&CDS_LOCATION = "C1906" &SEC = "1" #&CDS_SEC = "1";
"A":   PN = "1"  !CDS_PN = "1";
"B":   PN = "2"  !CDS_PN = "2";
BODY = "Q_CAP","I46": LOCATION = "C1902" #&CDS_LOCATION = "C1902" &SEC = "1" #&CDS_SEC = "1";
"A":   PN = "1"  !CDS_PN = "1";
"B":   PN = "2"  !CDS_PN = "2";
BODY = "Q_CAP","I47": LOCATION = "C1896" #&CDS_LOCATION = "C1896" &SEC = "1" #&CDS_SEC = "1";
"A":   PN = "1"  !CDS_PN = "1";
"B":   PN = "2"  !CDS_PN = "2";
BODY = "Q_CAP","I48": LOCATION = "C1911" #&CDS_LOCATION = "C1911" &SEC = "1" #&CDS_SEC = "1";
"A":   PN = "1"  !CDS_PN = "1";
"B":   PN = "2"  !CDS_PN = "2";
BODY = "Q_CAP","I49": LOCATION = "C1142" #&CDS_LOCATION = "C1142" &SEC = "1" #&CDS_SEC = "1";
"A":   PN = "1"  !CDS_PN = "1";
"B":   PN = "2"  !CDS_PN = "2";
BODY = "Q_CAP","I50": LOCATION = "C1138" #&CDS_LOCATION = "C1138" &SEC = "1" #&CDS_SEC = "1";
"A":   PN = "1"  !CDS_PN = "1";
"B":   PN = "2"  !CDS_PN = "2";
BODY = "Q_CAP","I51": LOCATION = "C1133" #&CDS_LOCATION = "C1133" &SEC = "1" #&CDS_SEC = "1";
"A":   PN = "1"  !CDS_PN = "1";
"B":   PN = "2"  !CDS_PN = "2";
BODY = "Q_CAP","I52": LOCATION = "C1127" #&CDS_LOCATION = "C1127" &SEC = "1" #&CDS_SEC = "1";
"A":   PN = "1"  !CDS_PN = "1";
"B":   PN = "2"  !CDS_PN = "2";
BODY = "Q_CAP","I53": LOCATION = "C1913" #&CDS_LOCATION = "C1913" &SEC = "1" #&CDS_SEC = "1";
"A":   PN = "1"  !CDS_PN = "1";
"B":   PN = "2"  !CDS_PN = "2";
BODY = "Q_CAP","I54": LOCATION = "C1947" #&CDS_LOCATION = "C1947" &SEC = "1" #&CDS_SEC = "1";
"A":   PN = "1"  !CDS_PN = "1";
"B":   PN = "2"  !CDS_PN = "2";
BODY = "Q_CAP","I55": LOCATION = "C1940" #&CDS_LOCATION = "C1940" &SEC = "1" #&CDS_SEC = "1";
"A":   PN = "1"  !CDS_PN = "1";
"B":   PN = "2"  !CDS_PN = "2";
BODY = "Q_CAP","I56": LOCATION = "C1122" #&CDS_LOCATION = "C1122" &SEC = "1" #&CDS_SEC = "1";
"A":   PN = "1"  !CDS_PN = "1";
"B":   PN = "2"  !CDS_PN = "2";
BODY = "Q_CAP","I57": LOCATION = "C1900" #&CDS_LOCATION = "C1900" &SEC = "1" #&CDS_SEC = "1";
"A":   PN = "1"  !CDS_PN = "1";
"B":   PN = "2"  !CDS_PN = "2";
BODY = "Q_CAP","I58": LOCATION = "C1894" #&CDS_LOCATION = "C1894" &SEC = "1" #&CDS_SEC = "1";
"A":   PN = "1"  !CDS_PN = "1";
"B":   PN = "2"  !CDS_PN = "2";
BODY = "Q_CAP","I59": LOCATION = "C1909" #&CDS_LOCATION = "C1909" &SEC = "1" #&CDS_SEC = "1";
"A":   PN = "1"  !CDS_PN = "1";
"B":   PN = "2"  !CDS_PN = "2";
BODY = "Q_RES","I60": LOCATION = "R3349" #&CDS_LOCATION = "R3349" &SEC = "1" #&CDS_SEC = "1";
"A":   PN = "1"  !CDS_PN = "1";
"B":   PN = "2"  !CDS_PN = "2";
BODY = "Q_CAP","I62": LOCATION = "C1945" #&CDS_LOCATION = "C1945" &SEC = "1" #&CDS_SEC = "1";
"A":   PN = "1"  !CDS_PN = "1";
"B":   PN = "2"  !CDS_PN = "2";
BODY = "Q_RES","I63": LOCATION = "R3346" #&CDS_LOCATION = "R3346" &SEC = "1" #&CDS_SEC = "1";
"A":   PN = "1"  !CDS_PN = "1";
"B":   PN = "2"  !CDS_PN = "2";
BODY = "Q_CAP","I64": LOCATION = "C1938" #&CDS_LOCATION = "C1938" &SEC = "1" #&CDS_SEC = "1";
"A":   PN = "1"  !CDS_PN = "1";
"B":   PN = "2"  !CDS_PN = "2";
BODY = "Q_CAP","I65": LOCATION = "C1946" #&CDS_LOCATION = "C1946" &SEC = "1" #&CDS_SEC = "1";
"A":   PN = "1"  !CDS_PN = "1";
"B":   PN = "2"  !CDS_PN = "2";
BODY = "Q_CAP","I66": LOCATION = "C1939" #&CDS_LOCATION = "C1939" &SEC = "1" #&CDS_SEC = "1";
"A":   PN = "1"  !CDS_PN = "1";
"B":   PN = "2"  !CDS_PN = "2";
BODY = "Q_RES","I67": LOCATION = "R3348" #&CDS_LOCATION = "R3348" &SEC = "1" #&CDS_SEC = "1";
"A":   PN = "1"  !CDS_PN = "1";
"B":   PN = "2"  !CDS_PN = "2";
BODY = "Q_CAP","I70": LOCATION = "C1944" #&CDS_LOCATION = "C1944" &SEC = "1" #&CDS_SEC = "1";
"A":   PN = "1"  !CDS_PN = "1";
"B":   PN = "2"  !CDS_PN = "2";
BODY = "Q_CAP","I71": LOCATION = "C1937" #&CDS_LOCATION = "C1937" &SEC = "1" #&CDS_SEC = "1";
"A":   PN = "1"  !CDS_PN = "1";
"B":   PN = "2"  !CDS_PN = "2";
BODY = "Q_RES","I72": LOCATION = "R3347" #&CDS_LOCATION = "R3347" &SEC = "1" #&CDS_SEC = "1";
"A":   PN = "1"  !CDS_PN = "1";
"B":   PN = "2"  !CDS_PN = "2";
BODY = "Q_CAP","I74": LOCATION = "C1899" #&CDS_LOCATION = "C1899" &SEC = "1" #&CDS_SEC = "1";
"A":   PN = "1"  !CDS_PN = "1";
"B":   PN = "2"  !CDS_PN = "2";
BODY = "Q_CAP","I76": LOCATION = "C1893" #&CDS_LOCATION = "C1893" &SEC = "1" #&CDS_SEC = "1";
"A":   PN = "1"  !CDS_PN = "1";
"B":   PN = "2"  !CDS_PN = "2";
BODY = "Q_CAP","I77": LOCATION = "C1908" #&CDS_LOCATION = "C1908" &SEC = "1" #&CDS_SEC = "1";
"A":   PN = "1"  !CDS_PN = "1";
"B":   PN = "2"  !CDS_PN = "2";
BODY = "Q_CAP","I80": LOCATION = "C1942" #&CDS_LOCATION = "C1942" &SEC = "1" #&CDS_SEC = "1";
"A":   PN = "1"  !CDS_PN = "1";
"B":   PN = "2"  !CDS_PN = "2";
BODY = "Q_RES","I81": LOCATION = "R3345" #&CDS_LOCATION = "R3345" &SEC = "1" #&CDS_SEC = "1";
"A":   PN = "1"  !CDS_PN = "1";
"B":   PN = "2"  !CDS_PN = "2";
BODY = "Q_CAP","I82": LOCATION = "C1935" #&CDS_LOCATION = "C1935" &SEC = "1" #&CDS_SEC = "1";
"A":   PN = "1"  !CDS_PN = "1";
"B":   PN = "2"  !CDS_PN = "2";
BODY = "Q_CAP","I97": LOCATION = "C1118" #&CDS_LOCATION = "C1118" &SEC = "1" #&CDS_SEC = "1";
"A":   PN = "1"  !CDS_PN = "1";
"B":   PN = "2"  !CDS_PN = "2";
BODY = "Q_CAP","I99": LOCATION = "C1113" #&CDS_LOCATION = "C1113" &SEC = "1" #&CDS_SEC = "1";
"A":   PN = "1"  !CDS_PN = "1";
"B":   PN = "2"  !CDS_PN = "2";
BODY = "Q_CAP","I100": LOCATION = "C1124" #&CDS_LOCATION = "C1124" &SEC = "1" #&CDS_SEC = "1";
"A":   PN = "1"  !CDS_PN = "1";
"B":   PN = "2"  !CDS_PN = "2";
BODY = "Q_CAP","I101": LOCATION = "C1941" #&CDS_LOCATION = "C1941" &SEC = "1" #&CDS_SEC = "1";
"A":   PN = "1"  !CDS_PN = "1";
"B":   PN = "2"  !CDS_PN = "2";
BODY = "LCMXO3LF9400C5BG484C","I102": LOCATION = "U249" #&CDS_LOCATION = "U249" &SEC = "5" #&CDS_SEC = "5";
"VCC1":   PN = "K10"  !CDS_PN = "K10";
"VCC2":   PN = "K11"  !CDS_PN = "K11";
"VCC3":   PN = "K12"  !CDS_PN = "K12";
"VCC4":   PN = "K13"  !CDS_PN = "K13";
"VCC5":   PN = "L11"  !CDS_PN = "L11";
"VCC6":   PN = "L12"  !CDS_PN = "L12";
"VCC7":   PN = "M11"  !CDS_PN = "M11";
"VCC8":   PN = "M12"  !CDS_PN = "M12";
"VCC9":   PN = "N10"  !CDS_PN = "N10";
"VCC10":   PN = "N11"  !CDS_PN = "N11";
"VCC11":   PN = "N12"  !CDS_PN = "N12";
"VCC12":   PN = "N13"  !CDS_PN = "N13";
"VCCIO0_1":   PN = "C7"  !CDS_PN = "C7";
"VCCIO0_2":   PN = "C12"  !CDS_PN = "C12";
"VCCIO0_3":   PN = "C16"  !CDS_PN = "C16";
"VCCIO0_4":   PN = "G10"  !CDS_PN = "G10";
"VCCIO0_5":   PN = "G13"  !CDS_PN = "G13";
"VCCIO0_6":   PN = "H9"  !CDS_PN = "H9";
"VCCIO0_7":   PN = "H11"  !CDS_PN = "H11";
"VCCIO0_8":   PN = "H12"  !CDS_PN = "H12";
"VCCIO0_9":   PN = "H14"  !CDS_PN = "H14";
"VCCIO1_1":   PN = "F20"  !CDS_PN = "F20";
"VCCIO1_2":   PN = "J15"  !CDS_PN = "J15";
"VCCIO1_3":   PN = "K15"  !CDS_PN = "K15";
"VCCIO1_4":   PN = "L15"  !CDS_PN = "L15";
"VCCIO1_5":   PN = "M15"  !CDS_PN = "M15";
"VCCIO1_6":   PN = "M18"  !CDS_PN = "M18";
"VCCIO1_7":   PN = "N15"  !CDS_PN = "N15";
"VCCIO1_8":   PN = "P15"  !CDS_PN = "P15";
"VCCIO1_9":   PN = "V20"  !CDS_PN = "V20";
"VCCIO2_1":   PN = "R9"  !CDS_PN = "R9";
"VCCIO2_2":   PN = "R10"  !CDS_PN = "R10";
"VCCIO2_3":   PN = "R11"  !CDS_PN = "R11";
"VCCIO2_4":   PN = "R12"  !CDS_PN = "R12";
"VCCIO2_5":   PN = "R13"  !CDS_PN = "R13";
"VCCIO2_6":   PN = "R14"  !CDS_PN = "R14";
"VCCIO2_7":   PN = "W7"  !CDS_PN = "W7";
"VCCIO2_8":   PN = "W11"  !CDS_PN = "W11";
"VCCIO2_9":   PN = "W16"  !CDS_PN = "W16";
"VCCIO3_1":   PN = "N8"  !CDS_PN = "N8";
"VCCIO3_2":   PN = "P8"  !CDS_PN = "P8";
"VCCIO3_3":   PN = "V3"  !CDS_PN = "V3";
"VCCIO4_1":   PN = "L8"  !CDS_PN = "L8";
"VCCIO4_2":   PN = "M8"  !CDS_PN = "M8";
"VCCIO4_3":   PN = "M3"  !CDS_PN = "M3";
"VCCIO5_1":   PN = "F3"  !CDS_PN = "F3";
"VCCIO5_2":   PN = "J8"  !CDS_PN = "J8";
"VCCIO5_3":   PN = "K8"  !CDS_PN = "K8";
BODY = "Q_CAP","I107": LOCATION = "C1842" #&CDS_LOCATION = "C1842" &SEC = "1" #&CDS_SEC = "1";
"A":   PN = "1"  !CDS_PN = "1";
"B":   PN = "2"  !CDS_PN = "2";
BODY = "Q_RES","I108": LOCATION = "R3344" #&CDS_LOCATION = "R3344" &SEC = "1" #&CDS_SEC = "1";
"A":   PN = "1"  !CDS_PN = "1";
"B":   PN = "2"  !CDS_PN = "2";
BODY = "Q_RES","I119": LOCATION = "R3458" #&CDS_LOCATION = "R3458" &SEC = "1" #&CDS_SEC = "1";
"A":   PN = "1"  !CDS_PN = "1";
"B":   PN = "2"  !CDS_PN = "2";
BODY = "Q_CAP","I120": LOCATION = "C1934" #&CDS_LOCATION = "C1934" &SEC = "1" #&CDS_SEC = "1";
"A":   PN = "1"  !CDS_PN = "1";
"B":   PN = "2"  !CDS_PN = "2";
BODY = "Q_CAP","I121": LOCATION = "C1150" #&CDS_LOCATION = "C1150" &SEC = "1" #&CDS_SEC = "1";
"A":   PN = "1"  !CDS_PN = "1";
"B":   PN = "2"  !CDS_PN = "2";
DRAWING = "@s9s_mb_2u_lib.s9s_mb_2u(sch_1):page270";
BODY = "Q_RES","I17": #LOCATION = "R2524" !CDS_LOCATION = "R2524" &SEC = "1" #&CDS_SEC = "1";
"A":   PN = "1"  !CDS_PN = "1";
"B":   PN = "2"  !CDS_PN = "2";
BODY = "Q_RES","I18": #LOCATION = "R2525" !CDS_LOCATION = "R2525" &SEC = "1" #&CDS_SEC = "1";
"A":   PN = "1"  !CDS_PN = "1";
"B":   PN = "2"  !CDS_PN = "2";
BODY = "Q_RES","I19": #LOCATION = "R2550" !CDS_LOCATION = "R2550" &SEC = "1" #&CDS_SEC = "1";
"A":   PN = "1"  !CDS_PN = "1";
"B":   PN = "2"  !CDS_PN = "2";
BODY = "Q_RES","I63": #LOCATION = "PR317" !CDS_LOCATION = "PR317" &SEC = "1" #&CDS_SEC = "1";
"A":   PN = "1"  !CDS_PN = "1";
"B":   PN = "2"  !CDS_PN = "2";
BODY = "Q_CAP","I67": #LOCATION = "C2860" !CDS_LOCATION = "C2860" &SEC = "1" #&CDS_SEC = "1";
"A":   PN = "1"  !CDS_PN = "1";
"B":   PN = "2"  !CDS_PN = "2";
BODY = "Q_RES","I4": #LOCATION = "PR306" !CDS_LOCATION = "PR306" &SEC = "1" #&CDS_SEC = "1";
"A":   PN = "1"  !CDS_PN = "1";
"B":   PN = "2"  !CDS_PN = "2";
BODY = "Q_RES","I25": #LOCATION = "R2522" !CDS_LOCATION = "R2522" &SEC = "1" #&CDS_SEC = "1";
"A":   PN = "1"  !CDS_PN = "1";
"B":   PN = "2"  !CDS_PN = "2";
BODY = "Q_RES","I36": #LOCATION = "R2523" !CDS_LOCATION = "R2523" &SEC = "1" #&CDS_SEC = "1";
"A":   PN = "1"  !CDS_PN = "1";
"B":   PN = "2"  !CDS_PN = "2";
BODY = "Q_RES","I60": #LOCATION = "R308" !CDS_LOCATION = "R308" &SEC = "1" #&CDS_SEC = "1";
"A":   PN = "1"  !CDS_PN = "1";
"B":   PN = "2"  !CDS_PN = "2";
BODY = "Q_RES","I61": #LOCATION = "R307" !CDS_LOCATION = "R307" &SEC = "1" #&CDS_SEC = "1";
"A":   PN = "1"  !CDS_PN = "1";
"B":   PN = "2"  !CDS_PN = "2";
BODY = "Q_RES","I66": #LOCATION = "R2521" !CDS_LOCATION = "R2521" &SEC = "1" #&CDS_SEC = "1";
"A":   PN = "1"  !CDS_PN = "1";
"B":   PN = "2"  !CDS_PN = "2";
BODY = "Q_CAP","I68": #LOCATION = "C2859" !CDS_LOCATION = "C2859" &SEC = "1" #&CDS_SEC = "1";
"A":   PN = "1"  !CDS_PN = "1";
"B":   PN = "2"  !CDS_PN = "2";
BODY = "Q_RES","I74": #LOCATION = "PR637" !CDS_LOCATION = "PR637" &SEC = "1" #&CDS_SEC = "1";
"A":   PN = "1"  !CDS_PN = "1";
"B":   PN = "2"  !CDS_PN = "2";
BODY = "Q_CAP","I121": #LOCATION = "PC1194" !CDS_LOCATION = "PC1194" &SEC = "1" #&CDS_SEC = "1";
"A":   PN = "1"  !CDS_PN = "1";
"B":   PN = "2"  !CDS_PN = "2";
BODY = "Q_RES","I12": #LOCATION = "PR560" !CDS_LOCATION = "PR560" &SEC = "1" #&CDS_SEC = "1";
"A":   PN = "1"  !CDS_PN = "1";
"B":   PN = "2"  !CDS_PN = "2";
BODY = "Q_CAP","I28": #LOCATION = "PC547" !CDS_LOCATION = "PC547" &SEC = "1" #&CDS_SEC = "1";
"A":   PN = "1"  !CDS_PN = "1";
"B":   PN = "2"  !CDS_PN = "2";
BODY = "Q_RES","I29": #LOCATION = "PR313" !CDS_LOCATION = "PR313" &SEC = "1" #&CDS_SEC = "1";
"A":   PN = "1"  !CDS_PN = "1";
"B":   PN = "2"  !CDS_PN = "2";
BODY = "Q_CAP","I31": #LOCATION = "PC548" !CDS_LOCATION = "PC548" &SEC = "1" #&CDS_SEC = "1";
"A":   PN = "1"  !CDS_PN = "1";
"B":   PN = "2"  !CDS_PN = "2";
BODY = "Q_CAP","I34": #LOCATION = "C2446" !CDS_LOCATION = "C2446" #SEC = "1" !CDS_SEC = "1";
"A":   PN = "1"  !CDS_PN = "1";
"B":   PN = "2"  !CDS_PN = "2";
BODY = "Q_CAP","I35": #LOCATION = "C2447" !CDS_LOCATION = "C2447" &SEC = "1" #&CDS_SEC = "1";
"A":   PN = "1"  !CDS_PN = "1";
"B":   PN = "2"  !CDS_PN = "2";
BODY = "Q_RES","I59": #LOCATION = "R309" !CDS_LOCATION = "R309" &SEC = "1" #&CDS_SEC = "1";
"A":   PN = "1"  !CDS_PN = "1";
"B":   PN = "2"  !CDS_PN = "2";
BODY = "Q_RES","I65": #LOCATION = "R2520" !CDS_LOCATION = "R2520" &SEC = "1" #&CDS_SEC = "1";
"A":   PN = "1"  !CDS_PN = "1";
"B":   PN = "2"  !CDS_PN = "2";
BODY = "Q_RES","I101": #LOCATION = "R2555" !CDS_LOCATION = "R2555" &SEC = "1" #&CDS_SEC = "1";
"A":   PN = "1"  !CDS_PN = "1";
"B":   PN = "2"  !CDS_PN = "2";
BODY = "Q_CAP","I120": #LOCATION = "PC552" !CDS_LOCATION = "PC552" &SEC = "1" #&CDS_SEC = "1";
"A":   PN = "1"  !CDS_PN = "1";
"B":   PN = "2"  !CDS_PN = "2";
BODY = "Q_RES","I7": #LOCATION = "PR303" !CDS_LOCATION = "PR303" &SEC = "1" #&CDS_SEC = "1";
"A":   PN = "1"  !CDS_PN = "1";
"B":   PN = "2"  !CDS_PN = "2";
BODY = "Q_RES","I16": #LOCATION = "R2552" !CDS_LOCATION = "R2552" &SEC = "1" #&CDS_SEC = "1";
"A":   PN = "1"  !CDS_PN = "1";
"B":   PN = "2"  !CDS_PN = "2";
BODY = "Q_SHORT","I22": #LOCATION = "PJ49" !CDS_LOCATION = "PJ49" &SEC = "1" #&CDS_SEC = "1";
"1":   PN = "1"  !CDS_PN = "1";
"2":   PN = "2"  !CDS_PN = "2";
BODY = "Q_CAP","I38": #LOCATION = "PC422" !CDS_LOCATION = "PC422" &SEC = "1" #&CDS_SEC = "1";
"A":   PN = "1"  !CDS_PN = "1";
"B":   PN = "2"  !CDS_PN = "2";
BODY = "Q_RES","I49": #LOCATION = "PR578" !CDS_LOCATION = "PR578" &SEC = "1" #&CDS_SEC = "1";
"A":   PN = "1"  !CDS_PN = "1";
"B":   PN = "2"  !CDS_PN = "2";
BODY = "Q_RES","I58": #LOCATION = "R310" !CDS_LOCATION = "R310" &SEC = "1" #&CDS_SEC = "1";
"A":   PN = "1"  !CDS_PN = "1";
"B":   PN = "2"  !CDS_PN = "2";
BODY = "Q_CAP","I64": #LOCATION = "PC549" !CDS_LOCATION = "PC549" &SEC = "1" #&CDS_SEC = "1";
"A":   PN = "1"  !CDS_PN = "1";
"B":   PN = "2"  !CDS_PN = "2";
BODY = "Q_RES","I81": #LOCATION = "PR4238" !CDS_LOCATION = "PR4238" &SEC = "1" #&CDS_SEC = "1";
"A":   PN = "1"  !CDS_PN = "1";
"B":   PN = "2"  !CDS_PN = "2";
BODY = "Q_RES","I100": #LOCATION = "R2554" !CDS_LOCATION = "R2554" &SEC = "1" #&CDS_SEC = "1";
"A":   PN = "1"  !CDS_PN = "1";
"B":   PN = "2"  !CDS_PN = "2";
BODY = "Q_CAP","I104": #LOCATION = "C2449" !CDS_LOCATION = "C2449" &SEC = "1" #&CDS_SEC = "1";
"A":   PN = "1"  !CDS_PN = "1";
"B":   PN = "2"  !CDS_PN = "2";
BODY = "Q_CAP","I122": #LOCATION = "PC555" !CDS_LOCATION = "PC555" &SEC = "1" #&CDS_SEC = "1";
"A":   PN = "1"  !CDS_PN = "1";
"B":   PN = "2"  !CDS_PN = "2";
BODY = "Q_RES","I126": #LOCATION = "PR323" !CDS_LOCATION = "PR323" &SEC = "1" #&CDS_SEC = "1";
"A":   PN = "1"  !CDS_PN = "1";
"B":   PN = "2"  !CDS_PN = "2";
BODY = "Q_RES","I6": #LOCATION = "PR318" !CDS_LOCATION = "PR318" &SEC = "1" #&CDS_SEC = "1";
"A":   PN = "1"  !CDS_PN = "1";
"B":   PN = "2"  !CDS_PN = "2";
BODY = "Q_RES","I9": #LOCATION = "PR304" !CDS_LOCATION = "PR304" &SEC = "1" #&CDS_SEC = "1";
"A":   PN = "1"  !CDS_PN = "1";
"B":   PN = "2"  !CDS_PN = "2";
BODY = "Q_RES","I15": #LOCATION = "R2551" !CDS_LOCATION = "R2551" &SEC = "1" #&CDS_SEC = "1";
"A":   PN = "1"  !CDS_PN = "1";
"B":   PN = "2"  !CDS_PN = "2";
BODY = "Q_RES","I23": #LOCATION = "PR561" !CDS_LOCATION = "PR561" &SEC = "1" #&CDS_SEC = "1";
"A":   PN = "1"  !CDS_PN = "1";
"B":   PN = "2"  !CDS_PN = "2";
BODY = "Q_RES","I27": #LOCATION = "PR305" !CDS_LOCATION = "PR305" &SEC = "1" #&CDS_SEC = "1";
"A":   PN = "1"  !CDS_PN = "1";
"B":   PN = "2"  !CDS_PN = "2";
BODY = "RAA229126GNPHA0","I33": #LOCATION = "PU29" !CDS_LOCATION = "PU29" #SEC = "1" !CDS_SEC = "1";
"ADDR_CFG":   PN = "42"  !CDS_PN = "42";
"CFP":   PN = "41"  !CDS_PN = "41";
"CS0":   PN = "38"  !CDS_PN = "38";
"CS1":   PN = "37"  !CDS_PN = "37";
"CS2":   PN = "36"  !CDS_PN = "36";
"CS3":   PN = "35"  !CDS_PN = "35";
"CS4":   PN = "34"  !CDS_PN = "34";
"CS5":   PN = "33"  !CDS_PN = "33";
"CS6":   PN = "32"  !CDS_PN = "32";
"CS7":   PN = "31"  !CDS_PN = "31";
"CS8":   PN = "30"  !CDS_PN = "30";
"CS9":   PN = "29"  !CDS_PN = "29";
"CS10":   PN = "28"  !CDS_PN = "28";
"CS11":   PN = "27"  !CDS_PN = "27";
"EN0":   PN = "17"  !CDS_PN = "17";
"EN1":   PN = "24"  !CDS_PN = "24";
"NPINALERT||NPSYS_CRIT":   PN = "19"  !CDS_PN = "19";
"NPMALERT":   PN = "15"  !CDS_PN = "15";
"NSVALERT":   PN = "23"  !CDS_PN = "23";
"NVRHOT":   PN = "18"  !CDS_PN = "18";
"PG0":   PN = "16"  !CDS_PN = "16";
"PG1":   PN = "20"  !CDS_PN = "20";
"PMSCL":   PN = "14"  !CDS_PN = "14";
"PMSDA":   PN = "13"  !CDS_PN = "13";
"PWM0":   PN = "1"  !CDS_PN = "1";
"PWM1":   PN = "2"  !CDS_PN = "2";
"PWM2":   PN = "3"  !CDS_PN = "3";
"PWM3":   PN = "4"  !CDS_PN = "4";
"PWM4":   PN = "5"  !CDS_PN = "5";
"PWM5":   PN = "6"  !CDS_PN = "6";
"PWM6":   PN = "7"  !CDS_PN = "7";
"PWM7":   PN = "8"  !CDS_PN = "8";
"PWM8":   PN = "9"  !CDS_PN = "9";
"PWM9":   PN = "10"  !CDS_PN = "10";
"PWM10":   PN = "11"  !CDS_PN = "11";
"PWM11":   PN = "12"  !CDS_PN = "12";
"RGND0":   PN = "26"  !CDS_PN = "26";
"RGND1":   PN = "39"  !CDS_PN = "39";
"SVCLK":   PN = "21"  !CDS_PN = "21";
"SVDATA":   PN = "22"  !CDS_PN = "22";
"TEMP0":   PN = "43"  !CDS_PN = "43";
"TEMP1||ISYS":   PN = "44"  !CDS_PN = "44";
"TH_GND":   PN = "TH"  !CDS_PN = "TH";
"VCC":   PN = "47"  !CDS_PN = "47";
"VCCS":   PN = "48"  !CDS_PN = "48";
"VINSEN||VSYS":   PN = "46"  !CDS_PN = "46";
"VMON||IINSEN||VSYS||ISYS":   PN = "45"  !CDS_PN = "45";
"VSEN0":   PN = "25"  !CDS_PN = "25";
"VSEN1":   PN = "40"  !CDS_PN = "40";
BODY = "Q_RES","I37": #LOCATION = "PR242" !CDS_LOCATION = "PR242" &SEC = "1" #&CDS_SEC = "1";
"A":   PN = "1"  !CDS_PN = "1";
"B":   PN = "2"  !CDS_PN = "2";
BODY = "Q_RES","I45": #LOCATION = "PR574" !CDS_LOCATION = "PR574" &SEC = "1" #&CDS_SEC = "1";
"A":   PN = "1"  !CDS_PN = "1";
"B":   PN = "2"  !CDS_PN = "2";
BODY = "Q_SHORT","I46": #LOCATION = "PJ52" !CDS_LOCATION = "PJ52" &SEC = "1" #&CDS_SEC = "1";
"1":   PN = "1"  !CDS_PN = "1";
"2":   PN = "2"  !CDS_PN = "2";
BODY = "Q_RES","I56": #LOCATION = "R311" !CDS_LOCATION = "R311" &SEC = "1" #&CDS_SEC = "1";
"A":   PN = "1"  !CDS_PN = "1";
"B":   PN = "2"  !CDS_PN = "2";
BODY = "Q_RES","I57": #LOCATION = "R312" !CDS_LOCATION = "R312" &SEC = "1" #&CDS_SEC = "1";
"A":   PN = "1"  !CDS_PN = "1";
"B":   PN = "2"  !CDS_PN = "2";
BODY = "Q_CAP","I72": #LOCATION = "PC554" !CDS_LOCATION = "PC554" &SEC = "1" #&CDS_SEC = "1";
"A":   PN = "1"  !CDS_PN = "1";
"B":   PN = "2"  !CDS_PN = "2";
BODY = "Q_RES","I80": #LOCATION = "PR4239" !CDS_LOCATION = "PR4239" &SEC = "1" #&CDS_SEC = "1";
"A":   PN = "1"  !CDS_PN = "1";
"B":   PN = "2"  !CDS_PN = "2";
BODY = "Q_CAP","I92": #LOCATION = "PC101" !CDS_LOCATION = "PC101" &SEC = "1" #&CDS_SEC = "1";
"A":   PN = "1"  !CDS_PN = "1";
"B":   PN = "2"  !CDS_PN = "2";
BODY = "Q_RES","I94": #LOCATION = "PR453" !CDS_LOCATION = "PR453" &SEC = "1" #&CDS_SEC = "1";
"A":   PN = "1"  !CDS_PN = "1";
"B":   PN = "2"  !CDS_PN = "2";
BODY = "Q_RES","I99": #LOCATION = "R2553" !CDS_LOCATION = "R2553" &SEC = "1" #&CDS_SEC = "1";
"A":   PN = "1"  !CDS_PN = "1";
"B":   PN = "2"  !CDS_PN = "2";
BODY = "Q_CAP","I103": #LOCATION = "C2448" !CDS_LOCATION = "C2448" &SEC = "1" #&CDS_SEC = "1";
"A":   PN = "1"  !CDS_PN = "1";
"B":   PN = "2"  !CDS_PN = "2";
BODY = "Q_CAP","I119": #LOCATION = "PC553" !CDS_LOCATION = "PC553" &SEC = "1" #&CDS_SEC = "1";
"A":   PN = "1"  !CDS_PN = "1";
"B":   PN = "2"  !CDS_PN = "2";
BODY = "Q_CAP","I128": #LOCATION = "PC2366" !CDS_LOCATION = "PC2366" &SEC = "1" #&CDS_SEC = "1";
"A":   PN = "1"  !CDS_PN = "1";
"B":   PN = "2"  !CDS_PN = "2";
DRAWING = "@s9s_mb_2u_lib.s9s_mb_2u(sch_1):page275";
BODY = "Q_RES","I2": #LOCATION = "PR224" !CDS_LOCATION = "PR224" &SEC = "1" #&CDS_SEC = "1";
"A":   PN = "1"  !CDS_PN = "1";
"B":   PN = "2"  !CDS_PN = "2";
BODY = "ISL99390FRZTR5935","I9": #LOCATION = "PU76_P1_2" !CDS_LOCATION = "PU76_P1_2" &SEC = "1" #&CDS_SEC = "1";
"AGND":   PN = "2"  !CDS_PN = "2";
"BOOT":   PN = "33"  !CDS_PN = "33";
"DNC":   PN = "31"  !CDS_PN = "31";
"EN":   PN = "35"  !CDS_PN = "35";
"GL1":   PN = "6"  !CDS_PN = "6";
"GL2":   PN = "41"  !CDS_PN = "41";
"IOUT":   PN = "38"  !CDS_PN = "38";
"LSET":   PN = "37"  !CDS_PN = "37";
"PGND1":   PN = "5"  !CDS_PN = "5";
"PGND2":   PN = "7_9-20_24"  !CDS_PN = "7_9-20_24";
"PGND3":   PN = "40"  !CDS_PN = "40";
"PHASE":   PN = "32"  !CDS_PN = "32";
"PVCC":   PN = "4"  !CDS_PN = "4";
"PWM":   PN = "34"  !CDS_PN = "34";
"REFIN":   PN = "39"  !CDS_PN = "39";
"SW":   PN = "10_19"  !CDS_PN = "10_19";
"TOUT_FLT":   PN = "36"  !CDS_PN = "36";
"VCC":   PN = "3"  !CDS_PN = "3";
"VIN1":   PN = "25_29"  !CDS_PN = "25_29";
"VIN2":   PN = "30"  !CDS_PN = "30";
"VOS":   PN = "1"  !CDS_PN = "1";
BODY = "Q_CAP","I27": #LOCATION = "PC395" !CDS_LOCATION = "PC395" &SEC = "1" #&CDS_SEC = "1";
"A":   PN = "1"  !CDS_PN = "1";
"B":   PN = "2"  !CDS_PN = "2";
BODY = "Q_CAP","I37": #LOCATION = "PC398_P1_2" !CDS_LOCATION = "PC398_P1_2" &SEC = "1" #&CDS_SEC = "1";
"A":   PN = "1"  !CDS_PN = "1";
"B":   PN = "2"  !CDS_PN = "2";
BODY = "Q_CAP","I39": #LOCATION = "PC400_P1_2" !CDS_LOCATION = "PC400_P1_2" &SEC = "1" #&CDS_SEC = "1";
"A":   PN = "1"  !CDS_PN = "1";
"B":   PN = "2"  !CDS_PN = "2";
BODY = "Q_INDUCTOR","I44": #LOCATION = "PL19" !CDS_LOCATION = "PL19" &SEC = "1" #&CDS_SEC = "1";
"1":   PN = "1"  !CDS_PN = "1";
"2":   PN = "2"  !CDS_PN = "2";
BODY = "Q_CAP","I46": #LOCATION = "PC725_P1_2" !CDS_LOCATION = "PC725_P1_2" &SEC = "1" #&CDS_SEC = "1";
"A":   PN = "1"  !CDS_PN = "1";
"B":   PN = "2"  !CDS_PN = "2";
BODY = "Q_CAP","I49": #LOCATION = "PC397_P1_1" !CDS_LOCATION = "PC397_P1_1" &SEC = "1" #&CDS_SEC = "1";
"A":   PN = "1"  !CDS_PN = "1";
"B":   PN = "2"  !CDS_PN = "2";
BODY = "Q_RES","I50": #LOCATION = "PR1800" !CDS_LOCATION = "PR1800" &SEC = "1" #&CDS_SEC = "1";
"A":   PN = "1"  !CDS_PN = "1";
"B":   PN = "2"  !CDS_PN = "2";
BODY = "Q_RES","I53": #LOCATION = "PR1331" !CDS_LOCATION = "PR1331" &SEC = "1" #&CDS_SEC = "1";
"A":   PN = "1"  !CDS_PN = "1";
"B":   PN = "2"  !CDS_PN = "2";
BODY = "Q_INDUCTOR","I55": #LOCATION = "PL18" !CDS_LOCATION = "PL18" &SEC = "1" #&CDS_SEC = "1";
"1":   PN = "1"  !CDS_PN = "1";
"2":   PN = "2"  !CDS_PN = "2";
BODY = "Q_CAP","I60": #LOCATION = "PC621_P1_1" !CDS_LOCATION = "PC621_P1_1" &SEC = "1" #&CDS_SEC = "1";
"A":   PN = "1"  !CDS_PN = "1";
"B":   PN = "2"  !CDS_PN = "2";
BODY = "Q_CAP","I63": #LOCATION = "PC413_P1_2" !CDS_LOCATION = "PC413_P1_2" &SEC = "1" #&CDS_SEC = "1";
"A":   PN = "1"  !CDS_PN = "1";
"B":   PN = "2"  !CDS_PN = "2";
BODY = "Q_CAPP","I68": #LOCATION = "PC416" !CDS_LOCATION = "PC416" &SEC = "1" #&CDS_SEC = "1";
"A":   PN = "1"  !CDS_PN = "1";
"B":   PN = "2"  !CDS_PN = "2";
BODY = "Q_CAP","I84": #LOCATION = "PC1679" !CDS_LOCATION = "PC1679" &SEC = "1" #&CDS_SEC = "1";
"A":   PN = "1"  !CDS_PN = "1";
"B":   PN = "2"  !CDS_PN = "2";
BODY = "Q_CAP","I29": #LOCATION = "PC1367" !CDS_LOCATION = "PC1367" &SEC = "1" #&CDS_SEC = "1";
"A":   PN = "1"  !CDS_PN = "1";
"B":   PN = "2"  !CDS_PN = "2";
BODY = "Q_CAP","I40": #LOCATION = "PC404_P1_2" !CDS_LOCATION = "PC404_P1_2" &SEC = "1" #&CDS_SEC = "1";
"A":   PN = "1"  !CDS_PN = "1";
"B":   PN = "2"  !CDS_PN = "2";
BODY = "Q_RES","I41": #LOCATION = "PR1332" !CDS_LOCATION = "PR1332" &SEC = "1" #&CDS_SEC = "1";
"A":   PN = "1"  !CDS_PN = "1";
"B":   PN = "2"  !CDS_PN = "2";
BODY = "Q_CAP","I51": #LOCATION = "PC399_P1_1" !CDS_LOCATION = "PC399_P1_1" &SEC = "1" #&CDS_SEC = "1";
"A":   PN = "1"  !CDS_PN = "1";
"B":   PN = "2"  !CDS_PN = "2";
BODY = "Q_CAP","I52": #LOCATION = "PC403_P1_1" !CDS_LOCATION = "PC403_P1_1" &SEC = "1" #&CDS_SEC = "1";
"A":   PN = "1"  !CDS_PN = "1";
"B":   PN = "2"  !CDS_PN = "2";
BODY = "Q_CAP","I62": #LOCATION = "PC411_P1_2" !CDS_LOCATION = "PC411_P1_2" &SEC = "1" #&CDS_SEC = "1";
"A":   PN = "1"  !CDS_PN = "1";
"B":   PN = "2"  !CDS_PN = "2";
BODY = "Q_CAP","I83": #LOCATION = "PC1678" !CDS_LOCATION = "PC1678" &SEC = "1" #&CDS_SEC = "1";
"A":   PN = "1"  !CDS_PN = "1";
"B":   PN = "2"  !CDS_PN = "2";
BODY = "Q_CAP","I11": #LOCATION = "PC396" !CDS_LOCATION = "PC396" &SEC = "1" #&CDS_SEC = "1";
"A":   PN = "1"  !CDS_PN = "1";
"B":   PN = "2"  !CDS_PN = "2";
BODY = "Q_RES","I12": #LOCATION = "PR227" !CDS_LOCATION = "PR227" &SEC = "1" #&CDS_SEC = "1";
"A":   PN = "1"  !CDS_PN = "1";
"B":   PN = "2"  !CDS_PN = "2";
BODY = "Q_RES","I32": #LOCATION = "PR701" !CDS_LOCATION = "PR701" &SEC = "1" #&CDS_SEC = "1";
"A":   PN = "1"  !CDS_PN = "1";
"B":   PN = "2"  !CDS_PN = "2";
BODY = "Q_RES","I34": #LOCATION = "PR703" !CDS_LOCATION = "PR703" &SEC = "1" #&CDS_SEC = "1";
"A":   PN = "1"  !CDS_PN = "1";
"B":   PN = "2"  !CDS_PN = "2";
BODY = "Q_RES","I38": #LOCATION = "PR1801" !CDS_LOCATION = "PR1801" &SEC = "1" #&CDS_SEC = "1";
"A":   PN = "1"  !CDS_PN = "1";
"B":   PN = "2"  !CDS_PN = "2";
BODY = "Q_CAP","I54": #LOCATION = "PC401" !CDS_LOCATION = "PC401" &SEC = "1" #&CDS_SEC = "1";
"A":   PN = "1"  !CDS_PN = "1";
"B":   PN = "2"  !CDS_PN = "2";
BODY = "Q_CAP","I56": #LOCATION = "PC405_P1_1" !CDS_LOCATION = "PC405_P1_1" &SEC = "1" #&CDS_SEC = "1";
"A":   PN = "1"  !CDS_PN = "1";
"B":   PN = "2"  !CDS_PN = "2";
BODY = "Q_CAP","I61": #LOCATION = "PC408_P1_2" !CDS_LOCATION = "PC408_P1_2" &SEC = "1" #&CDS_SEC = "1";
"A":   PN = "1"  !CDS_PN = "1";
"B":   PN = "2"  !CDS_PN = "2";
BODY = "Q_RES","I64": #LOCATION = "PR4241" !CDS_LOCATION = "PR4241" &SEC = "1" #&CDS_SEC = "1";
"A":   PN = "1"  !CDS_PN = "1";
"B":   PN = "2"  !CDS_PN = "2";
BODY = "Q_CAPP","I70": #LOCATION = "PC418" !CDS_LOCATION = "PC418" &SEC = "1" #&CDS_SEC = "1";
"A":   PN = "1"  !CDS_PN = "1";
"B":   PN = "2"  !CDS_PN = "2";
BODY = "Q_CAPP","I72": #LOCATION = "PC2172" !CDS_LOCATION = "PC2172" &SEC = "1" #&CDS_SEC = "1";
"A":   PN = "1"  !CDS_PN = "1";
"B":   PN = "2"  !CDS_PN = "2";
BODY = "Q_CAP","I80": #LOCATION = "PC1677" !CDS_LOCATION = "PC1677" &SEC = "1" #&CDS_SEC = "1";
"A":   PN = "1"  !CDS_PN = "1";
"B":   PN = "2"  !CDS_PN = "2";
BODY = "Q_CAP","I8": #LOCATION = "PC1368" !CDS_LOCATION = "PC1368" &SEC = "1" #&CDS_SEC = "1";
"A":   PN = "1"  !CDS_PN = "1";
"B":   PN = "2"  !CDS_PN = "2";
BODY = "Q_RES","I13": #LOCATION = "PR702" !CDS_LOCATION = "PR702" &SEC = "1" #&CDS_SEC = "1";
"A":   PN = "1"  !CDS_PN = "1";
"B":   PN = "2"  !CDS_PN = "2";
BODY = "Q_CAP","I16": #LOCATION = "PC1243_P1_2" !CDS_LOCATION = "PC1243_P1_2" &SEC = "1" #&CDS_SEC = "1";
"A":   PN = "1"  !CDS_PN = "1";
"B":   PN = "2"  !CDS_PN = "2";
BODY = "Q_RES","I17": #LOCATION = "PR704" !CDS_LOCATION = "PR704" &SEC = "1" #&CDS_SEC = "1";
"A":   PN = "1"  !CDS_PN = "1";
"B":   PN = "2"  !CDS_PN = "2";
BODY = "Q_RES","I20": #LOCATION = "PR225" !CDS_LOCATION = "PR225" &SEC = "1" #&CDS_SEC = "1";
"A":   PN = "1"  !CDS_PN = "1";
"B":   PN = "2"  !CDS_PN = "2";
BODY = "Q_RES","I28": #LOCATION = "PR226" !CDS_LOCATION = "PR226" &SEC = "1" #&CDS_SEC = "1";
"A":   PN = "1"  !CDS_PN = "1";
"B":   PN = "2"  !CDS_PN = "2";
BODY = "Q_CAP","I31": #LOCATION = "PC1242_P1_1" !CDS_LOCATION = "PC1242_P1_1" &SEC = "1" #&CDS_SEC = "1";
"A":   PN = "1"  !CDS_PN = "1";
"B":   PN = "2"  !CDS_PN = "2";
BODY = "Q_CAP","I42": #LOCATION = "PC406_P1_2" !CDS_LOCATION = "PC406_P1_2" &SEC = "1" #&CDS_SEC = "1";
"A":   PN = "1"  !CDS_PN = "1";
"B":   PN = "2"  !CDS_PN = "2";
BODY = "Q_CAP","I43": #LOCATION = "PC402" !CDS_LOCATION = "PC402" &SEC = "1" #&CDS_SEC = "1";
"A":   PN = "1"  !CDS_PN = "1";
"B":   PN = "2"  !CDS_PN = "2";
BODY = "Q_CAP","I58": #LOCATION = "PC724_P1_1" !CDS_LOCATION = "PC724_P1_1" &SEC = "1" #&CDS_SEC = "1";
"A":   PN = "1"  !CDS_PN = "1";
"B":   PN = "2"  !CDS_PN = "2";
BODY = "Q_CAPP","I66": #LOCATION = "PC414" !CDS_LOCATION = "PC414" &SEC = "1" #&CDS_SEC = "1";
"A":   PN = "1"  !CDS_PN = "1";
"B":   PN = "2"  !CDS_PN = "2";
BODY = "Q_CAPP","I67": #LOCATION = "PC415" !CDS_LOCATION = "PC415" &SEC = "1" #&CDS_SEC = "1";
"A":   PN = "1"  !CDS_PN = "1";
"B":   PN = "2"  !CDS_PN = "2";
BODY = "Q_CAP","I74": #LOCATION = "PC410_P1_1" !CDS_LOCATION = "PC410_P1_1" &SEC = "1" #&CDS_SEC = "1";
"A":   PN = "1"  !CDS_PN = "1";
"B":   PN = "2"  !CDS_PN = "2";
BODY = "Q_CAP","I75": #LOCATION = "PC412_P1_1" !CDS_LOCATION = "PC412_P1_1" &SEC = "1" #&CDS_SEC = "1";
"A":   PN = "1"  !CDS_PN = "1";
"B":   PN = "2"  !CDS_PN = "2";
BODY = "Q_CAP","I77": #LOCATION = "PC1657" !CDS_LOCATION = "PC1657" &SEC = "1" #&CDS_SEC = "1";
"A":   PN = "1"  !CDS_PN = "1";
"B":   PN = "2"  !CDS_PN = "2";
BODY = "Q_INDUCTOR","I79": #LOCATION = "PL43" !CDS_LOCATION = "PL43" &SEC = "1" #&CDS_SEC = "1";
"1":   PN = "1"  !CDS_PN = "1";
"2":   PN = "2"  !CDS_PN = "2";
BODY = "Q_CAP","I85": #LOCATION = "PC1680" !CDS_LOCATION = "PC1680" &SEC = "1" #&CDS_SEC = "1";
"A":   PN = "1"  !CDS_PN = "1";
"B":   PN = "2"  !CDS_PN = "2";
BODY = "Q_CAPP","I87": #LOCATION = "PC417" !CDS_LOCATION = "PC417" &SEC = "1" #&CDS_SEC = "1";
"A":   PN = "1"  !CDS_PN = "1";
"B":   PN = "2"  !CDS_PN = "2";
BODY = "ISL99390FRZTR5935","I89": #LOCATION = "PU75_P1_1" !CDS_LOCATION = "PU75_P1_1" &SEC = "1" #&CDS_SEC = "1";
"AGND":   PN = "2"  !CDS_PN = "2";
"BOOT":   PN = "33"  !CDS_PN = "33";
"DNC":   PN = "31"  !CDS_PN = "31";
"EN":   PN = "35"  !CDS_PN = "35";
"GL1":   PN = "6"  !CDS_PN = "6";
"GL2":   PN = "41"  !CDS_PN = "41";
"IOUT":   PN = "38"  !CDS_PN = "38";
"LSET":   PN = "37"  !CDS_PN = "37";
"PGND1":   PN = "5"  !CDS_PN = "5";
"PGND2":   PN = "7_9-20_24"  !CDS_PN = "7_9-20_24";
"PGND3":   PN = "40"  !CDS_PN = "40";
"PHASE":   PN = "32"  !CDS_PN = "32";
"PVCC":   PN = "4"  !CDS_PN = "4";
"PWM":   PN = "34"  !CDS_PN = "34";
"REFIN":   PN = "39"  !CDS_PN = "39";
"SW":   PN = "10_19"  !CDS_PN = "10_19";
"TOUT_FLT":   PN = "36"  !CDS_PN = "36";
"VCC":   PN = "3"  !CDS_PN = "3";
"VIN1":   PN = "25_29"  !CDS_PN = "25_29";
"VIN2":   PN = "30"  !CDS_PN = "30";
"VOS":   PN = "1"  !CDS_PN = "1";
DRAWING = "@s9s_mb_2u_lib.s9s_mb_2u(sch_1):page159";
BODY = "Q_RES","I2": LOCATION = "R4653" #&CDS_LOCATION = "R4653" &SEC = "1" #&CDS_SEC = "1";
"A":   PN = "1"  !CDS_PN = "1";
"B":   PN = "2"  !CDS_PN = "2";
BODY = "Q_RES","I4": LOCATION = "R4647" #&CDS_LOCATION = "R4647" &SEC = "1" #&CDS_SEC = "1";
"A":   PN = "1"  !CDS_PN = "1";
"B":   PN = "2"  !CDS_PN = "2";
BODY = "Q_RES","I15": LOCATION = "R4646" #&CDS_LOCATION = "R4646" &SEC = "1" #&CDS_SEC = "1";
"A":   PN = "1"  !CDS_PN = "1";
"B":   PN = "2"  !CDS_PN = "2";
BODY = "Q_RES","I16": LOCATION = "R4645" #&CDS_LOCATION = "R4645" &SEC = "1" #&CDS_SEC = "1";
"A":   PN = "1"  !CDS_PN = "1";
"B":   PN = "2"  !CDS_PN = "2";
BODY = "Q_CAP","I27": LOCATION = "C2353" #&CDS_LOCATION = "C2353" &SEC = "1" #&CDS_SEC = "1";
"A":   PN = "1"  !CDS_PN = "1";
"B":   PN = "2"  !CDS_PN = "2";
BODY = "Q_CAP","I32": LOCATION = "C2352" #&CDS_LOCATION = "C2352" &SEC = "1" #&CDS_SEC = "1";
"A":   PN = "1"  !CDS_PN = "1";
"B":   PN = "2"  !CDS_PN = "2";
BODY = "Q_RES","I62": LOCATION = "R4655" #&CDS_LOCATION = "R4655" &SEC = "1" #&CDS_SEC = "1";
"A":   PN = "1"  !CDS_PN = "1";
"B":   PN = "2"  !CDS_PN = "2";
BODY = "Q_RES","I66": LOCATION = "R4656" #&CDS_LOCATION = "R4656" &SEC = "1" #&CDS_SEC = "1";
"A":   PN = "1"  !CDS_PN = "1";
"B":   PN = "2"  !CDS_PN = "2";
BODY = "Q_RES","I67": LOCATION = "R4654" #&CDS_LOCATION = "R4654" &SEC = "1" #&CDS_SEC = "1";
"A":   PN = "1"  !CDS_PN = "1";
"B":   PN = "2"  !CDS_PN = "2";
BODY = "Q_RES","I81": LOCATION = "R3386" #&CDS_LOCATION = "R3386" &SEC = "1" #&CDS_SEC = "1";
"A":   PN = "1"  !CDS_PN = "1";
"B":   PN = "2"  !CDS_PN = "2";
BODY = "DS125BR111RTWR","I95": LOCATION = "U328" #&CDS_LOCATION = "U328" #SEC = "1" !CDS_SEC = "1";
"ENSMB":   PN = "3"  !CDS_PN = "3";
"EQA0||AD0":   PN = "10"  !CDS_PN = "10";
"EQA1||AD1":   PN = "9"  !CDS_PN = "9";
"EQB0||AD3":   PN = "1"  !CDS_PN = "1";
"EQB1||AD2":   PN = "2"  !CDS_PN = "2";
"INA+":   PN = "24"  !CDS_PN = "24";
"INA-":   PN = "23"  !CDS_PN = "23";
"INB+":   PN = "11"  !CDS_PN = "11";
"INB-":   PN = "12"  !CDS_PN = "12";
"OUTA+":   PN = "7"  !CDS_PN = "7";
"OUTA-":   PN = "8"  !CDS_PN = "8";
"OUTB+":   PN = "20"  !CDS_PN = "20";
"OUTB-":   PN = "19"  !CDS_PN = "19";
"PWDN":   PN = "6"  !CDS_PN = "6";
"RES":   PN = "13"  !CDS_PN = "13";
"RXDET||DONE#":   PN = "18"  !CDS_PN = "18";
"SCL||VODB_DB":   PN = "5"  !CDS_PN = "5";
"SD_TH":   PN = "14"  !CDS_PN = "14";
"SDA||VODA_DB":   PN = "4"  !CDS_PN = "4";
"TH_GND":   PN = "25"  !CDS_PN = "25";
"VDD_21":   PN = "21"  !CDS_PN = "21";
"VDD_22":   PN = "22"  !CDS_PN = "22";
"VDD_SEL":   PN = "16"  !CDS_PN = "16";
"VIN":   PN = "15"  !CDS_PN = "15";
"VOD_SEL||READEN#":   PN = "17"  !CDS_PN = "17";
BODY = "Q_CAP","I100": LOCATION = "C2358" #&CDS_LOCATION = "C2358" &SEC = "1" #&CDS_SEC = "1";
"A":   PN = "1"  !CDS_PN = "1";
"B":   PN = "2"  !CDS_PN = "2";
BODY = "Q_RES","I102": LOCATION = "R4651" #&CDS_LOCATION = "R4651" &SEC = "1" #&CDS_SEC = "1";
"A":   PN = "1"  !CDS_PN = "1";
"B":   PN = "2"  !CDS_PN = "2";
BODY = "Q_RES","I7": LOCATION = "R4642" #&CDS_LOCATION = "R4642" &SEC = "1" #&CDS_SEC = "1";
"A":   PN = "1"  !CDS_PN = "1";
"B":   PN = "2"  !CDS_PN = "2";
BODY = "Q_RES","I10": LOCATION = "R4694" #&CDS_LOCATION = "R4694" &SEC = "1" #&CDS_SEC = "1";
"A":   PN = "1"  !CDS_PN = "1";
"B":   PN = "2"  !CDS_PN = "2";
BODY = "Q_RES","I11": LOCATION = "R4644" #&CDS_LOCATION = "R4644" &SEC = "1" #&CDS_SEC = "1";
"A":   PN = "1"  !CDS_PN = "1";
"B":   PN = "2"  !CDS_PN = "2";
BODY = "Q_RES","I13": LOCATION = "R4643" #&CDS_LOCATION = "R4643" &SEC = "1" #&CDS_SEC = "1";
"A":   PN = "1"  !CDS_PN = "1";
"B":   PN = "2"  !CDS_PN = "2";
BODY = "Q_CAP","I28": LOCATION = "C2354" #&CDS_LOCATION = "C2354" &SEC = "1" #&CDS_SEC = "1";
"A":   PN = "1"  !CDS_PN = "1";
"B":   PN = "2"  !CDS_PN = "2";
BODY = "Q_CAP","I29": LOCATION = "C1868" #&CDS_LOCATION = "C1868" &SEC = "1" #&CDS_SEC = "1";
"A":   PN = "1"  !CDS_PN = "1";
"B":   PN = "2"  !CDS_PN = "2";
BODY = "Q_CAP","I30": LOCATION = "C1869" #&CDS_LOCATION = "C1869" &SEC = "1" #&CDS_SEC = "1";
"A":   PN = "1"  !CDS_PN = "1";
"B":   PN = "2"  !CDS_PN = "2";
BODY = "Q_CAP","I31": LOCATION = "C2351" #&CDS_LOCATION = "C2351" &SEC = "1" #&CDS_SEC = "1";
"A":   PN = "1"  !CDS_PN = "1";
"B":   PN = "2"  !CDS_PN = "2";
BODY = "Q_CAP","I33": LOCATION = "C1870" #&CDS_LOCATION = "C1870" &SEC = "1" #&CDS_SEC = "1";
"A":   PN = "1"  !CDS_PN = "1";
"B":   PN = "2"  !CDS_PN = "2";
BODY = "Q_CAP","I34": LOCATION = "C1871" #&CDS_LOCATION = "C1871" &SEC = "1" #&CDS_SEC = "1";
"A":   PN = "1"  !CDS_PN = "1";
"B":   PN = "2"  !CDS_PN = "2";
BODY = "Q_RES","I35": LOCATION = "R4666" #&CDS_LOCATION = "R4666" &SEC = "1" #&CDS_SEC = "1";
"A":   PN = "1"  !CDS_PN = "1";
"B":   PN = "2"  !CDS_PN = "2";
BODY = "Q_RES","I36": LOCATION = "R4665" #&CDS_LOCATION = "R4665" &SEC = "1" #&CDS_SEC = "1";
"A":   PN = "1"  !CDS_PN = "1";
"B":   PN = "2"  !CDS_PN = "2";
BODY = "Q_RES","I41": LOCATION = "R4663" #&CDS_LOCATION = "R4663" &SEC = "1" #&CDS_SEC = "1";
"A":   PN = "1"  !CDS_PN = "1";
"B":   PN = "2"  !CDS_PN = "2";
BODY = "Q_RES","I42": LOCATION = "R4664" #&CDS_LOCATION = "R4664" &SEC = "1" #&CDS_SEC = "1";
"A":   PN = "1"  !CDS_PN = "1";
"B":   PN = "2"  !CDS_PN = "2";
BODY = "Q_RES","I43": LOCATION = "R4662" #&CDS_LOCATION = "R4662" &SEC = "1" #&CDS_SEC = "1";
"A":   PN = "1"  !CDS_PN = "1";
"B":   PN = "2"  !CDS_PN = "2";
BODY = "Q_RES","I44": LOCATION = "R4661" #&CDS_LOCATION = "R4661" &SEC = "1" #&CDS_SEC = "1";
"A":   PN = "1"  !CDS_PN = "1";
"B":   PN = "2"  !CDS_PN = "2";
BODY = "Q_RES","I45": LOCATION = "R4660" #&CDS_LOCATION = "R4660" &SEC = "1" #&CDS_SEC = "1";
"A":   PN = "1"  !CDS_PN = "1";
"B":   PN = "2"  !CDS_PN = "2";
BODY = "Q_RES","I46": LOCATION = "R4659" #&CDS_LOCATION = "R4659" &SEC = "1" #&CDS_SEC = "1";
"A":   PN = "1"  !CDS_PN = "1";
"B":   PN = "2"  !CDS_PN = "2";
BODY = "Q_RES","I53": LOCATION = "R3362" #&CDS_LOCATION = "R3362" &SEC = "1" #&CDS_SEC = "1";
"A":   PN = "1"  !CDS_PN = "1";
"B":   PN = "2"  !CDS_PN = "2";
BODY = "Q_RES","I61": LOCATION = "R3381" #&CDS_LOCATION = "R3381" &SEC = "1" #&CDS_SEC = "1";
"A":   PN = "1"  !CDS_PN = "1";
"B":   PN = "2"  !CDS_PN = "2";
BODY = "Q_RES","I65": LOCATION = "R4657" #&CDS_LOCATION = "R4657" &SEC = "1" #&CDS_SEC = "1";
"A":   PN = "1"  !CDS_PN = "1";
"B":   PN = "2"  !CDS_PN = "2";
BODY = "Q_RES","I71": LOCATION = "R4650" #&CDS_LOCATION = "R4650" &SEC = "1" #&CDS_SEC = "1";
"A":   PN = "1"  !CDS_PN = "1";
"B":   PN = "2"  !CDS_PN = "2";
BODY = "Q_RES","I72": LOCATION = "R4648" #&CDS_LOCATION = "R4648" &SEC = "1" #&CDS_SEC = "1";
"A":   PN = "1"  !CDS_PN = "1";
"B":   PN = "2"  !CDS_PN = "2";
BODY = "Q_RES","I74": LOCATION = "R4649" #&CDS_LOCATION = "R4649" &SEC = "1" #&CDS_SEC = "1";
"A":   PN = "1"  !CDS_PN = "1";
"B":   PN = "2"  !CDS_PN = "2";
BODY = "Q_RES","I80": LOCATION = "R4658" #&CDS_LOCATION = "R4658" &SEC = "1" #&CDS_SEC = "1";
"A":   PN = "1"  !CDS_PN = "1";
"B":   PN = "2"  !CDS_PN = "2";
BODY = "Q_CAP","I96": LOCATION = "C2355" #&CDS_LOCATION = "C2355" &SEC = "1" #&CDS_SEC = "1";
"A":   PN = "1"  !CDS_PN = "1";
"B":   PN = "2"  !CDS_PN = "2";
BODY = "Q_CAP","I98": LOCATION = "C2356" #&CDS_LOCATION = "C2356" &SEC = "1" #&CDS_SEC = "1";
"A":   PN = "1"  !CDS_PN = "1";
"B":   PN = "2"  !CDS_PN = "2";
BODY = "Q_CAP","I99": LOCATION = "C2357" #&CDS_LOCATION = "C2357" &SEC = "1" #&CDS_SEC = "1";
"A":   PN = "1"  !CDS_PN = "1";
"B":   PN = "2"  !CDS_PN = "2";
DRAWING = "@s9s_mb_2u_lib.s9s_mb_2u(sch_1):page299";
BODY = "Q_RES","I3": LOCATION = "R3430" #&CDS_LOCATION = "R3430" &SEC = "1" #&CDS_SEC = "1";
"A":   PN = "1"  !CDS_PN = "1";
"B":   PN = "2"  !CDS_PN = "2";
BODY = "Q_RES","I17": LOCATION = "R3428" #&CDS_LOCATION = "R3428" &SEC = "1" #&CDS_SEC = "1";
"A":   PN = "1"  !CDS_PN = "1";
"B":   PN = "2"  !CDS_PN = "2";
BODY = "MOSFET_NCH_DUAL","I21": LOCATION = "Q104" #&CDS_LOCATION = "Q104" &SEC = "1" #&CDS_SEC = "1";
"D1":   PN = "6"  !CDS_PN = "6";
"G1":   PN = "2"  !CDS_PN = "2";
"S1":   PN = "1"  !CDS_PN = "1";
BODY = "Q_RES","I23": LOCATION = "R3435" #&CDS_LOCATION = "R3435" &SEC = "1" #&CDS_SEC = "1";
"A":   PN = "1"  !CDS_PN = "1";
"B":   PN = "2"  !CDS_PN = "2";
BODY = "MOSFET_NCH_DUAL","I26": #LOCATION = "Q104" !CDS_LOCATION = "Q104" &SEC = "2" #&CDS_SEC = "2";
"D2":   PN = "3"  !CDS_PN = "3";
"G2":   PN = "5"  !CDS_PN = "5";
"S2":   PN = "4"  !CDS_PN = "4";
BODY = "Q_RES","I27": LOCATION = "R3437" #&CDS_LOCATION = "R3437" &SEC = "1" #&CDS_SEC = "1";
"A":   PN = "1"  !CDS_PN = "1";
"B":   PN = "2"  !CDS_PN = "2";
BODY = "Q_CAP","I30": LOCATION = "C1976" #&CDS_LOCATION = "C1976" &SEC = "1" #&CDS_SEC = "1";
"A":   PN = "1"  !CDS_PN = "1";
"B":   PN = "2"  !CDS_PN = "2";
BODY = "MOSFET_NCH_DUAL","I37": LOCATION = "Q103" #&CDS_LOCATION = "Q103" &SEC = "1" #&CDS_SEC = "1";
"D1":   PN = "6"  !CDS_PN = "6";
"G1":   PN = "2"  !CDS_PN = "2";
"S1":   PN = "1"  !CDS_PN = "1";
BODY = "Q_RES","I39": LOCATION = "R3434" #&CDS_LOCATION = "R3434" &SEC = "1" #&CDS_SEC = "1";
"A":   PN = "1"  !CDS_PN = "1";
"B":   PN = "2"  !CDS_PN = "2";
BODY = "MOSFET_NCH_DUAL","I40": LOCATION = "Q102" #&CDS_LOCATION = "Q102" &SEC = "1" #&CDS_SEC = "1";
"D1":   PN = "6"  !CDS_PN = "6";
"G1":   PN = "2"  !CDS_PN = "2";
"S1":   PN = "1"  !CDS_PN = "1";
BODY = "MOSFET_NCH_DUAL","I43": #LOCATION = "Q103" !CDS_LOCATION = "Q103" &SEC = "2" #&CDS_SEC = "2";
"D2":   PN = "3"  !CDS_PN = "3";
"G2":   PN = "5"  !CDS_PN = "5";
"S2":   PN = "4"  !CDS_PN = "4";
BODY = "Q_RES","I45": LOCATION = "R3436" #&CDS_LOCATION = "R3436" &SEC = "1" #&CDS_SEC = "1";
"A":   PN = "1"  !CDS_PN = "1";
"B":   PN = "2"  !CDS_PN = "2";
BODY = "MOSFET_NCH_DUAL","I48": LOCATION = "Q102" #&CDS_LOCATION = "Q102" &SEC = "2" #&CDS_SEC = "2";
"D2":   PN = "3"  !CDS_PN = "3";
"G2":   PN = "5"  !CDS_PN = "5";
"S2":   PN = "4"  !CDS_PN = "4";
BODY = "Q_RES","I49": LOCATION = "R3433" #&CDS_LOCATION = "R3433" &SEC = "1" #&CDS_SEC = "1";
"A":   PN = "1"  !CDS_PN = "1";
"B":   PN = "2"  !CDS_PN = "2";
BODY = "MOSFET_NCH_DUAL","I52": LOCATION = "Q101" #&CDS_LOCATION = "Q101" &SEC = "1" #&CDS_SEC = "1";
"D1":   PN = "6"  !CDS_PN = "6";
"G1":   PN = "2"  !CDS_PN = "2";
"S1":   PN = "1"  !CDS_PN = "1";
BODY = "Q_RES","I53": LOCATION = "R3432" #&CDS_LOCATION = "R3432" &SEC = "1" #&CDS_SEC = "1";
"A":   PN = "1"  !CDS_PN = "1";
"B":   PN = "2"  !CDS_PN = "2";
BODY = "Q_RES","I55": LOCATION = "R3438" #&CDS_LOCATION = "R3438" &SEC = "1" #&CDS_SEC = "1";
"A":   PN = "1"  !CDS_PN = "1";
"B":   PN = "2"  !CDS_PN = "2";
BODY = "MOSFET_NCH_DUAL","I57": LOCATION = "Q101" #&CDS_LOCATION = "Q101" &SEC = "2" #&CDS_SEC = "2";
"D2":   PN = "3"  !CDS_PN = "3";
"G2":   PN = "5"  !CDS_PN = "5";
"S2":   PN = "4"  !CDS_PN = "4";
BODY = "Q_RES","I59": LOCATION = "R3439" #&CDS_LOCATION = "R3439" &SEC = "1" #&CDS_SEC = "1";
"A":   PN = "1"  !CDS_PN = "1";
"B":   PN = "2"  !CDS_PN = "2";
BODY = "Q_CAP","I71": LOCATION = "C1973" #&CDS_LOCATION = "C1973" &SEC = "1" #&CDS_SEC = "1";
"A":   PN = "1"  !CDS_PN = "1";
"B":   PN = "2"  !CDS_PN = "2";
BODY = "Q_CAP","I74": LOCATION = "C1974" #&CDS_LOCATION = "C1974" &SEC = "1" #&CDS_SEC = "1";
"A":   PN = "1"  !CDS_PN = "1";
"B":   PN = "2"  !CDS_PN = "2";
BODY = "Q_CAP","I129": LOCATION = "C1975" #&CDS_LOCATION = "C1975" &SEC = "1" #&CDS_SEC = "1";
"A":   PN = "1"  !CDS_PN = "1";
"B":   PN = "2"  !CDS_PN = "2";
BODY = "Q_RES","I130": LOCATION = "R3429" #&CDS_LOCATION = "R3429" &SEC = "1" #&CDS_SEC = "1";
"A":   PN = "1"  !CDS_PN = "1";
"B":   PN = "2"  !CDS_PN = "2";
BODY = "Q_RES","I131": LOCATION = "R3463" #&CDS_LOCATION = "R3463" &SEC = "1" #&CDS_SEC = "1";
"A":   PN = "1"  !CDS_PN = "1";
"B":   PN = "2"  !CDS_PN = "2";
BODY = "Q_RES","I132": LOCATION = "R3465" #&CDS_LOCATION = "R3465" &SEC = "1" #&CDS_SEC = "1";
"A":   PN = "1"  !CDS_PN = "1";
"B":   PN = "2"  !CDS_PN = "2";
BODY = "Q_RES","I133": LOCATION = "R3431" #&CDS_LOCATION = "R3431" &SEC = "1" #&CDS_SEC = "1";
"A":   PN = "1"  !CDS_PN = "1";
"B":   PN = "2"  !CDS_PN = "2";
BODY = "Q_RES","I134": LOCATION = "R3464" #&CDS_LOCATION = "R3464" &SEC = "1" #&CDS_SEC = "1";
"A":   PN = "1"  !CDS_PN = "1";
"B":   PN = "2"  !CDS_PN = "2";
BODY = "MOSFET_NCH_DUAL","I135": LOCATION = "Q106" #&CDS_LOCATION = "Q106" &SEC = "1" #&CDS_SEC = "1";
"D1":   PN = "6"  !CDS_PN = "6";
"G1":   PN = "2"  !CDS_PN = "2";
"S1":   PN = "1"  !CDS_PN = "1";
BODY = "Q_RES","I144": LOCATION = "R3471" #&CDS_LOCATION = "R3471" &SEC = "1" #&CDS_SEC = "1";
"A":   PN = "1"  !CDS_PN = "1";
"B":   PN = "2"  !CDS_PN = "2";
BODY = "Q_RES","I145": LOCATION = "R3470" #&CDS_LOCATION = "R3470" &SEC = "1" #&CDS_SEC = "1";
"A":   PN = "1"  !CDS_PN = "1";
"B":   PN = "2"  !CDS_PN = "2";
BODY = "Q_RES","I147": LOCATION = "R3472" #&CDS_LOCATION = "R3472" &SEC = "1" #&CDS_SEC = "1";
"A":   PN = "1"  !CDS_PN = "1";
"B":   PN = "2"  !CDS_PN = "2";
BODY = "Q_CAP","I152": LOCATION = "C1978" #&CDS_LOCATION = "C1978" &SEC = "1" #&CDS_SEC = "1";
"A":   PN = "1"  !CDS_PN = "1";
"B":   PN = "2"  !CDS_PN = "2";
BODY = "Q_RES","I154": LOCATION = "R3475" #&CDS_LOCATION = "R3475" &SEC = "1" #&CDS_SEC = "1";
"A":   PN = "1"  !CDS_PN = "1";
"B":   PN = "2"  !CDS_PN = "2";
BODY = "MOSFET_NCH_DUAL","I157": #LOCATION = "Q107" !CDS_LOCATION = "Q107" &SEC = "2" #&CDS_SEC = "2";
"D2":   PN = "3"  !CDS_PN = "3";
"G2":   PN = "5"  !CDS_PN = "5";
"S2":   PN = "4"  !CDS_PN = "4";
BODY = "Q_RES","I158": LOCATION = "R3474" #&CDS_LOCATION = "R3474" &SEC = "1" #&CDS_SEC = "1";
"A":   PN = "1"  !CDS_PN = "1";
"B":   PN = "2"  !CDS_PN = "2";
BODY = "MOSFET_NCH_DUAL","I160": LOCATION = "Q107" #&CDS_LOCATION = "Q107" &SEC = "1" #&CDS_SEC = "1";
"D1":   PN = "6"  !CDS_PN = "6";
"G1":   PN = "2"  !CDS_PN = "2";
"S1":   PN = "1"  !CDS_PN = "1";
BODY = "Q_RES","I163": LOCATION = "R3473" #&CDS_LOCATION = "R3473" &SEC = "1" #&CDS_SEC = "1";
"A":   PN = "1"  !CDS_PN = "1";
"B":   PN = "2"  !CDS_PN = "2";
BODY = "Q_RES","I166": LOCATION = "R3487" #&CDS_LOCATION = "R3487" &SEC = "1" #&CDS_SEC = "1";
"A":   PN = "1"  !CDS_PN = "1";
"B":   PN = "2"  !CDS_PN = "2";
BODY = "Q_RES","I167": LOCATION = "R3498" #&CDS_LOCATION = "R3498" &SEC = "1" #&CDS_SEC = "1";
"A":   PN = "1"  !CDS_PN = "1";
"B":   PN = "2"  !CDS_PN = "2";
BODY = "MOSFET_NCH_DUAL","I168": #LOCATION = "Q108" !CDS_LOCATION = "Q108" &SEC = "2" #&CDS_SEC = "2";
"D2":   PN = "3"  !CDS_PN = "3";
"G2":   PN = "5"  !CDS_PN = "5";
"S2":   PN = "4"  !CDS_PN = "4";
BODY = "MOSFET_NCH_DUAL","I169": LOCATION = "Q108" #&CDS_LOCATION = "Q108" &SEC = "1" #&CDS_SEC = "1";
"D1":   PN = "6"  !CDS_PN = "6";
"G1":   PN = "2"  !CDS_PN = "2";
"S1":   PN = "1"  !CDS_PN = "1";
BODY = "Q_CAP","I171": LOCATION = "C1988" #&CDS_LOCATION = "C1988" &SEC = "1" #&CDS_SEC = "1";
"A":   PN = "1"  !CDS_PN = "1";
"B":   PN = "2"  !CDS_PN = "2";
BODY = "Q_RES","I174": LOCATION = "R3504" #&CDS_LOCATION = "R3504" &SEC = "1" #&CDS_SEC = "1";
"A":   PN = "1"  !CDS_PN = "1";
"B":   PN = "2"  !CDS_PN = "2";
BODY = "Q_RES","I177": LOCATION = "R3503" #&CDS_LOCATION = "R3503" &SEC = "1" #&CDS_SEC = "1";
"A":   PN = "1"  !CDS_PN = "1";
"B":   PN = "2"  !CDS_PN = "2";
BODY = "Q_RES","I181": LOCATION = "R3502" #&CDS_LOCATION = "R3502" &SEC = "1" #&CDS_SEC = "1";
"A":   PN = "1"  !CDS_PN = "1";
"B":   PN = "2"  !CDS_PN = "2";
BODY = "Q_RES","I184": LOCATION = "R3525" #&CDS_LOCATION = "R3525" &SEC = "1" #&CDS_SEC = "1";
"A":   PN = "1"  !CDS_PN = "1";
"B":   PN = "2"  !CDS_PN = "2";
DRAWING = "@s9s_mb_2u_lib.s9s_mb_2u(sch_1):page160";
BODY = "74LVC2G17GW","I26": LOCATION = "U253" #&CDS_LOCATION = "U253" &SEC = "1" #&CDS_SEC = "1";
"A0":   PN = "1"  !CDS_PN = "1";
"A1":   PN = "3"  !CDS_PN = "3";
"B0":   PN = "6"  !CDS_PN = "6";
"B1":   PN = "4"  !CDS_PN = "4";
"GND":   PN = "2"  !CDS_PN = "2";
"VCC":   PN = "5"  !CDS_PN = "5";
BODY = "Q_CAP","I29": LOCATION = "C1958" #&CDS_LOCATION = "C1958" &SEC = "1" #&CDS_SEC = "1";
"A":   PN = "1"  !CDS_PN = "1";
"B":   PN = "2"  !CDS_PN = "2";
BODY = "Q_RES","I95": LOCATION = "R3452" #&CDS_LOCATION = "R3452" &SEC = "1" #&CDS_SEC = "1";
"A":   PN = "1"  !CDS_PN = "1";
"B":   PN = "2"  !CDS_PN = "2";
BODY = "Q_RES","I123": LOCATION = "R3457" #&CDS_LOCATION = "R3457" &SEC = "1" #&CDS_SEC = "1";
"A":   PN = "1"  !CDS_PN = "1";
"B":   PN = "2"  !CDS_PN = "2";
BODY = "Q_RES","I124": LOCATION = "R3456" #&CDS_LOCATION = "R3456" &SEC = "1" #&CDS_SEC = "1";
"A":   PN = "1"  !CDS_PN = "1";
"B":   PN = "2"  !CDS_PN = "2";
BODY = "Q_RES","I127": LOCATION = "R3451" #&CDS_LOCATION = "R3451" &SEC = "1" #&CDS_SEC = "1";
"A":   PN = "1"  !CDS_PN = "1";
"B":   PN = "2"  !CDS_PN = "2";
BODY = "Q_RES","I139": LOCATION = "R3455" #&CDS_LOCATION = "R3455" &SEC = "1" #&CDS_SEC = "1";
"A":   PN = "1"  !CDS_PN = "1";
"B":   PN = "2"  !CDS_PN = "2";
BODY = "Q_CAP","I148": LOCATION = "C1957" #&CDS_LOCATION = "C1957" &SEC = "1" #&CDS_SEC = "1";
"A":   PN = "1"  !CDS_PN = "1";
"B":   PN = "2"  !CDS_PN = "2";
BODY = "74LVC2G17GW","I153": LOCATION = "U252" #&CDS_LOCATION = "U252" &SEC = "1" #&CDS_SEC = "1";
"A0":   PN = "1"  !CDS_PN = "1";
"A1":   PN = "3"  !CDS_PN = "3";
"B0":   PN = "6"  !CDS_PN = "6";
"B1":   PN = "4"  !CDS_PN = "4";
"GND":   PN = "2"  !CDS_PN = "2";
"VCC":   PN = "5"  !CDS_PN = "5";
BODY = "Q_RES","I164": LOCATION = "R3453" #&CDS_LOCATION = "R3453" &SEC = "1" #&CDS_SEC = "1";
"A":   PN = "1"  !CDS_PN = "1";
"B":   PN = "2"  !CDS_PN = "2";
BODY = "Q_RES","I165": LOCATION = "R3454" #&CDS_LOCATION = "R3454" &SEC = "1" #&CDS_SEC = "1";
"A":   PN = "1"  !CDS_PN = "1";
"B":   PN = "2"  !CDS_PN = "2";
BODY = "Q_RES","I168": LOCATION = "R3448" #&CDS_LOCATION = "R3448" &SEC = "1" #&CDS_SEC = "1";
"A":   PN = "1"  !CDS_PN = "1";
"B":   PN = "2"  !CDS_PN = "2";
BODY = "Q_RES","I170": LOCATION = "R3449" #&CDS_LOCATION = "R3449" &SEC = "1" #&CDS_SEC = "1";
"A":   PN = "1"  !CDS_PN = "1";
"B":   PN = "2"  !CDS_PN = "2";
BODY = "74LVC2G17GW","I173": LOCATION = "U256" #&CDS_LOCATION = "U256" &SEC = "1" #&CDS_SEC = "1";
"A0":   PN = "1"  !CDS_PN = "1";
"A1":   PN = "3"  !CDS_PN = "3";
"B0":   PN = "6"  !CDS_PN = "6";
"B1":   PN = "4"  !CDS_PN = "4";
"GND":   PN = "2"  !CDS_PN = "2";
"VCC":   PN = "5"  !CDS_PN = "5";
BODY = "Q_CAP","I175": LOCATION = "C1977" #&CDS_LOCATION = "C1977" &SEC = "1" #&CDS_SEC = "1";
"A":   PN = "1"  !CDS_PN = "1";
"B":   PN = "2"  !CDS_PN = "2";
BODY = "Q_RES","I181": LOCATION = "R3467" #&CDS_LOCATION = "R3467" &SEC = "1" #&CDS_SEC = "1";
"A":   PN = "1"  !CDS_PN = "1";
"B":   PN = "2"  !CDS_PN = "2";
BODY = "Q_RES","I184": LOCATION = "R3466" #&CDS_LOCATION = "R3466" &SEC = "1" #&CDS_SEC = "1";
"A":   PN = "1"  !CDS_PN = "1";
"B":   PN = "2"  !CDS_PN = "2";
BODY = "Q_RES","I187": LOCATION = "R2910" #&CDS_LOCATION = "R2910" &SEC = "1" #&CDS_SEC = "1";
"A":   PN = "1"  !CDS_PN = "1";
"B":   PN = "2"  !CDS_PN = "2";
BODY = "Q_RES","I188": LOCATION = "R2918" #&CDS_LOCATION = "R2918" &SEC = "1" #&CDS_SEC = "1";
"A":   PN = "1"  !CDS_PN = "1";
"B":   PN = "2"  !CDS_PN = "2";
BODY = "Q_RES","I192": LOCATION = "R2914" #&CDS_LOCATION = "R2914" &SEC = "1" #&CDS_SEC = "1";
"A":   PN = "1"  !CDS_PN = "1";
"B":   PN = "2"  !CDS_PN = "2";
BODY = "Q_RES","I195": LOCATION = "R2932" #&CDS_LOCATION = "R2932" &SEC = "1" #&CDS_SEC = "1";
"A":   PN = "1"  !CDS_PN = "1";
"B":   PN = "2"  !CDS_PN = "2";
BODY = "Q_RES","I197": #LOCATION = "R3468" !CDS_LOCATION = "R3468" &SEC = "1" #&CDS_SEC = "1";
"A":   PN = "1"  !CDS_PN = "1";
"B":   PN = "2"  !CDS_PN = "2";
BODY = "Q_RES","I198": #LOCATION = "R3515" !CDS_LOCATION = "R3515" &SEC = "1" #&CDS_SEC = "1";
"A":   PN = "1"  !CDS_PN = "1";
"B":   PN = "2"  !CDS_PN = "2";
BODY = "Q_RES","I199": #LOCATION = "R3469" !CDS_LOCATION = "R3469" &SEC = "1" #&CDS_SEC = "1";
"A":   PN = "1"  !CDS_PN = "1";
"B":   PN = "2"  !CDS_PN = "2";
BODY = "Q_RES","I200": #LOCATION = "R3391" !CDS_LOCATION = "R3391" &SEC = "1" #&CDS_SEC = "1";
"A":   PN = "1"  !CDS_PN = "1";
"B":   PN = "2"  !CDS_PN = "2";
BODY = "Q_RES","I201": #LOCATION = "R3390" !CDS_LOCATION = "R3390" &SEC = "1" #&CDS_SEC = "1";
"A":   PN = "1"  !CDS_PN = "1";
"B":   PN = "2"  !CDS_PN = "2";
BODY = "Q_RES","I202": #LOCATION = "R3392" !CDS_LOCATION = "R3392" &SEC = "1" #&CDS_SEC = "1";
"A":   PN = "1"  !CDS_PN = "1";
"B":   PN = "2"  !CDS_PN = "2";
DRAWING = "@s9s_mb_2u_lib.s9s_mb_2u(sch_1):page147";
BODY = "Q_RES","I5": LOCATION = "R3443" #&CDS_LOCATION = "R3443" &SEC = "1" #&CDS_SEC = "1";
"A":   PN = "1"  !CDS_PN = "1";
"B":   PN = "2"  !CDS_PN = "2";
BODY = "Q_RES","I8": LOCATION = "R3440" #&CDS_LOCATION = "R3440" &SEC = "1" #&CDS_SEC = "1";
"A":   PN = "1"  !CDS_PN = "1";
"B":   PN = "2"  !CDS_PN = "2";
BODY = "Q_RES","I11": LOCATION = "R2656" #&CDS_LOCATION = "R2656" &SEC = "1" #&CDS_SEC = "1";
"A":   PN = "1"  !CDS_PN = "1";
"B":   PN = "2"  !CDS_PN = "2";
BODY = "Q_RES","I6": LOCATION = "R3442" #&CDS_LOCATION = "R3442" &SEC = "1" #&CDS_SEC = "1";
"A":   PN = "1"  !CDS_PN = "1";
"B":   PN = "2"  !CDS_PN = "2";
BODY = "Q_RES","I7": LOCATION = "R3441" #&CDS_LOCATION = "R3441" &SEC = "1" #&CDS_SEC = "1";
"A":   PN = "1"  !CDS_PN = "1";
"B":   PN = "2"  !CDS_PN = "2";
BODY = "Q_CAP","I15": LOCATION = "C2372" #&CDS_LOCATION = "C2372" &SEC = "1" #&CDS_SEC = "1";
"A":   PN = "1"  !CDS_PN = "1";
"B":   PN = "2"  !CDS_PN = "2";
BODY = "Q_RES","I18": LOCATION = "R4726" #&CDS_LOCATION = "R4726" &SEC = "1" #&CDS_SEC = "1";
"A":   PN = "1"  !CDS_PN = "1";
"B":   PN = "2"  !CDS_PN = "2";
BODY = "MOSFET_NCH_DUAL","I20": #LOCATION = "Q151" !CDS_LOCATION = "Q151" &SEC = "2" #&CDS_SEC = "2";
"D2":   PN = "3"  !CDS_PN = "3";
"G2":   PN = "5"  !CDS_PN = "5";
"S2":   PN = "4"  !CDS_PN = "4";
BODY = "Q_CAP","I22": LOCATION = "C2373" #&CDS_LOCATION = "C2373" &SEC = "1" #&CDS_SEC = "1";
"A":   PN = "1"  !CDS_PN = "1";
"B":   PN = "2"  !CDS_PN = "2";
BODY = "Q_RES","I25": LOCATION = "R4733" #&CDS_LOCATION = "R4733" &SEC = "1" #&CDS_SEC = "1";
"A":   PN = "1"  !CDS_PN = "1";
"B":   PN = "2"  !CDS_PN = "2";
BODY = "MOSFET_NCH_DUAL","I26": #LOCATION = "Q152" !CDS_LOCATION = "Q152" &SEC = "2" #&CDS_SEC = "2";
"D2":   PN = "3"  !CDS_PN = "3";
"G2":   PN = "5"  !CDS_PN = "5";
"S2":   PN = "4"  !CDS_PN = "4";
BODY = "Q_RES","I28": LOCATION = "R4725" #&CDS_LOCATION = "R4725" &SEC = "1" #&CDS_SEC = "1";
"A":   PN = "1"  !CDS_PN = "1";
"B":   PN = "2"  !CDS_PN = "2";
BODY = "MOSFET_NCH_DUAL","I31": LOCATION = "Q151" #&CDS_LOCATION = "Q151" &SEC = "1" #&CDS_SEC = "1";
"D1":   PN = "6"  !CDS_PN = "6";
"G1":   PN = "2"  !CDS_PN = "2";
"S1":   PN = "1"  !CDS_PN = "1";
BODY = "Q_RES","I33": LOCATION = "R4727" #&CDS_LOCATION = "R4727" &SEC = "1" #&CDS_SEC = "1";
"A":   PN = "1"  !CDS_PN = "1";
"B":   PN = "2"  !CDS_PN = "2";
BODY = "Q_RES","I34": LOCATION = "R4724" #&CDS_LOCATION = "R4724" &SEC = "1" #&CDS_SEC = "1";
"A":   PN = "1"  !CDS_PN = "1";
"B":   PN = "2"  !CDS_PN = "2";
BODY = "Q_RES","I36": LOCATION = "R4732" #&CDS_LOCATION = "R4732" &SEC = "1" #&CDS_SEC = "1";
"A":   PN = "1"  !CDS_PN = "1";
"B":   PN = "2"  !CDS_PN = "2";
BODY = "MOSFET_NCH_DUAL","I38": LOCATION = "Q152" #&CDS_LOCATION = "Q152" &SEC = "1" #&CDS_SEC = "1";
"D1":   PN = "6"  !CDS_PN = "6";
"G1":   PN = "2"  !CDS_PN = "2";
"S1":   PN = "1"  !CDS_PN = "1";
BODY = "Q_RES","I41": LOCATION = "R4730" #&CDS_LOCATION = "R4730" &SEC = "1" #&CDS_SEC = "1";
"A":   PN = "1"  !CDS_PN = "1";
"B":   PN = "2"  !CDS_PN = "2";
BODY = "Q_RES","I42": LOCATION = "R4731" #&CDS_LOCATION = "R4731" &SEC = "1" #&CDS_SEC = "1";
"A":   PN = "1"  !CDS_PN = "1";
"B":   PN = "2"  !CDS_PN = "2";
BODY = "Q_CAP","I47": LOCATION = "C2374" #&CDS_LOCATION = "C2374" &SEC = "1" #&CDS_SEC = "1";
"A":   PN = "1"  !CDS_PN = "1";
"B":   PN = "2"  !CDS_PN = "2";
BODY = "Q_RES","I50": LOCATION = "R4740" #&CDS_LOCATION = "R4740" &SEC = "1" #&CDS_SEC = "1";
"A":   PN = "1"  !CDS_PN = "1";
"B":   PN = "2"  !CDS_PN = "2";
BODY = "MOSFET_NCH_DUAL","I51": #LOCATION = "Q153" !CDS_LOCATION = "Q153" &SEC = "2" #&CDS_SEC = "2";
"D2":   PN = "3"  !CDS_PN = "3";
"G2":   PN = "5"  !CDS_PN = "5";
"S2":   PN = "4"  !CDS_PN = "4";
BODY = "Q_RES","I54": LOCATION = "R4739" #&CDS_LOCATION = "R4739" &SEC = "1" #&CDS_SEC = "1";
"A":   PN = "1"  !CDS_PN = "1";
"B":   PN = "2"  !CDS_PN = "2";
BODY = "MOSFET_NCH_DUAL","I55": #LOCATION = "Q153" !CDS_LOCATION = "Q153" &SEC = "1" #&CDS_SEC = "1";
"D1":   PN = "6"  !CDS_PN = "6";
"G1":   PN = "2"  !CDS_PN = "2";
"S1":   PN = "1"  !CDS_PN = "1";
BODY = "Q_RES","I58": LOCATION = "R4737" #&CDS_LOCATION = "R4737" &SEC = "1" #&CDS_SEC = "1";
"A":   PN = "1"  !CDS_PN = "1";
"B":   PN = "2"  !CDS_PN = "2";
BODY = "Q_RES","I60": LOCATION = "R4738" #&CDS_LOCATION = "R4738" &SEC = "1" #&CDS_SEC = "1";
"A":   PN = "1"  !CDS_PN = "1";
"B":   PN = "2"  !CDS_PN = "2";
BODY = "MOSFET_NCH_DUAL","I62": #LOCATION = "Q154" !CDS_LOCATION = "Q154" &SEC = "2" #&CDS_SEC = "2";
"D2":   PN = "3"  !CDS_PN = "3";
"G2":   PN = "5"  !CDS_PN = "5";
"S2":   PN = "4"  !CDS_PN = "4";
BODY = "Q_RES","I65": LOCATION = "R4801" #&CDS_LOCATION = "R4801" &SEC = "1" #&CDS_SEC = "1";
"A":   PN = "1"  !CDS_PN = "1";
"B":   PN = "2"  !CDS_PN = "2";
BODY = "Q_CAP","I66": LOCATION = "C2391" #&CDS_LOCATION = "C2391" &SEC = "1" #&CDS_SEC = "1";
"A":   PN = "1"  !CDS_PN = "1";
"B":   PN = "2"  !CDS_PN = "2";
BODY = "Q_RES","I70": LOCATION = "R4800" #&CDS_LOCATION = "R4800" &SEC = "1" #&CDS_SEC = "1";
"A":   PN = "1"  !CDS_PN = "1";
"B":   PN = "2"  !CDS_PN = "2";
BODY = "MOSFET_NCH_DUAL","I71": #LOCATION = "Q154" !CDS_LOCATION = "Q154" &SEC = "1" #&CDS_SEC = "1";
"D1":   PN = "6"  !CDS_PN = "6";
"G1":   PN = "2"  !CDS_PN = "2";
"S1":   PN = "1"  !CDS_PN = "1";
BODY = "Q_RES","I75": LOCATION = "R4798" #&CDS_LOCATION = "R4798" &SEC = "1" #&CDS_SEC = "1";
"A":   PN = "1"  !CDS_PN = "1";
"B":   PN = "2"  !CDS_PN = "2";
BODY = "Q_RES","I76": LOCATION = "R4799" #&CDS_LOCATION = "R4799" &SEC = "1" #&CDS_SEC = "1";
"A":   PN = "1"  !CDS_PN = "1";
"B":   PN = "2"  !CDS_PN = "2";
DRAWING = "@s9s_mb_2u_lib.s9s_mb_2u(sch_1):page296";
BODY = "Q_CAP","I13": LOCATION = "C1963" #&CDS_LOCATION = "C1963" &SEC = "1" #&CDS_SEC = "1";
"A":   PN = "1"  !CDS_PN = "1";
"B":   PN = "2"  !CDS_PN = "2";
BODY = "74LVC2G07DW7","I16": LOCATION = "U255" #&CDS_LOCATION = "U255" &SEC = "1" #&CDS_SEC = "1";
"1A":   PN = "1"  !CDS_PN = "1";
"1Y":   PN = "6"  !CDS_PN = "6";
"2A":   PN = "3"  !CDS_PN = "3";
"2Y":   PN = "4"  !CDS_PN = "4";
"GND":   PN = "2"  !CDS_PN = "2";
"VCC":   PN = "5"  !CDS_PN = "5";
BODY = "Q_RES","I29": LOCATION = "R3459" #&CDS_LOCATION = "R3459" &SEC = "1" #&CDS_SEC = "1";
"A":   PN = "1"  !CDS_PN = "1";
"B":   PN = "2"  !CDS_PN = "2";
BODY = "Q_RES","I31": LOCATION = "R3460" #&CDS_LOCATION = "R3460" &SEC = "1" #&CDS_SEC = "1";
"A":   PN = "1"  !CDS_PN = "1";
"B":   PN = "2"  !CDS_PN = "2";
BODY = "Q_RES","I33": LOCATION = "R3462" #&CDS_LOCATION = "R3462" &SEC = "1" #&CDS_SEC = "1";
"A":   PN = "1"  !CDS_PN = "1";
"B":   PN = "2"  !CDS_PN = "2";
BODY = "Q_RES","I35": LOCATION = "R3461" #&CDS_LOCATION = "R3461" &SEC = "1" #&CDS_SEC = "1";
"A":   PN = "1"  !CDS_PN = "1";
"B":   PN = "2"  !CDS_PN = "2";
BODY = "Q_RES","I37": LOCATION = "R3397" #&CDS_LOCATION = "R3397" &SEC = "1" #&CDS_SEC = "1";
"A":   PN = "1"  !CDS_PN = "1";
"B":   PN = "2"  !CDS_PN = "2";
BODY = "Q_RES","I40": LOCATION = "R3488" #&CDS_LOCATION = "R3488" &SEC = "1" #&CDS_SEC = "1";
"A":   PN = "1"  !CDS_PN = "1";
"B":   PN = "2"  !CDS_PN = "2";
BODY = "Q_RES","I42": LOCATION = "R3489" #&CDS_LOCATION = "R3489" &SEC = "1" #&CDS_SEC = "1";
"A":   PN = "1"  !CDS_PN = "1";
"B":   PN = "2"  !CDS_PN = "2";
BODY = "Q_RES","I45": LOCATION = "R3496" #&CDS_LOCATION = "R3496" &SEC = "1" #&CDS_SEC = "1";
"A":   PN = "1"  !CDS_PN = "1";
"B":   PN = "2"  !CDS_PN = "2";
BODY = "Q_RES","I47": LOCATION = "R3492" #&CDS_LOCATION = "R3492" &SEC = "1" #&CDS_SEC = "1";
"A":   PN = "1"  !CDS_PN = "1";
"B":   PN = "2"  !CDS_PN = "2";
BODY = "Q_RES","I48": LOCATION = "R3493" #&CDS_LOCATION = "R3493" &SEC = "1" #&CDS_SEC = "1";
"A":   PN = "1"  !CDS_PN = "1";
"B":   PN = "2"  !CDS_PN = "2";
BODY = "74LVC2G07DW7","I50": LOCATION = "U257" #&CDS_LOCATION = "U257" &SEC = "1" #&CDS_SEC = "1";
"1A":   PN = "1"  !CDS_PN = "1";
"1Y":   PN = "6"  !CDS_PN = "6";
"2A":   PN = "3"  !CDS_PN = "3";
"2Y":   PN = "4"  !CDS_PN = "4";
"GND":   PN = "2"  !CDS_PN = "2";
"VCC":   PN = "5"  !CDS_PN = "5";
BODY = "Q_RES","I53": LOCATION = "R3497" #&CDS_LOCATION = "R3497" &SEC = "1" #&CDS_SEC = "1";
"A":   PN = "1"  !CDS_PN = "1";
"B":   PN = "2"  !CDS_PN = "2";
BODY = "Q_RES","I55": LOCATION = "R3494" #&CDS_LOCATION = "R3494" &SEC = "1" #&CDS_SEC = "1";
"A":   PN = "1"  !CDS_PN = "1";
"B":   PN = "2"  !CDS_PN = "2";
BODY = "Q_RES","I57": LOCATION = "R3490" #&CDS_LOCATION = "R3490" &SEC = "1" #&CDS_SEC = "1";
"A":   PN = "1"  !CDS_PN = "1";
"B":   PN = "2"  !CDS_PN = "2";
BODY = "Q_RES","I62": LOCATION = "R3495" #&CDS_LOCATION = "R3495" &SEC = "1" #&CDS_SEC = "1";
"A":   PN = "1"  !CDS_PN = "1";
"B":   PN = "2"  !CDS_PN = "2";
BODY = "Q_CAP","I67": LOCATION = "C1979" #&CDS_LOCATION = "C1979" &SEC = "1" #&CDS_SEC = "1";
"A":   PN = "1"  !CDS_PN = "1";
"B":   PN = "2"  !CDS_PN = "2";
BODY = "Q_RES","I70": LOCATION = "R3491" #&CDS_LOCATION = "R3491" &SEC = "1" #&CDS_SEC = "1";
"A":   PN = "1"  !CDS_PN = "1";
"B":   PN = "2"  !CDS_PN = "2";
DRAWING = "@s9s_mb_2u_lib.s9s_mb_2u(sch_1):page220";
BODY = "Q_RES","I3": LOCATION = "R3587" #&CDS_LOCATION = "R3587" &SEC = "1" #&CDS_SEC = "1";
"A":   PN = "1"  !CDS_PN = "1";
"B":   PN = "2"  !CDS_PN = "2";
BODY = "Q_RES","I4": LOCATION = "R3586" #&CDS_LOCATION = "R3586" &SEC = "1" #&CDS_SEC = "1";
"A":   PN = "1"  !CDS_PN = "1";
"B":   PN = "2"  !CDS_PN = "2";
BODY = "Q_RES","I11": LOCATION = "R3589" #&CDS_LOCATION = "R3589" &SEC = "1" #&CDS_SEC = "1";
"A":   PN = "1"  !CDS_PN = "1";
"B":   PN = "2"  !CDS_PN = "2";
BODY = "Q_RES","I16": LOCATION = "R3588" #&CDS_LOCATION = "R3588" &SEC = "1" #&CDS_SEC = "1";
"A":   PN = "1"  !CDS_PN = "1";
"B":   PN = "2"  !CDS_PN = "2";
BODY = "Q_RES","I17": LOCATION = "R3590" #&CDS_LOCATION = "R3590" &SEC = "1" #&CDS_SEC = "1";
"A":   PN = "1"  !CDS_PN = "1";
"B":   PN = "2"  !CDS_PN = "2";
BODY = "Q_RES","I18": LOCATION = "R3591" #&CDS_LOCATION = "R3591" &SEC = "1" #&CDS_SEC = "1";
"A":   PN = "1"  !CDS_PN = "1";
"B":   PN = "2"  !CDS_PN = "2";
BODY = "Q_RES","I19": LOCATION = "R3593" #&CDS_LOCATION = "R3593" &SEC = "1" #&CDS_SEC = "1";
"A":   PN = "1"  !CDS_PN = "1";
"B":   PN = "2"  !CDS_PN = "2";
BODY = "Q_RES","I20": LOCATION = "R3592" #&CDS_LOCATION = "R3592" &SEC = "1" #&CDS_SEC = "1";
"A":   PN = "1"  !CDS_PN = "1";
"B":   PN = "2"  !CDS_PN = "2";
BODY = "Q_RES","I21": LOCATION = "R3594" #&CDS_LOCATION = "R3594" &SEC = "1" #&CDS_SEC = "1";
"A":   PN = "1"  !CDS_PN = "1";
"B":   PN = "2"  !CDS_PN = "2";
BODY = "Q_RES","I26": LOCATION = "R3595" #&CDS_LOCATION = "R3595" &SEC = "1" #&CDS_SEC = "1";
"A":   PN = "1"  !CDS_PN = "1";
"B":   PN = "2"  !CDS_PN = "2";
DRAWING = "@s9s_mb_2u_lib.s9s_mb_2u(sch_1):page163";
BODY = "Q_CAP","I26": LOCATION = "C2018" #&CDS_LOCATION = "C2018" &SEC = "1" #&CDS_SEC = "1";
"A":   PN = "1"  !CDS_PN = "1";
"B":   PN = "2"  !CDS_PN = "2";
BODY = "Q_RES","I33": LOCATION = "R3575" #&CDS_LOCATION = "R3575" &SEC = "1" #&CDS_SEC = "1";
"A":   PN = "1"  !CDS_PN = "1";
"B":   PN = "2"  !CDS_PN = "2";
BODY = "Q_RES","I35": LOCATION = "R3574" #&CDS_LOCATION = "R3574" &SEC = "1" #&CDS_SEC = "1";
"A":   PN = "1"  !CDS_PN = "1";
"B":   PN = "2"  !CDS_PN = "2";
BODY = "Q_RES","I36": LOCATION = "R3611" #&CDS_LOCATION = "R3611" &SEC = "1" #&CDS_SEC = "1";
"A":   PN = "1"  !CDS_PN = "1";
"B":   PN = "2"  !CDS_PN = "2";
BODY = "Q_RES","I37": LOCATION = "R3573" #&CDS_LOCATION = "R3573" &SEC = "1" #&CDS_SEC = "1";
"A":   PN = "1"  !CDS_PN = "1";
"B":   PN = "2"  !CDS_PN = "2";
BODY = "Q_RES","I38": LOCATION = "R3572" #&CDS_LOCATION = "R3572" &SEC = "1" #&CDS_SEC = "1";
"A":   PN = "1"  !CDS_PN = "1";
"B":   PN = "2"  !CDS_PN = "2";
BODY = "Q_RES","I41": LOCATION = "R3560" #&CDS_LOCATION = "R3560" &SEC = "1" #&CDS_SEC = "1";
"A":   PN = "1"  !CDS_PN = "1";
"B":   PN = "2"  !CDS_PN = "2";
BODY = "Q_CAP","I42": LOCATION = "C2013" #&CDS_LOCATION = "C2013" &SEC = "1" #&CDS_SEC = "1";
"A":   PN = "1"  !CDS_PN = "1";
"B":   PN = "2"  !CDS_PN = "2";
BODY = "Q_RES","I45": LOCATION = "R3610" #&CDS_LOCATION = "R3610" &SEC = "1" #&CDS_SEC = "1";
"A":   PN = "1"  !CDS_PN = "1";
"B":   PN = "2"  !CDS_PN = "2";
BODY = "INA230AIRGTR","I46": LOCATION = "U264" #&CDS_LOCATION = "U264" &SEC = "1" #&CDS_SEC = "1";
"A0":   PN = "2"  !CDS_PN = "2";
"A1":   PN = "1"  !CDS_PN = "1";
"ALERT":   PN = "3"  !CDS_PN = "3";
"BUS":   PN = "11"  !CDS_PN = "11";
"GND":   PN = "10"  !CDS_PN = "10";
"IN+":   PN = "13"  !CDS_PN = "13";
"IN-":   PN = "12"  !CDS_PN = "12";
"NC0":   PN = "6"  !CDS_PN = "6";
"NC1":   PN = "7"  !CDS_PN = "7";
"NC2":   PN = "8"  !CDS_PN = "8";
"NC3":   PN = "14"  !CDS_PN = "14";
"NC4":   PN = "15"  !CDS_PN = "15";
"NC5":   PN = "16"  !CDS_PN = "16";
"SCL":   PN = "5"  !CDS_PN = "5";
"SDA":   PN = "4"  !CDS_PN = "4";
"TH":   PN = "TH"  !CDS_PN = "TH";
"VS":   PN = "9"  !CDS_PN = "9";
BODY = "Q_CAP","I49": LOCATION = "C2019" #&CDS_LOCATION = "C2019" &SEC = "1" #&CDS_SEC = "1";
"A":   PN = "1"  !CDS_PN = "1";
"B":   PN = "2"  !CDS_PN = "2";
BODY = "Q_RES","I56": LOCATION = "R3579" #&CDS_LOCATION = "R3579" &SEC = "1" #&CDS_SEC = "1";
"A":   PN = "1"  !CDS_PN = "1";
"B":   PN = "2"  !CDS_PN = "2";
BODY = "Q_RES","I58": LOCATION = "R3578" #&CDS_LOCATION = "R3578" &SEC = "1" #&CDS_SEC = "1";
"A":   PN = "1"  !CDS_PN = "1";
"B":   PN = "2"  !CDS_PN = "2";
BODY = "Q_RES","I59": LOCATION = "R3613" #&CDS_LOCATION = "R3613" &SEC = "1" #&CDS_SEC = "1";
"A":   PN = "1"  !CDS_PN = "1";
"B":   PN = "2"  !CDS_PN = "2";
BODY = "Q_RES","I60": LOCATION = "R3577" #&CDS_LOCATION = "R3577" &SEC = "1" #&CDS_SEC = "1";
"A":   PN = "1"  !CDS_PN = "1";
"B":   PN = "2"  !CDS_PN = "2";
BODY = "Q_RES","I61": LOCATION = "R3576" #&CDS_LOCATION = "R3576" &SEC = "1" #&CDS_SEC = "1";
"A":   PN = "1"  !CDS_PN = "1";
"B":   PN = "2"  !CDS_PN = "2";
BODY = "Q_RES","I64": LOCATION = "R3561" #&CDS_LOCATION = "R3561" &SEC = "1" #&CDS_SEC = "1";
"A":   PN = "1"  !CDS_PN = "1";
"B":   PN = "2"  !CDS_PN = "2";
BODY = "Q_CAP","I65": LOCATION = "C2014" #&CDS_LOCATION = "C2014" &SEC = "1" #&CDS_SEC = "1";
"A":   PN = "1"  !CDS_PN = "1";
"B":   PN = "2"  !CDS_PN = "2";
BODY = "Q_RES","I68": LOCATION = "R3612" #&CDS_LOCATION = "R3612" &SEC = "1" #&CDS_SEC = "1";
"A":   PN = "1"  !CDS_PN = "1";
"B":   PN = "2"  !CDS_PN = "2";
BODY = "INA230AIRGTR","I69": LOCATION = "U265" #&CDS_LOCATION = "U265" &SEC = "1" #&CDS_SEC = "1";
"A0":   PN = "2"  !CDS_PN = "2";
"A1":   PN = "1"  !CDS_PN = "1";
"ALERT":   PN = "3"  !CDS_PN = "3";
"BUS":   PN = "11"  !CDS_PN = "11";
"GND":   PN = "10"  !CDS_PN = "10";
"IN+":   PN = "13"  !CDS_PN = "13";
"IN-":   PN = "12"  !CDS_PN = "12";
"NC0":   PN = "6"  !CDS_PN = "6";
"NC1":   PN = "7"  !CDS_PN = "7";
"NC2":   PN = "8"  !CDS_PN = "8";
"NC3":   PN = "14"  !CDS_PN = "14";
"NC4":   PN = "15"  !CDS_PN = "15";
"NC5":   PN = "16"  !CDS_PN = "16";
"SCL":   PN = "5"  !CDS_PN = "5";
"SDA":   PN = "4"  !CDS_PN = "4";
"TH":   PN = "TH"  !CDS_PN = "TH";
"VS":   PN = "9"  !CDS_PN = "9";
BODY = "Q_CAP","I71": LOCATION = "C2021" #&CDS_LOCATION = "C2021" &SEC = "1" #&CDS_SEC = "1";
"A":   PN = "1"  !CDS_PN = "1";
"B":   PN = "2"  !CDS_PN = "2";
BODY = "Q_CAP","I72": LOCATION = "C2022" #&CDS_LOCATION = "C2022" &SEC = "1" #&CDS_SEC = "1";
"A":   PN = "1"  !CDS_PN = "1";
"B":   PN = "2"  !CDS_PN = "2";
BODY = "Q_RES","I86": LOCATION = "R3623" #&CDS_LOCATION = "R3623" &SEC = "1" #&CDS_SEC = "1";
"A":   PN = "1"  !CDS_PN = "1";
"B":   PN = "2"  !CDS_PN = "2";
BODY = "Q_RES","I87": LOCATION = "R3621" #&CDS_LOCATION = "R3621" &SEC = "1" #&CDS_SEC = "1";
"A":   PN = "1"  !CDS_PN = "1";
"B":   PN = "2"  !CDS_PN = "2";
BODY = "Q_RES","I89": LOCATION = "R3624" #&CDS_LOCATION = "R3624" &SEC = "1" #&CDS_SEC = "1";
"A":   PN = "1"  !CDS_PN = "1";
"B":   PN = "2"  !CDS_PN = "2";
BODY = "Q_RES","I90": LOCATION = "R3622" #&CDS_LOCATION = "R3622" &SEC = "1" #&CDS_SEC = "1";
"A":   PN = "1"  !CDS_PN = "1";
"B":   PN = "2"  !CDS_PN = "2";
BODY = "INA230AIRGTR","I94": LOCATION = "U263" #&CDS_LOCATION = "U263" &SEC = "1" #&CDS_SEC = "1";
"A0":   PN = "2"  !CDS_PN = "2";
"A1":   PN = "1"  !CDS_PN = "1";
"ALERT":   PN = "3"  !CDS_PN = "3";
"BUS":   PN = "11"  !CDS_PN = "11";
"GND":   PN = "10"  !CDS_PN = "10";
"IN+":   PN = "13"  !CDS_PN = "13";
"IN-":   PN = "12"  !CDS_PN = "12";
"NC0":   PN = "6"  !CDS_PN = "6";
"NC1":   PN = "7"  !CDS_PN = "7";
"NC2":   PN = "8"  !CDS_PN = "8";
"NC3":   PN = "14"  !CDS_PN = "14";
"NC4":   PN = "15"  !CDS_PN = "15";
"NC5":   PN = "16"  !CDS_PN = "16";
"SCL":   PN = "5"  !CDS_PN = "5";
"SDA":   PN = "4"  !CDS_PN = "4";
"TH":   PN = "TH"  !CDS_PN = "TH";
"VS":   PN = "9"  !CDS_PN = "9";
BODY = "Q_RES","I96": LOCATION = "R3559" #&CDS_LOCATION = "R3559" &SEC = "1" #&CDS_SEC = "1";
"A":   PN = "1"  !CDS_PN = "1";
"B":   PN = "2"  !CDS_PN = "2";
BODY = "Q_CAP","I98": LOCATION = "C2012" #&CDS_LOCATION = "C2012" &SEC = "1" #&CDS_SEC = "1";
"A":   PN = "1"  !CDS_PN = "1";
"B":   PN = "2"  !CDS_PN = "2";
BODY = "Q_RES","I100": LOCATION = "R3620" #&CDS_LOCATION = "R3620" &SEC = "1" #&CDS_SEC = "1";
"A":   PN = "1"  !CDS_PN = "1";
"B":   PN = "2"  !CDS_PN = "2";
BODY = "Q_RES","I101": LOCATION = "R3568" #&CDS_LOCATION = "R3568" &SEC = "1" #&CDS_SEC = "1";
"A":   PN = "1"  !CDS_PN = "1";
"B":   PN = "2"  !CDS_PN = "2";
BODY = "Q_RES","I102": LOCATION = "R3569" #&CDS_LOCATION = "R3569" &SEC = "1" #&CDS_SEC = "1";
"A":   PN = "1"  !CDS_PN = "1";
"B":   PN = "2"  !CDS_PN = "2";
BODY = "Q_RES","I103": LOCATION = "R3608" #&CDS_LOCATION = "R3608" &SEC = "1" #&CDS_SEC = "1";
"A":   PN = "1"  !CDS_PN = "1";
"B":   PN = "2"  !CDS_PN = "2";
BODY = "Q_RES","I104": LOCATION = "R3609" #&CDS_LOCATION = "R3609" &SEC = "1" #&CDS_SEC = "1";
"A":   PN = "1"  !CDS_PN = "1";
"B":   PN = "2"  !CDS_PN = "2";
BODY = "Q_CAP","I108": LOCATION = "C2020" #&CDS_LOCATION = "C2020" &SEC = "1" #&CDS_SEC = "1";
"A":   PN = "1"  !CDS_PN = "1";
"B":   PN = "2"  !CDS_PN = "2";
BODY = "Q_RES","I109": LOCATION = "R3570" #&CDS_LOCATION = "R3570" &SEC = "1" #&CDS_SEC = "1";
"A":   PN = "1"  !CDS_PN = "1";
"B":   PN = "2"  !CDS_PN = "2";
BODY = "Q_RES","I110": LOCATION = "R3571" #&CDS_LOCATION = "R3571" &SEC = "1" #&CDS_SEC = "1";
"A":   PN = "1"  !CDS_PN = "1";
"B":   PN = "2"  !CDS_PN = "2";
BODY = "Q_CAP","I114": LOCATION = "C2017" #&CDS_LOCATION = "C2017" &SEC = "1" #&CDS_SEC = "1";
"A":   PN = "1"  !CDS_PN = "1";
"B":   PN = "2"  !CDS_PN = "2";
BODY = "Q_RES","I122": LOCATION = "R4091" #&CDS_LOCATION = "R4091" &SEC = "1" #&CDS_SEC = "1";
"A":   PN = "1"  !CDS_PN = "1";
"B":   PN = "2"  !CDS_PN = "2";
BODY = "Q_RES","I124": LOCATION = "R4090" #&CDS_LOCATION = "R4090" &SEC = "1" #&CDS_SEC = "1";
"A":   PN = "1"  !CDS_PN = "1";
"B":   PN = "2"  !CDS_PN = "2";
BODY = "Q_RES","I126": LOCATION = "R4092" #&CDS_LOCATION = "R4092" &SEC = "1" #&CDS_SEC = "1";
"A":   PN = "1"  !CDS_PN = "1";
"B":   PN = "2"  !CDS_PN = "2";
BODY = "Q_RES","I127": #LOCATION = "R3633" !CDS_LOCATION = "R3633" &SEC = "1" #&CDS_SEC = "1";
"A":   PN = "1"  !CDS_PN = "1";
"B":   PN = "2"  !CDS_PN = "2";
BODY = "Q_RES","I128": #LOCATION = "R3634" !CDS_LOCATION = "R3634" &SEC = "1" #&CDS_SEC = "1";
"A":   PN = "1"  !CDS_PN = "1";
"B":   PN = "2"  !CDS_PN = "2";
BODY = "Q_RES","I129": #LOCATION = "R3635" !CDS_LOCATION = "R3635" &SEC = "1" #&CDS_SEC = "1";
"A":   PN = "1"  !CDS_PN = "1";
"B":   PN = "2"  !CDS_PN = "2";
DRAWING = "@s9s_mb_2u_lib.s9s_mb_2u(sch_1):page295";
BODY = "INA230AIRGTR","I30": LOCATION = "U266" #&CDS_LOCATION = "U266" &SEC = "1" #&CDS_SEC = "1";
"A0":   PN = "2"  !CDS_PN = "2";
"A1":   PN = "1"  !CDS_PN = "1";
"ALERT":   PN = "3"  !CDS_PN = "3";
"BUS":   PN = "11"  !CDS_PN = "11";
"GND":   PN = "10"  !CDS_PN = "10";
"IN+":   PN = "13"  !CDS_PN = "13";
"IN-":   PN = "12"  !CDS_PN = "12";
"NC0":   PN = "6"  !CDS_PN = "6";
"NC1":   PN = "7"  !CDS_PN = "7";
"NC2":   PN = "8"  !CDS_PN = "8";
"NC3":   PN = "14"  !CDS_PN = "14";
"NC4":   PN = "15"  !CDS_PN = "15";
"NC5":   PN = "16"  !CDS_PN = "16";
"SCL":   PN = "5"  !CDS_PN = "5";
"SDA":   PN = "4"  !CDS_PN = "4";
"TH":   PN = "TH"  !CDS_PN = "TH";
"VS":   PN = "9"  !CDS_PN = "9";
BODY = "Q_RES","I31": LOCATION = "R3616" #&CDS_LOCATION = "R3616" &SEC = "1" #&CDS_SEC = "1";
"A":   PN = "1"  !CDS_PN = "1";
"B":   PN = "2"  !CDS_PN = "2";
BODY = "Q_CAP","I34": LOCATION = "C2015" #&CDS_LOCATION = "C2015" &SEC = "1" #&CDS_SEC = "1";
"A":   PN = "1"  !CDS_PN = "1";
"B":   PN = "2"  !CDS_PN = "2";
BODY = "Q_RES","I35": LOCATION = "R3563" #&CDS_LOCATION = "R3563" &SEC = "1" #&CDS_SEC = "1";
"A":   PN = "1"  !CDS_PN = "1";
"B":   PN = "2"  !CDS_PN = "2";
BODY = "Q_RES","I38": LOCATION = "R3600" #&CDS_LOCATION = "R3600" &SEC = "1" #&CDS_SEC = "1";
"A":   PN = "1"  !CDS_PN = "1";
"B":   PN = "2"  !CDS_PN = "2";
BODY = "Q_RES","I39": LOCATION = "R3601" #&CDS_LOCATION = "R3601" &SEC = "1" #&CDS_SEC = "1";
"A":   PN = "1"  !CDS_PN = "1";
"B":   PN = "2"  !CDS_PN = "2";
BODY = "Q_RES","I40": LOCATION = "R3617" #&CDS_LOCATION = "R3617" &SEC = "1" #&CDS_SEC = "1";
"A":   PN = "1"  !CDS_PN = "1";
"B":   PN = "2"  !CDS_PN = "2";
BODY = "Q_RES","I41": LOCATION = "R3602" #&CDS_LOCATION = "R3602" &SEC = "1" #&CDS_SEC = "1";
"A":   PN = "1"  !CDS_PN = "1";
"B":   PN = "2"  !CDS_PN = "2";
BODY = "Q_RES","I43": LOCATION = "R3603" #&CDS_LOCATION = "R3603" &SEC = "1" #&CDS_SEC = "1";
"A":   PN = "1"  !CDS_PN = "1";
"B":   PN = "2"  !CDS_PN = "2";
BODY = "Q_CAP","I50": LOCATION = "C2024" #&CDS_LOCATION = "C2024" &SEC = "1" #&CDS_SEC = "1";
"A":   PN = "1"  !CDS_PN = "1";
"B":   PN = "2"  !CDS_PN = "2";
BODY = "Q_CAP","I77": LOCATION = "C2027" #&CDS_LOCATION = "C2027" &SEC = "1" #&CDS_SEC = "1";
"A":   PN = "1"  !CDS_PN = "1";
"B":   PN = "2"  !CDS_PN = "2";
BODY = "Q_RES","I88": LOCATION = "R3628" #&CDS_LOCATION = "R3628" &SEC = "1" #&CDS_SEC = "1";
"A":   PN = "1"  !CDS_PN = "1";
"B":   PN = "2"  !CDS_PN = "2";
BODY = "Q_RES","I89": LOCATION = "R3627" #&CDS_LOCATION = "R3627" &SEC = "1" #&CDS_SEC = "1";
"A":   PN = "1"  !CDS_PN = "1";
"B":   PN = "2"  !CDS_PN = "2";
BODY = "Q_RES","I122": LOCATION = "R3752" #&CDS_LOCATION = "R3752" &SEC = "1" #&CDS_SEC = "1";
"A":   PN = "1"  !CDS_PN = "1";
"B":   PN = "2"  !CDS_PN = "2";
BODY = "Q_CAP","I125": LOCATION = "C2067" #&CDS_LOCATION = "C2067" &SEC = "1" #&CDS_SEC = "1";
"A":   PN = "1"  !CDS_PN = "1";
"B":   PN = "2"  !CDS_PN = "2";
BODY = "INA230AIRGTR","I129": LOCATION = "U276" #&CDS_LOCATION = "U276" &SEC = "1" #&CDS_SEC = "1";
"A0":   PN = "2"  !CDS_PN = "2";
"A1":   PN = "1"  !CDS_PN = "1";
"ALERT":   PN = "3"  !CDS_PN = "3";
"BUS":   PN = "11"  !CDS_PN = "11";
"GND":   PN = "10"  !CDS_PN = "10";
"IN+":   PN = "13"  !CDS_PN = "13";
"IN-":   PN = "12"  !CDS_PN = "12";
"NC0":   PN = "6"  !CDS_PN = "6";
"NC1":   PN = "7"  !CDS_PN = "7";
"NC2":   PN = "8"  !CDS_PN = "8";
"NC3":   PN = "14"  !CDS_PN = "14";
"NC4":   PN = "15"  !CDS_PN = "15";
"NC5":   PN = "16"  !CDS_PN = "16";
"SCL":   PN = "5"  !CDS_PN = "5";
"SDA":   PN = "4"  !CDS_PN = "4";
"TH":   PN = "TH"  !CDS_PN = "TH";
"VS":   PN = "9"  !CDS_PN = "9";
BODY = "Q_RES","I130": LOCATION = "R3754" #&CDS_LOCATION = "R3754" &SEC = "1" #&CDS_SEC = "1";
"A":   PN = "1"  !CDS_PN = "1";
"B":   PN = "2"  !CDS_PN = "2";
BODY = "Q_RES","I131": LOCATION = "R3756" #&CDS_LOCATION = "R3756" &SEC = "1" #&CDS_SEC = "1";
"A":   PN = "1"  !CDS_PN = "1";
"B":   PN = "2"  !CDS_PN = "2";
BODY = "Q_RES","I132": LOCATION = "R3758" #&CDS_LOCATION = "R3758" &SEC = "1" #&CDS_SEC = "1";
"A":   PN = "1"  !CDS_PN = "1";
"B":   PN = "2"  !CDS_PN = "2";
BODY = "Q_CAP","I133": LOCATION = "C2071" #&CDS_LOCATION = "C2071" &SEC = "1" #&CDS_SEC = "1";
"A":   PN = "1"  !CDS_PN = "1";
"B":   PN = "2"  !CDS_PN = "2";
BODY = "Q_RES","I134": LOCATION = "R3760" #&CDS_LOCATION = "R3760" &SEC = "1" #&CDS_SEC = "1";
"A":   PN = "1"  !CDS_PN = "1";
"B":   PN = "2"  !CDS_PN = "2";
BODY = "Q_RES","I135": LOCATION = "R3764" #&CDS_LOCATION = "R3764" &SEC = "1" #&CDS_SEC = "1";
"A":   PN = "1"  !CDS_PN = "1";
"B":   PN = "2"  !CDS_PN = "2";
BODY = "Q_RES","I136": LOCATION = "R3763" #&CDS_LOCATION = "R3763" &SEC = "1" #&CDS_SEC = "1";
"A":   PN = "1"  !CDS_PN = "1";
"B":   PN = "2"  !CDS_PN = "2";
BODY = "Q_CAP","I142": LOCATION = "C2069" #&CDS_LOCATION = "C2069" &SEC = "1" #&CDS_SEC = "1";
"A":   PN = "1"  !CDS_PN = "1";
"B":   PN = "2"  !CDS_PN = "2";
BODY = "Q_RES","I146": LOCATION = "R3751" #&CDS_LOCATION = "R3751" &SEC = "1" #&CDS_SEC = "1";
"A":   PN = "1"  !CDS_PN = "1";
"B":   PN = "2"  !CDS_PN = "2";
BODY = "Q_RES","I149": LOCATION = "R4093" #&CDS_LOCATION = "R4093" &SEC = "1" #&CDS_SEC = "1";
"A":   PN = "1"  !CDS_PN = "1";
"B":   PN = "2"  !CDS_PN = "2";
BODY = "Q_RES","I151": LOCATION = "R4094" #&CDS_LOCATION = "R4094" &SEC = "1" #&CDS_SEC = "1";
"A":   PN = "1"  !CDS_PN = "1";
"B":   PN = "2"  !CDS_PN = "2";
BODY = "Q_RES","I152": #LOCATION = "R3645" !CDS_LOCATION = "R3645" &SEC = "1" #&CDS_SEC = "1";
"A":   PN = "1"  !CDS_PN = "1";
"B":   PN = "2"  !CDS_PN = "2";
BODY = "Q_RES","I153": #LOCATION = "R3767" !CDS_LOCATION = "R3767" &SEC = "1" #&CDS_SEC = "1";
"A":   PN = "1"  !CDS_PN = "1";
"B":   PN = "2"  !CDS_PN = "2";
DRAWING = "@s9s_mb_2u_lib.s9s_mb_2u(sch_1):page161";
BODY = "Q_CAP","I16": LOCATION = "C2010" #&CDS_LOCATION = "C2010" &SEC = "1" #&CDS_SEC = "1";
"A":   PN = "1"  !CDS_PN = "1";
"B":   PN = "2"  !CDS_PN = "2";
BODY = "Q_RES","I77": LOCATION = "R4180" #&CDS_LOCATION = "R4180" &SEC = "1" #&CDS_SEC = "1";
"A":   PN = "1"  !CDS_PN = "1";
"B":   PN = "2"  !CDS_PN = "2";
BODY = "Q_RES","I78": LOCATION = "R4183" #&CDS_LOCATION = "R4183" &SEC = "1" #&CDS_SEC = "1";
"A":   PN = "1"  !CDS_PN = "1";
"B":   PN = "2"  !CDS_PN = "2";
BODY = "Q_RES","I79": LOCATION = "R4215" #&CDS_LOCATION = "R4215" &SEC = "1" #&CDS_SEC = "1";
"A":   PN = "1"  !CDS_PN = "1";
"B":   PN = "2"  !CDS_PN = "2";
BODY = "Q_RES","I81": LOCATION = "R4199" #&CDS_LOCATION = "R4199" &SEC = "1" #&CDS_SEC = "1";
"A":   PN = "1"  !CDS_PN = "1";
"B":   PN = "2"  !CDS_PN = "2";
BODY = "Q_RES","I82": LOCATION = "R4198" #&CDS_LOCATION = "R4198" &SEC = "1" #&CDS_SEC = "1";
"A":   PN = "1"  !CDS_PN = "1";
"B":   PN = "2"  !CDS_PN = "2";
BODY = "Q_RES","I85": LOCATION = "R4207" #&CDS_LOCATION = "R4207" &SEC = "1" #&CDS_SEC = "1";
"A":   PN = "1"  !CDS_PN = "1";
"B":   PN = "2"  !CDS_PN = "2";
BODY = "Q_RES","I86": LOCATION = "R4206" #&CDS_LOCATION = "R4206" &SEC = "1" #&CDS_SEC = "1";
"A":   PN = "1"  !CDS_PN = "1";
"B":   PN = "2"  !CDS_PN = "2";
BODY = "Q_RES","I89": LOCATION = "R4191" #&CDS_LOCATION = "R4191" &SEC = "1" #&CDS_SEC = "1";
"A":   PN = "1"  !CDS_PN = "1";
"B":   PN = "2"  !CDS_PN = "2";
BODY = "Q_RES","I91": LOCATION = "R4190" #&CDS_LOCATION = "R4190" &SEC = "1" #&CDS_SEC = "1";
"A":   PN = "1"  !CDS_PN = "1";
"B":   PN = "2"  !CDS_PN = "2";
BODY = "Q_RES","I94": LOCATION = "R4204" #&CDS_LOCATION = "R4204" &SEC = "1" #&CDS_SEC = "1";
"A":   PN = "1"  !CDS_PN = "1";
"B":   PN = "2"  !CDS_PN = "2";
BODY = "Q_RES","I95": LOCATION = "R4196" #&CDS_LOCATION = "R4196" &SEC = "1" #&CDS_SEC = "1";
"A":   PN = "1"  !CDS_PN = "1";
"B":   PN = "2"  !CDS_PN = "2";
BODY = "Q_RES","I96": LOCATION = "R4205" #&CDS_LOCATION = "R4205" &SEC = "1" #&CDS_SEC = "1";
"A":   PN = "1"  !CDS_PN = "1";
"B":   PN = "2"  !CDS_PN = "2";
BODY = "Q_RES","I98": LOCATION = "R4197" #&CDS_LOCATION = "R4197" &SEC = "1" #&CDS_SEC = "1";
"A":   PN = "1"  !CDS_PN = "1";
"B":   PN = "2"  !CDS_PN = "2";
BODY = "Q_RES","I101": LOCATION = "R4188" #&CDS_LOCATION = "R4188" &SEC = "1" #&CDS_SEC = "1";
"A":   PN = "1"  !CDS_PN = "1";
"B":   PN = "2"  !CDS_PN = "2";
BODY = "Q_RES","I102": LOCATION = "R4189" #&CDS_LOCATION = "R4189" &SEC = "1" #&CDS_SEC = "1";
"A":   PN = "1"  !CDS_PN = "1";
"B":   PN = "2"  !CDS_PN = "2";
BODY = "Q_CAP","I104": LOCATION = "C2276" #&CDS_LOCATION = "C2276" &SEC = "1" #&CDS_SEC = "1";
"A":   PN = "1"  !CDS_PN = "1";
"B":   PN = "2"  !CDS_PN = "2";
BODY = "Q_RES","I107": LOCATION = "R4182" #&CDS_LOCATION = "R4182" &SEC = "1" #&CDS_SEC = "1";
"A":   PN = "1"  !CDS_PN = "1";
"B":   PN = "2"  !CDS_PN = "2";
BODY = "Q_RES","I108": LOCATION = "R4214" #&CDS_LOCATION = "R4214" &SEC = "1" #&CDS_SEC = "1";
"A":   PN = "1"  !CDS_PN = "1";
"B":   PN = "2"  !CDS_PN = "2";
BODY = "Q_RES","I109": LOCATION = "R4179" #&CDS_LOCATION = "R4179" &SEC = "1" #&CDS_SEC = "1";
"A":   PN = "1"  !CDS_PN = "1";
"B":   PN = "2"  !CDS_PN = "2";
BODY = "Q_RES","I114": LOCATION = "R4178" #&CDS_LOCATION = "R4178" &SEC = "1" #&CDS_SEC = "1";
"A":   PN = "1"  !CDS_PN = "1";
"B":   PN = "2"  !CDS_PN = "2";
BODY = "Q_RES","I115": LOCATION = "R4213" #&CDS_LOCATION = "R4213" &SEC = "1" #&CDS_SEC = "1";
"A":   PN = "1"  !CDS_PN = "1";
"B":   PN = "2"  !CDS_PN = "2";
BODY = "Q_RES","I116": LOCATION = "R4181" #&CDS_LOCATION = "R4181" &SEC = "1" #&CDS_SEC = "1";
"A":   PN = "1"  !CDS_PN = "1";
"B":   PN = "2"  !CDS_PN = "2";
BODY = "Q_CAP","I119": LOCATION = "C2275" #&CDS_LOCATION = "C2275" &SEC = "1" #&CDS_SEC = "1";
"A":   PN = "1"  !CDS_PN = "1";
"B":   PN = "2"  !CDS_PN = "2";
BODY = "Q_RES","I121": LOCATION = "R4187" #&CDS_LOCATION = "R4187" &SEC = "1" #&CDS_SEC = "1";
"A":   PN = "1"  !CDS_PN = "1";
"B":   PN = "2"  !CDS_PN = "2";
BODY = "Q_RES","I122": LOCATION = "R4186" #&CDS_LOCATION = "R4186" &SEC = "1" #&CDS_SEC = "1";
"A":   PN = "1"  !CDS_PN = "1";
"B":   PN = "2"  !CDS_PN = "2";
BODY = "Q_RES","I125": LOCATION = "R4195" #&CDS_LOCATION = "R4195" &SEC = "1" #&CDS_SEC = "1";
"A":   PN = "1"  !CDS_PN = "1";
"B":   PN = "2"  !CDS_PN = "2";
BODY = "Q_RES","I127": LOCATION = "R4203" #&CDS_LOCATION = "R4203" &SEC = "1" #&CDS_SEC = "1";
"A":   PN = "1"  !CDS_PN = "1";
"B":   PN = "2"  !CDS_PN = "2";
BODY = "Q_RES","I128": LOCATION = "R4194" #&CDS_LOCATION = "R4194" &SEC = "1" #&CDS_SEC = "1";
"A":   PN = "1"  !CDS_PN = "1";
"B":   PN = "2"  !CDS_PN = "2";
BODY = "Q_RES","I129": LOCATION = "R4202" #&CDS_LOCATION = "R4202" &SEC = "1" #&CDS_SEC = "1";
"A":   PN = "1"  !CDS_PN = "1";
"B":   PN = "2"  !CDS_PN = "2";
BODY = "Q_RES","I134": LOCATION = "R3553" #&CDS_LOCATION = "R3553" &SEC = "1" #&CDS_SEC = "1";
"A":   PN = "1"  !CDS_PN = "1";
"B":   PN = "2"  !CDS_PN = "2";
BODY = "Q_RES","I135": LOCATION = "R4212" #&CDS_LOCATION = "R4212" &SEC = "1" #&CDS_SEC = "1";
"A":   PN = "1"  !CDS_PN = "1";
"B":   PN = "2"  !CDS_PN = "2";
BODY = "Q_RES","I136": LOCATION = "R3554" #&CDS_LOCATION = "R3554" &SEC = "1" #&CDS_SEC = "1";
"A":   PN = "1"  !CDS_PN = "1";
"B":   PN = "2"  !CDS_PN = "2";
BODY = "Q_CAP","I139": LOCATION = "C2274" #&CDS_LOCATION = "C2274" &SEC = "1" #&CDS_SEC = "1";
"A":   PN = "1"  !CDS_PN = "1";
"B":   PN = "2"  !CDS_PN = "2";
BODY = "Q_RES","I141": LOCATION = "R4185" #&CDS_LOCATION = "R4185" &SEC = "1" #&CDS_SEC = "1";
"A":   PN = "1"  !CDS_PN = "1";
"B":   PN = "2"  !CDS_PN = "2";
BODY = "Q_RES","I142": LOCATION = "R4184" #&CDS_LOCATION = "R4184" &SEC = "1" #&CDS_SEC = "1";
"A":   PN = "1"  !CDS_PN = "1";
"B":   PN = "2"  !CDS_PN = "2";
BODY = "Q_RES","I145": LOCATION = "R4193" #&CDS_LOCATION = "R4193" &SEC = "1" #&CDS_SEC = "1";
"A":   PN = "1"  !CDS_PN = "1";
"B":   PN = "2"  !CDS_PN = "2";
BODY = "Q_RES","I147": LOCATION = "R4201" #&CDS_LOCATION = "R4201" &SEC = "1" #&CDS_SEC = "1";
"A":   PN = "1"  !CDS_PN = "1";
"B":   PN = "2"  !CDS_PN = "2";
BODY = "Q_RES","I148": LOCATION = "R4192" #&CDS_LOCATION = "R4192" &SEC = "1" #&CDS_SEC = "1";
"A":   PN = "1"  !CDS_PN = "1";
"B":   PN = "2"  !CDS_PN = "2";
BODY = "Q_RES","I149": LOCATION = "R4200" #&CDS_LOCATION = "R4200" &SEC = "1" #&CDS_SEC = "1";
"A":   PN = "1"  !CDS_PN = "1";
"B":   PN = "2"  !CDS_PN = "2";
BODY = "LM75BD","I164": #LOCATION = "U270" !CDS_LOCATION = "U270" &SEC = "1" #&CDS_SEC = "1";
"A0":   PN = "7"  !CDS_PN = "7";
"A1":   PN = "6"  !CDS_PN = "6";
"A2":   PN = "5"  !CDS_PN = "5";
"GND":   PN = "4"  !CDS_PN = "4";
"OS":   PN = "3"  !CDS_PN = "3";
"SCL":   PN = "2"  !CDS_PN = "2";
"SDA":   PN = "1"  !CDS_PN = "1";
"VCC":   PN = "8"  !CDS_PN = "8";
BODY = "LM75BD","I165": #LOCATION = "U271" !CDS_LOCATION = "U271" &SEC = "1" #&CDS_SEC = "1";
"A0":   PN = "7"  !CDS_PN = "7";
"A1":   PN = "6"  !CDS_PN = "6";
"A2":   PN = "5"  !CDS_PN = "5";
"GND":   PN = "4"  !CDS_PN = "4";
"OS":   PN = "3"  !CDS_PN = "3";
"SCL":   PN = "2"  !CDS_PN = "2";
"SDA":   PN = "1"  !CDS_PN = "1";
"VCC":   PN = "8"  !CDS_PN = "8";
BODY = "LM75BD","I166": #LOCATION = "U272" !CDS_LOCATION = "U272" &SEC = "1" #&CDS_SEC = "1";
"A0":   PN = "7"  !CDS_PN = "7";
"A1":   PN = "6"  !CDS_PN = "6";
"A2":   PN = "5"  !CDS_PN = "5";
"GND":   PN = "4"  !CDS_PN = "4";
"OS":   PN = "3"  !CDS_PN = "3";
"SCL":   PN = "2"  !CDS_PN = "2";
"SDA":   PN = "1"  !CDS_PN = "1";
"VCC":   PN = "8"  !CDS_PN = "8";
BODY = "LM75BD","I167": #LOCATION = "U273" !CDS_LOCATION = "U273" &SEC = "1" #&CDS_SEC = "1";
"A0":   PN = "7"  !CDS_PN = "7";
"A1":   PN = "6"  !CDS_PN = "6";
"A2":   PN = "5"  !CDS_PN = "5";
"GND":   PN = "4"  !CDS_PN = "4";
"OS":   PN = "3"  !CDS_PN = "3";
"SCL":   PN = "2"  !CDS_PN = "2";
"SDA":   PN = "1"  !CDS_PN = "1";
"VCC":   PN = "8"  !CDS_PN = "8";
BODY = "Q_RES","I168": #LOCATION = "R4211" !CDS_LOCATION = "R4211" &SEC = "1" #&CDS_SEC = "1";
"A":   PN = "1"  !CDS_PN = "1";
"B":   PN = "2"  !CDS_PN = "2";
BODY = "Q_RES","I169": #LOCATION = "R4209" !CDS_LOCATION = "R4209" &SEC = "1" #&CDS_SEC = "1";
"A":   PN = "1"  !CDS_PN = "1";
"B":   PN = "2"  !CDS_PN = "2";
BODY = "Q_RES","I170": #LOCATION = "R4210" !CDS_LOCATION = "R4210" &SEC = "1" #&CDS_SEC = "1";
"A":   PN = "1"  !CDS_PN = "1";
"B":   PN = "2"  !CDS_PN = "2";
BODY = "Q_RES","I171": #LOCATION = "R4208" !CDS_LOCATION = "R4208" &SEC = "1" #&CDS_SEC = "1";
"A":   PN = "1"  !CDS_PN = "1";
"B":   PN = "2"  !CDS_PN = "2";
DRAWING = "@s9s_mb_2u_lib.s9s_mb_2u(sch_1):page221";
BODY = "Q_RES","I2": LOCATION = "R3704" #&CDS_LOCATION = "R3704" &SEC = "1" #&CDS_SEC = "1";
"A":   PN = "1"  !CDS_PN = "1";
"B":   PN = "2"  !CDS_PN = "2";
BODY = "Q_RES","I3": LOCATION = "R3703" #&CDS_LOCATION = "R3703" &SEC = "1" #&CDS_SEC = "1";
"A":   PN = "1"  !CDS_PN = "1";
"B":   PN = "2"  !CDS_PN = "2";
BODY = "Q_RES","I6": LOCATION = "R3707" #&CDS_LOCATION = "R3707" &SEC = "1" #&CDS_SEC = "1";
"A":   PN = "1"  !CDS_PN = "1";
"B":   PN = "2"  !CDS_PN = "2";
BODY = "Q_RES","I8": LOCATION = "R3709" #&CDS_LOCATION = "R3709" &SEC = "1" #&CDS_SEC = "1";
"A":   PN = "1"  !CDS_PN = "1";
"B":   PN = "2"  !CDS_PN = "2";
BODY = "Q_RES","I9": LOCATION = "R3706" #&CDS_LOCATION = "R3706" &SEC = "1" #&CDS_SEC = "1";
"A":   PN = "1"  !CDS_PN = "1";
"B":   PN = "2"  !CDS_PN = "2";
BODY = "Q_RES","I10": LOCATION = "R3708" #&CDS_LOCATION = "R3708" &SEC = "1" #&CDS_SEC = "1";
"A":   PN = "1"  !CDS_PN = "1";
"B":   PN = "2"  !CDS_PN = "2";
BODY = "Q_RES","I34": LOCATION = "R3732" #&CDS_LOCATION = "R3732" &SEC = "1" #&CDS_SEC = "1";
"A":   PN = "1"  !CDS_PN = "1";
"B":   PN = "2"  !CDS_PN = "2";
BODY = "Q_RES","I48": LOCATION = "R3729" #&CDS_LOCATION = "R3729" &SEC = "1" #&CDS_SEC = "1";
"A":   PN = "1"  !CDS_PN = "1";
"B":   PN = "2"  !CDS_PN = "2";
BODY = "Q_RES","I49": LOCATION = "R3730" #&CDS_LOCATION = "R3730" &SEC = "1" #&CDS_SEC = "1";
"A":   PN = "1"  !CDS_PN = "1";
"B":   PN = "2"  !CDS_PN = "2";
BODY = "Q_RES","I50": LOCATION = "R3728" #&CDS_LOCATION = "R3728" &SEC = "1" #&CDS_SEC = "1";
"A":   PN = "1"  !CDS_PN = "1";
"B":   PN = "2"  !CDS_PN = "2";
BODY = "Q_RES","I51": LOCATION = "R3727" #&CDS_LOCATION = "R3727" &SEC = "1" #&CDS_SEC = "1";
"A":   PN = "1"  !CDS_PN = "1";
"B":   PN = "2"  !CDS_PN = "2";
BODY = "Q_RES","I52": LOCATION = "R3726" #&CDS_LOCATION = "R3726" &SEC = "1" #&CDS_SEC = "1";
"A":   PN = "1"  !CDS_PN = "1";
"B":   PN = "2"  !CDS_PN = "2";
BODY = "Q_RES","I53": LOCATION = "R3725" #&CDS_LOCATION = "R3725" &SEC = "1" #&CDS_SEC = "1";
"A":   PN = "1"  !CDS_PN = "1";
"B":   PN = "2"  !CDS_PN = "2";
BODY = "Q_RES","I55": LOCATION = "R3723" #&CDS_LOCATION = "R3723" &SEC = "1" #&CDS_SEC = "1";
"A":   PN = "1"  !CDS_PN = "1";
"B":   PN = "2"  !CDS_PN = "2";
BODY = "Q_RES","I56": LOCATION = "R3724" #&CDS_LOCATION = "R3724" &SEC = "1" #&CDS_SEC = "1";
"A":   PN = "1"  !CDS_PN = "1";
"B":   PN = "2"  !CDS_PN = "2";
BODY = "Q_RES","I98": LOCATION = "R3731" #&CDS_LOCATION = "R3731" &SEC = "1" #&CDS_SEC = "1";
"A":   PN = "1"  !CDS_PN = "1";
"B":   PN = "2"  !CDS_PN = "2";
BODY = "Q_RES","I99": LOCATION = "R4270" #&CDS_LOCATION = "R4270" &SEC = "1" #&CDS_SEC = "1";
"A":   PN = "1"  !CDS_PN = "1";
"B":   PN = "2"  !CDS_PN = "2";
BODY = "Q_RES","I102": LOCATION = "R4269" #&CDS_LOCATION = "R4269" &SEC = "1" #&CDS_SEC = "1";
"A":   PN = "1"  !CDS_PN = "1";
"B":   PN = "2"  !CDS_PN = "2";
BODY = "TCA9548APWR","I103": #LOCATION = "U39" !CDS_LOCATION = "U39" #SEC = "1" !CDS_SEC = "1";
"A0":   PN = "1"  !CDS_PN = "1";
"A1":   PN = "2"  !CDS_PN = "2";
"A2":   PN = "21"  !CDS_PN = "21";
"GND":   PN = "12"  !CDS_PN = "12";
"RESET#":   PN = "3"  !CDS_PN = "3";
"SC0":   PN = "5"  !CDS_PN = "5";
"SC1":   PN = "7"  !CDS_PN = "7";
"SC2":   PN = "9"  !CDS_PN = "9";
"SC3":   PN = "11"  !CDS_PN = "11";
"SC4":   PN = "14"  !CDS_PN = "14";
"SC5":   PN = "16"  !CDS_PN = "16";
"SC6":   PN = "18"  !CDS_PN = "18";
"SC7":   PN = "20"  !CDS_PN = "20";
"SCL":   PN = "22"  !CDS_PN = "22";
"SD0":   PN = "4"  !CDS_PN = "4";
"SD1":   PN = "6"  !CDS_PN = "6";
"SD2":   PN = "8"  !CDS_PN = "8";
"SD3":   PN = "10"  !CDS_PN = "10";
"SD4":   PN = "13"  !CDS_PN = "13";
"SD5":   PN = "15"  !CDS_PN = "15";
"SD6":   PN = "17"  !CDS_PN = "17";
"SD7":   PN = "19"  !CDS_PN = "19";
"SDA":   PN = "23"  !CDS_PN = "23";
"VCC":   PN = "24"  !CDS_PN = "24";
BODY = "Q_CAP","I106": LOCATION = "C2056" #&CDS_LOCATION = "C2056" &SEC = "1" #&CDS_SEC = "1";
"A":   PN = "1"  !CDS_PN = "1";
"B":   PN = "2"  !CDS_PN = "2";
BODY = "Q_RES","I115": LOCATION = "R3712" #&CDS_LOCATION = "R3712" &SEC = "1" #&CDS_SEC = "1";
"A":   PN = "1"  !CDS_PN = "1";
"B":   PN = "2"  !CDS_PN = "2";
BODY = "Q_RES","I116": LOCATION = "R3711" #&CDS_LOCATION = "R3711" &SEC = "1" #&CDS_SEC = "1";
"A":   PN = "1"  !CDS_PN = "1";
"B":   PN = "2"  !CDS_PN = "2";
BODY = "Q_RES","I119": LOCATION = "R3722" #&CDS_LOCATION = "R3722" &SEC = "1" #&CDS_SEC = "1";
"A":   PN = "1"  !CDS_PN = "1";
"B":   PN = "2"  !CDS_PN = "2";
BODY = "Q_RES","I120": LOCATION = "R3721" #&CDS_LOCATION = "R3721" &SEC = "1" #&CDS_SEC = "1";
"A":   PN = "1"  !CDS_PN = "1";
"B":   PN = "2"  !CDS_PN = "2";
BODY = "Q_RES","I137": LOCATION = "R3713" #&CDS_LOCATION = "R3713" &SEC = "1" #&CDS_SEC = "1";
"A":   PN = "1"  !CDS_PN = "1";
"B":   PN = "2"  !CDS_PN = "2";
BODY = "Q_RES","I138": LOCATION = "R3714" #&CDS_LOCATION = "R3714" &SEC = "1" #&CDS_SEC = "1";
"A":   PN = "1"  !CDS_PN = "1";
"B":   PN = "2"  !CDS_PN = "2";
BODY = "Q_RES","I139": LOCATION = "R3715" #&CDS_LOCATION = "R3715" &SEC = "1" #&CDS_SEC = "1";
"A":   PN = "1"  !CDS_PN = "1";
"B":   PN = "2"  !CDS_PN = "2";
BODY = "Q_RES","I140": LOCATION = "R3716" #&CDS_LOCATION = "R3716" &SEC = "1" #&CDS_SEC = "1";
"A":   PN = "1"  !CDS_PN = "1";
"B":   PN = "2"  !CDS_PN = "2";
BODY = "Q_RES","I141": LOCATION = "R3717" #&CDS_LOCATION = "R3717" &SEC = "1" #&CDS_SEC = "1";
"A":   PN = "1"  !CDS_PN = "1";
"B":   PN = "2"  !CDS_PN = "2";
BODY = "Q_RES","I142": LOCATION = "R3718" #&CDS_LOCATION = "R3718" &SEC = "1" #&CDS_SEC = "1";
"A":   PN = "1"  !CDS_PN = "1";
"B":   PN = "2"  !CDS_PN = "2";
BODY = "Q_RES","I143": LOCATION = "R3719" #&CDS_LOCATION = "R3719" &SEC = "1" #&CDS_SEC = "1";
"A":   PN = "1"  !CDS_PN = "1";
"B":   PN = "2"  !CDS_PN = "2";
BODY = "Q_RES","I144": LOCATION = "R3720" #&CDS_LOCATION = "R3720" &SEC = "1" #&CDS_SEC = "1";
"A":   PN = "1"  !CDS_PN = "1";
"B":   PN = "2"  !CDS_PN = "2";
BODY = "Q_RES","I145": LOCATION = "R3710" #&CDS_LOCATION = "R3710" &SEC = "1" #&CDS_SEC = "1";
"A":   PN = "1"  !CDS_PN = "1";
"B":   PN = "2"  !CDS_PN = "2";
BODY = "Q_RES","I147": LOCATION = "R3705" #&CDS_LOCATION = "R3705" &SEC = "1" #&CDS_SEC = "1";
"A":   PN = "1"  !CDS_PN = "1";
"B":   PN = "2"  !CDS_PN = "2";
DRAWING = "@s9s_mb_2u_lib.s9s_mb_2u(sch_1):page297";
BODY = "Q_RES","I157": LOCATION = "R2350" #&CDS_LOCATION = "R2350" &SEC = "1" #&CDS_SEC = "1";
"A":   PN = "1"  !CDS_PN = "1";
"B":   PN = "2"  !CDS_PN = "2";
BODY = "Q_RES","I159": LOCATION = "R2304" #&CDS_LOCATION = "R2304" &SEC = "1" #&CDS_SEC = "1";
"A":   PN = "1"  !CDS_PN = "1";
"B":   PN = "2"  !CDS_PN = "2";
BODY = "74LVC1G126SE7","I163": LOCATION = "U145" #&CDS_LOCATION = "U145" #SEC = "1" !CDS_SEC = "1";
"A":   PN = "2"  !CDS_PN = "2";
"GND":   PN = "3"  !CDS_PN = "3";
"OE":   PN = "1"  !CDS_PN = "1";
"VCC":   PN = "5"  !CDS_PN = "5";
"Y":   PN = "4"  !CDS_PN = "4";
BODY = "Q_RES","I165": LOCATION = "R2457" #&CDS_LOCATION = "R2457" &SEC = "1" #&CDS_SEC = "1";
"A":   PN = "1"  !CDS_PN = "1";
"B":   PN = "2"  !CDS_PN = "2";
BODY = "Q_RES","I169": LOCATION = "R2282" #&CDS_LOCATION = "R2282" &SEC = "1" #&CDS_SEC = "1";
"A":   PN = "1"  !CDS_PN = "1";
"B":   PN = "2"  !CDS_PN = "2";
BODY = "Q_CAP","I170": LOCATION = "C1614" #&CDS_LOCATION = "C1614" &SEC = "1" #&CDS_SEC = "1";
"A":   PN = "1"  !CDS_PN = "1";
"B":   PN = "2"  !CDS_PN = "2";
BODY = "Q_CAP","I237": LOCATION = "C1277" #&CDS_LOCATION = "C1277" &SEC = "1" #&CDS_SEC = "1";
"A":   PN = "1"  !CDS_PN = "1";
"B":   PN = "2"  !CDS_PN = "2";
BODY = "Q_CAP","I245": LOCATION = "C1283" #&CDS_LOCATION = "C1283" &SEC = "1" #&CDS_SEC = "1";
"A":   PN = "1"  !CDS_PN = "1";
"B":   PN = "2"  !CDS_PN = "2";
BODY = "Q_CAP","I247": LOCATION = "C1282" #&CDS_LOCATION = "C1282" &SEC = "1" #&CDS_SEC = "1";
"A":   PN = "1"  !CDS_PN = "1";
"B":   PN = "2"  !CDS_PN = "2";
BODY = "Q_CAP","I252": LOCATION = "C1279" #&CDS_LOCATION = "C1279" &SEC = "1" #&CDS_SEC = "1";
"A":   PN = "1"  !CDS_PN = "1";
"B":   PN = "2"  !CDS_PN = "2";
BODY = "Q_CAP","I258": LOCATION = "C1278" #&CDS_LOCATION = "C1278" &SEC = "1" #&CDS_SEC = "1";
"A":   PN = "1"  !CDS_PN = "1";
"B":   PN = "2"  !CDS_PN = "2";
BODY = "Q_CAP","I260": LOCATION = "C1276" #&CDS_LOCATION = "C1276" &SEC = "1" #&CDS_SEC = "1";
"A":   PN = "1"  !CDS_PN = "1";
"B":   PN = "2"  !CDS_PN = "2";
BODY = "Q_RES","I264": #LOCATION = "R2317" !CDS_LOCATION = "R2317" &SEC = "1" #&CDS_SEC = "1";
"A":   PN = "1"  !CDS_PN = "1";
"B":   PN = "2"  !CDS_PN = "2";
BODY = "Q_RES","I291": LOCATION = "R3771" #&CDS_LOCATION = "R3771" &SEC = "1" #&CDS_SEC = "1";
"A":   PN = "1"  !CDS_PN = "1";
"B":   PN = "2"  !CDS_PN = "2";
BODY = "Q_RES","I293": #LOCATION = "R2296" !CDS_LOCATION = "R2296" &SEC = "1" #&CDS_SEC = "1";
"A":   PN = "1"  !CDS_PN = "1";
"B":   PN = "2"  !CDS_PN = "2";
BODY = "Q_RES","I296": LOCATION = "R2125" #&CDS_LOCATION = "R2125" &SEC = "1" #&CDS_SEC = "1";
"A":   PN = "1"  !CDS_PN = "1";
"B":   PN = "2"  !CDS_PN = "2";
BODY = "Q_RES","I299": LOCATION = "R3773" #&CDS_LOCATION = "R3773" &SEC = "1" #&CDS_SEC = "1";
"A":   PN = "1"  !CDS_PN = "1";
"B":   PN = "2"  !CDS_PN = "2";
BODY = "Q_RES","I301": LOCATION = "R3772" #&CDS_LOCATION = "R3772" &SEC = "1" #&CDS_SEC = "1";
"A":   PN = "1"  !CDS_PN = "1";
"B":   PN = "2"  !CDS_PN = "2";
BODY = "Q_RES","I302": LOCATION = "R2114" #&CDS_LOCATION = "R2114" &SEC = "1" #&CDS_SEC = "1";
"A":   PN = "1"  !CDS_PN = "1";
"B":   PN = "2"  !CDS_PN = "2";
BODY = "Q_CAP","I304": LOCATION = "C1592" #&CDS_LOCATION = "C1592" &SEC = "1" #&CDS_SEC = "1";
"A":   PN = "1"  !CDS_PN = "1";
"B":   PN = "2"  !CDS_PN = "2";
BODY = "74LVC2G07DW7","I305": #LOCATION = "U134" !CDS_LOCATION = "U134" &SEC = "1" #&CDS_SEC = "1";
"1A":   PN = "1"  !CDS_PN = "1";
"1Y":   PN = "6"  !CDS_PN = "6";
"2A":   PN = "3"  !CDS_PN = "3";
"2Y":   PN = "4"  !CDS_PN = "4";
"GND":   PN = "2"  !CDS_PN = "2";
"VCC":   PN = "5"  !CDS_PN = "5";
BODY = "Q_RES","I307": LOCATION = "R3775" #&CDS_LOCATION = "R3775" &SEC = "1" #&CDS_SEC = "1";
"A":   PN = "1"  !CDS_PN = "1";
"B":   PN = "2"  !CDS_PN = "2";
BODY = "Q_RES","I309": LOCATION = "R3779" #&CDS_LOCATION = "R3779" &SEC = "1" #&CDS_SEC = "1";
"A":   PN = "1"  !CDS_PN = "1";
"B":   PN = "2"  !CDS_PN = "2";
BODY = "Q_RES","I311": #LOCATION = "R2426" !CDS_LOCATION = "R2426" &SEC = "1" #&CDS_SEC = "1";
"A":   PN = "1"  !CDS_PN = "1";
"B":   PN = "2"  !CDS_PN = "2";
BODY = "Q_RES","I312": #LOCATION = "R1673" !CDS_LOCATION = "R1673" &SEC = "1" #&CDS_SEC = "1";
"A":   PN = "1"  !CDS_PN = "1";
"B":   PN = "2"  !CDS_PN = "2";
BODY = "Q_RES","I313": #LOCATION = "R2287" !CDS_LOCATION = "R2287" &SEC = "1" #&CDS_SEC = "1";
"A":   PN = "1"  !CDS_PN = "1";
"B":   PN = "2"  !CDS_PN = "2";
BODY = "MOSFET_NCH_GDS_ESD_PROTECTED","I316": #LOCATION = "Q46" !CDS_LOCATION = "Q46" &SEC = "1" #&CDS_SEC = "1";
"D":   PN = "D"  !CDS_PN = "D";
"G":   PN = "G"  !CDS_PN = "G";
"S":   PN = "S"  !CDS_PN = "S";
BODY = "SCONN56_123276793","I318": #LOCATION = "J90" !CDS_LOCATION = "J90" &SEC = "1" #&CDS_SEC = "1";
"DUALPORTEN#":   PN = "B9"  !CDS_PN = "B9";
"G1":   PN = "G1"  !CDS_PN = "G1";
"G2":   PN = "G2"  !CDS_PN = "G2";
"GND_A1":   PN = "A1"  !CDS_PN = "A1";
"GND_A2":   PN = "A2"  !CDS_PN = "A2";
"GND_A3":   PN = "A3"  !CDS_PN = "A3";
"GND_A4":   PN = "A4"  !CDS_PN = "A4";
"GND_A5":   PN = "A5"  !CDS_PN = "A5";
"GND_A6":   PN = "A6"  !CDS_PN = "A6";
"GND_A13":   PN = "A13"  !CDS_PN = "A13";
"GND_A16":   PN = "A16"  !CDS_PN = "A16";
"GND_A19":   PN = "A19"  !CDS_PN = "A19";
"GND_A22":   PN = "A22"  !CDS_PN = "A22";
"GND_A25":   PN = "A25"  !CDS_PN = "A25";
"GND_A28":   PN = "A28"  !CDS_PN = "A28";
"GND_B13":   PN = "B13"  !CDS_PN = "B13";
"GND_B16":   PN = "B16"  !CDS_PN = "B16";
"GND_B19":   PN = "B19"  !CDS_PN = "B19";
"GND_B22":   PN = "B22"  !CDS_PN = "B22";
"GND_B25":   PN = "B25"  !CDS_PN = "B25";
"GND_B28":   PN = "B28"  !CDS_PN = "B28";
"LED#_ACTIVITY":   PN = "A10"  !CDS_PN = "A10";
"MFG":   PN = "B7"  !CDS_PN = "B7";
"P3V3_AUX":   PN = "B11"  !CDS_PN = "B11";
"P12V_B1":   PN = "B1"  !CDS_PN = "B1";
"P12V_B2":   PN = "B2"  !CDS_PN = "B2";
"P12V_B3":   PN = "B3"  !CDS_PN = "B3";
"P12V_B4":   PN = "B4"  !CDS_PN = "B4";
"P12V_B5":   PN = "B5"  !CDS_PN = "B5";
"P12V_B6":   PN = "B6"  !CDS_PN = "B6";
"PER_N0":   PN = "A17"  !CDS_PN = "A17";
"PER_N1":   PN = "A20"  !CDS_PN = "A20";
"PER_N2":   PN = "A23"  !CDS_PN = "A23";
"PER_N3":   PN = "A26"  !CDS_PN = "A26";
"PER_P0":   PN = "A18"  !CDS_PN = "A18";
"PER_P1":   PN = "A21"  !CDS_PN = "A21";
"PER_P2":   PN = "A24"  !CDS_PN = "A24";
"PER_P3":   PN = "A27"  !CDS_PN = "A27";
"PERST0#":   PN = "B10"  !CDS_PN = "B10";
"PERST1#_CLKREQ#":   PN = "A11"  !CDS_PN = "A11";
"PET_N0":   PN = "B17"  !CDS_PN = "B17";
"PET_N1":   PN = "B20"  !CDS_PN = "B20";
"PET_N2":   PN = "B23"  !CDS_PN = "B23";
"PET_N3":   PN = "B26"  !CDS_PN = "B26";
"PET_P0":   PN = "B18"  !CDS_PN = "B18";
"PET_P1":   PN = "B21"  !CDS_PN = "B21";
"PET_P2":   PN = "B24"  !CDS_PN = "B24";
"PET_P3":   PN = "B27"  !CDS_PN = "B27";
"PRSNT0#":   PN = "A12"  !CDS_PN = "A12";
"PWRDIS":   PN = "B12"  !CDS_PN = "B12";
"REFCLK_N0":   PN = "B14"  !CDS_PN = "B14";
"REFCLK_N1":   PN = "A14"  !CDS_PN = "A14";
"REFCLK_P0":   PN = "B15"  !CDS_PN = "B15";
"REFCLK_P1":   PN = "A15"  !CDS_PN = "A15";
"RFU":   PN = "B8"  !CDS_PN = "B8";
"SMBCLK":   PN = "A7"  !CDS_PN = "A7";
"SMBDAT":   PN = "A8"  !CDS_PN = "A8";
"SMBRST#":   PN = "A9"  !CDS_PN = "A9";
BODY = "Q_CAP","I327": LOCATION = "C2378" #&CDS_LOCATION = "C2378" &SEC = "1" #&CDS_SEC = "1";
"A":   PN = "1"  !CDS_PN = "1";
"B":   PN = "2"  !CDS_PN = "2";
BODY = "APX80929SAG7","I329": LOCATION = "U336" #&CDS_LOCATION = "U336" &SEC = "1" #&CDS_SEC = "1";
"GND":   PN = "1"  !CDS_PN = "1";
"RESET_L":   PN = "2"  !CDS_PN = "2";
"VCC":   PN = "3"  !CDS_PN = "3";
BODY = "Q_RES","I331": LOCATION = "R4767" #&CDS_LOCATION = "R4767" &SEC = "1" #&CDS_SEC = "1";
"A":   PN = "1"  !CDS_PN = "1";
"B":   PN = "2"  !CDS_PN = "2";
DRAWING = "@s9s_mb_2u_lib.s9s_mb_2u(sch_1):page213";
BODY = "74LVC2G17GW","I2": LOCATION = "U150" #&CDS_LOCATION = "U150" &SEC = "1" #&CDS_SEC = "1";
"A0":   PN = "1"  !CDS_PN = "1";
"A1":   PN = "3"  !CDS_PN = "3";
"B0":   PN = "6"  !CDS_PN = "6";
"B1":   PN = "4"  !CDS_PN = "4";
"GND":   PN = "2"  !CDS_PN = "2";
"VCC":   PN = "5"  !CDS_PN = "5";
BODY = "Q_CAP","I5": LOCATION = "C1619" #&CDS_LOCATION = "C1619" &SEC = "1" #&CDS_SEC = "1";
"A":   PN = "1"  !CDS_PN = "1";
"B":   PN = "2"  !CDS_PN = "2";
BODY = "Q_RES","I7": LOCATION = "R2355" #&CDS_LOCATION = "R2355" &SEC = "1" #&CDS_SEC = "1";
"A":   PN = "1"  !CDS_PN = "1";
"B":   PN = "2"  !CDS_PN = "2";
BODY = "Q_RES","I18": LOCATION = "R4604" #&CDS_LOCATION = "R4604" &SEC = "1" #&CDS_SEC = "1";
"A":   PN = "1"  !CDS_PN = "1";
"B":   PN = "2"  !CDS_PN = "2";
BODY = "MOSFET_NCH_DUAL","I21": LOCATION = "Q144" #&CDS_LOCATION = "Q144" &SEC = "2" #&CDS_SEC = "2";
"D2":   PN = "3"  !CDS_PN = "3";
"G2":   PN = "5"  !CDS_PN = "5";
"S2":   PN = "4"  !CDS_PN = "4";
BODY = "Q_RES","I22": LOCATION = "R4605" #&CDS_LOCATION = "R4605" &SEC = "1" #&CDS_SEC = "1";
"A":   PN = "1"  !CDS_PN = "1";
"B":   PN = "2"  !CDS_PN = "2";
BODY = "MOSFET_NCH_DUAL","I27": #LOCATION = "Q144" !CDS_LOCATION = "Q144" &SEC = "1" #&CDS_SEC = "1";
"D1":   PN = "6"  !CDS_PN = "6";
"G1":   PN = "2"  !CDS_PN = "2";
"S1":   PN = "1"  !CDS_PN = "1";
BODY = "Q_RES","I29": LOCATION = "R1446" #&CDS_LOCATION = "R1446" &SEC = "1" #&CDS_SEC = "1";
"A":   PN = "1"  !CDS_PN = "1";
"B":   PN = "2"  !CDS_PN = "2";
BODY = "Q_RES","I32": LOCATION = "R4719" #&CDS_LOCATION = "R4719" &SEC = "1" #&CDS_SEC = "1";
"A":   PN = "1"  !CDS_PN = "1";
"B":   PN = "2"  !CDS_PN = "2";
BODY = "Q_RES","I33": LOCATION = "R4718" #&CDS_LOCATION = "R4718" &SEC = "1" #&CDS_SEC = "1";
"A":   PN = "1"  !CDS_PN = "1";
"B":   PN = "2"  !CDS_PN = "2";
BODY = "Q_CAP","I35": LOCATION = "C2370" #&CDS_LOCATION = "C2370" &SEC = "1" #&CDS_SEC = "1";
"A":   PN = "1"  !CDS_PN = "1";
"B":   PN = "2"  !CDS_PN = "2";
BODY = "74LVC2G07DW7","I37": LOCATION = "U332" #&CDS_LOCATION = "U332" &SEC = "1" #&CDS_SEC = "1";
"1A":   PN = "1"  !CDS_PN = "1";
"1Y":   PN = "6"  !CDS_PN = "6";
"2A":   PN = "3"  !CDS_PN = "3";
"2Y":   PN = "4"  !CDS_PN = "4";
"GND":   PN = "2"  !CDS_PN = "2";
"VCC":   PN = "5"  !CDS_PN = "5";
BODY = "Q_RES","I40": LOCATION = "R4716" #&CDS_LOCATION = "R4716" &SEC = "1" #&CDS_SEC = "1";
"A":   PN = "1"  !CDS_PN = "1";
"B":   PN = "2"  !CDS_PN = "2";
BODY = "Q_RES","I41": LOCATION = "R4717" #&CDS_LOCATION = "R4717" &SEC = "1" #&CDS_SEC = "1";
"A":   PN = "1"  !CDS_PN = "1";
"B":   PN = "2"  !CDS_PN = "2";
BODY = "Q_CAP","I42": LOCATION = "C2369" #&CDS_LOCATION = "C2369" &SEC = "1" #&CDS_SEC = "1";
"A":   PN = "1"  !CDS_PN = "1";
"B":   PN = "2"  !CDS_PN = "2";
DRAWING = "@s9s_mb_2u_lib.s9s_mb_2u(sch_1):page236";
BODY = "Q_RES","I46": #LOCATION = "R3845" !CDS_LOCATION = "R3845" &SEC = "1" #&CDS_SEC = "1";
"A":   PN = "1"  !CDS_PN = "1";
"B":   PN = "2"  !CDS_PN = "2";
BODY = "Q_CAP","I42": #LOCATION = "PC2157" !CDS_LOCATION = "PC2157" &SEC = "1" #&CDS_SEC = "1";
"A":   PN = "1"  !CDS_PN = "1";
"B":   PN = "2"  !CDS_PN = "2";
BODY = "Q_CAP","I52": #LOCATION = "PC2162" !CDS_LOCATION = "PC2162" &SEC = "1" #&CDS_SEC = "1";
"A":   PN = "1"  !CDS_PN = "1";
"B":   PN = "2"  !CDS_PN = "2";
BODY = "Q_RES","I43": #LOCATION = "PR3844" !CDS_LOCATION = "PR3844" &SEC = "1" #&CDS_SEC = "1";
"A":   PN = "1"  !CDS_PN = "1";
"B":   PN = "2"  !CDS_PN = "2";
BODY = "Q_CAP","I49": #LOCATION = "PC2161" !CDS_LOCATION = "PC2161" &SEC = "1" #&CDS_SEC = "1";
"A":   PN = "1"  !CDS_PN = "1";
"B":   PN = "2"  !CDS_PN = "2";
BODY = "MP5016GQHLZ","I50": #LOCATION = "PU205" !CDS_LOCATION = "PU205" &SEC = "1" #&CDS_SEC = "1";
"DV_DT":   PN = "10"  !CDS_PN = "10";
"EN":   PN = "9"  !CDS_PN = "9";
"GATE":   PN = "8"  !CDS_PN = "8";
"GND":   PN = "3"  !CDS_PN = "3";
"ILIMIT":   PN = "4"  !CDS_PN = "4";
"MODE":   PN = "5"  !CDS_PN = "5";
"SOURCE":   PN = "6_7"  !CDS_PN = "6_7";
"VCC":   PN = "1_2"  !CDS_PN = "1_2";
BODY = "Q_CAP","I55": #LOCATION = "PC2159" !CDS_LOCATION = "PC2159" &SEC = "1" #&CDS_SEC = "1";
"A":   PN = "1"  !CDS_PN = "1";
"B":   PN = "2"  !CDS_PN = "2";
BODY = "Q_RES","I45": #LOCATION = "PR3846" !CDS_LOCATION = "PR3846" &SEC = "1" #&CDS_SEC = "1";
"A":   PN = "1"  !CDS_PN = "1";
"B":   PN = "2"  !CDS_PN = "2";
BODY = "Q_CAP","I54": #LOCATION = "PC2163" !CDS_LOCATION = "PC2163" &SEC = "1" #&CDS_SEC = "1";
"A":   PN = "1"  !CDS_PN = "1";
"B":   PN = "2"  !CDS_PN = "2";
BODY = "Q_CAP","I60": #LOCATION = "PC2153" !CDS_LOCATION = "PC2153" &SEC = "1" #&CDS_SEC = "1";
"A":   PN = "1"  !CDS_PN = "1";
"B":   PN = "2"  !CDS_PN = "2";
BODY = "Q_RES","I62": #LOCATION = "PR3835" !CDS_LOCATION = "PR3835" &SEC = "1" #&CDS_SEC = "1";
"A":   PN = "1"  !CDS_PN = "1";
"B":   PN = "2"  !CDS_PN = "2";
BODY = "Q_CAP","I63": #LOCATION = "PC2155" !CDS_LOCATION = "PC2155" &SEC = "1" #&CDS_SEC = "1";
"A":   PN = "1"  !CDS_PN = "1";
"B":   PN = "2"  !CDS_PN = "2";
BODY = "Q_RES","I65": LOCATION = "R3834" #&CDS_LOCATION = "R3834" &SEC = "1" #&CDS_SEC = "1";
"A":   PN = "1"  !CDS_PN = "1";
"B":   PN = "2"  !CDS_PN = "2";
BODY = "Q_CAP","I68": #LOCATION = "PC2154" !CDS_LOCATION = "PC2154" &SEC = "1" #&CDS_SEC = "1";
"A":   PN = "1"  !CDS_PN = "1";
"B":   PN = "2"  !CDS_PN = "2";
BODY = "RS31312R","I70": #LOCATION = "PU204" !CDS_LOCATION = "PU204" &SEC = "1" #&CDS_SEC = "1";
"AVIN":   PN = "12"  !CDS_PN = "12";
"EN":   PN = "1"  !CDS_PN = "1";
"ENTM":   PN = "3"  !CDS_PN = "3";
"FLTB":   PN = "9"  !CDS_PN = "9";
"GND":   PN = "7"  !CDS_PN = "7";
"IMON":   PN = "8"  !CDS_PN = "8";
"ISET":   PN = "5"  !CDS_PN = "5";
"LOADEN":   PN = "2"  !CDS_PN = "2";
"OV":   PN = "11"  !CDS_PN = "11";
"PG":   PN = "10"  !CDS_PN = "10";
"SS":   PN = "6"  !CDS_PN = "6";
"TIMER":   PN = "4"  !CDS_PN = "4";
"VIN_21_22":   PN = "21_22"  !CDS_PN = "21_22";
"VIN_23":   PN = "23"  !CDS_PN = "23";
"VIN_24":   PN = "24"  !CDS_PN = "24";
"VIN_25":   PN = "25"  !CDS_PN = "25";
"VIN_26":   PN = "26"  !CDS_PN = "26";
"VOUT_13":   PN = "13"  !CDS_PN = "13";
"VOUT_14":   PN = "14"  !CDS_PN = "14";
"VOUT_15":   PN = "15"  !CDS_PN = "15";
"VOUT_16":   PN = "16"  !CDS_PN = "16";
"VOUT_17":   PN = "17"  !CDS_PN = "17";
"VOUT_18":   PN = "18"  !CDS_PN = "18";
"VOUT_19":   PN = "19"  !CDS_PN = "19";
"VOUT_20":   PN = "20"  !CDS_PN = "20";
BODY = "Q_RES","I72": #LOCATION = "PR3837" !CDS_LOCATION = "PR3837" &SEC = "1" #&CDS_SEC = "1";
"A":   PN = "1"  !CDS_PN = "1";
"B":   PN = "2"  !CDS_PN = "2";
BODY = "Q_CAP","I74": #LOCATION = "PC2156" !CDS_LOCATION = "PC2156" &SEC = "1" #&CDS_SEC = "1";
"A":   PN = "1"  !CDS_PN = "1";
"B":   PN = "2"  !CDS_PN = "2";
BODY = "Q_RES","I75": #LOCATION = "PR3839" !CDS_LOCATION = "PR3839" &SEC = "1" #&CDS_SEC = "1";
"A":   PN = "1"  !CDS_PN = "1";
"B":   PN = "2"  !CDS_PN = "2";
BODY = "Q_RES","I76": LOCATION = "R4532" #&CDS_LOCATION = "R4532" &SEC = "1" #&CDS_SEC = "1";
"A":   PN = "1"  !CDS_PN = "1";
"B":   PN = "2"  !CDS_PN = "2";
BODY = "Q_RES","I77": #LOCATION = "PR3838" !CDS_LOCATION = "PR3838" &SEC = "1" #&CDS_SEC = "1";
"A":   PN = "1"  !CDS_PN = "1";
"B":   PN = "2"  !CDS_PN = "2";
BODY = "Q_RES","I81": LOCATION = "R3872" #&CDS_LOCATION = "R3872" &SEC = "1" #&CDS_SEC = "1";
"A":   PN = "1"  !CDS_PN = "1";
"B":   PN = "2"  !CDS_PN = "2";
BODY = "Q_RES","I82": LOCATION = "R3871" #&CDS_LOCATION = "R3871" &SEC = "1" #&CDS_SEC = "1";
"A":   PN = "1"  !CDS_PN = "1";
"B":   PN = "2"  !CDS_PN = "2";
BODY = "Q_RES","I83": #LOCATION = "PR3842" !CDS_LOCATION = "PR3842" &SEC = "1" #&CDS_SEC = "1";
"A":   PN = "1"  !CDS_PN = "1";
"B":   PN = "2"  !CDS_PN = "2";
BODY = "Q_RES","I85": #LOCATION = "PR3840" !CDS_LOCATION = "PR3840" &SEC = "1" #&CDS_SEC = "1";
"A":   PN = "1"  !CDS_PN = "1";
"B":   PN = "2"  !CDS_PN = "2";
BODY = "Q_RES","I86": #LOCATION = "PR3841" !CDS_LOCATION = "PR3841" &SEC = "1" #&CDS_SEC = "1";
"A":   PN = "1"  !CDS_PN = "1";
"B":   PN = "2"  !CDS_PN = "2";
BODY = "Q_CAP","I88": #LOCATION = "PC2158" !CDS_LOCATION = "PC2158" &SEC = "1" #&CDS_SEC = "1";
"A":   PN = "1"  !CDS_PN = "1";
"B":   PN = "2"  !CDS_PN = "2";
BODY = "Q_RES","I89": #LOCATION = "PR3843" !CDS_LOCATION = "PR3843" &SEC = "1" #&CDS_SEC = "1";
"A":   PN = "1"  !CDS_PN = "1";
"B":   PN = "2"  !CDS_PN = "2";
BODY = "Q_CAP","I91": #LOCATION = "PC2160" !CDS_LOCATION = "PC2160" &SEC = "1" #&CDS_SEC = "1";
"A":   PN = "1"  !CDS_PN = "1";
"B":   PN = "2"  !CDS_PN = "2";
DRAWING = "@s9s_mb_2u_lib.s9s_mb_2u(sch_1):page324";
BODY = "Q_RES","I21": LOCATION = "R4064" #&CDS_LOCATION = "R4064" &SEC = "1" #&CDS_SEC = "1";
"A":   PN = "1"  !CDS_PN = "1";
"B":   PN = "2"  !CDS_PN = "2";
BODY = "Q_RES","I34": #LOCATION = "PR3969" !CDS_LOCATION = "PR3969" &SEC = "1" #&CDS_SEC = "1";
"A":   PN = "1"  !CDS_PN = "1";
"B":   PN = "2"  !CDS_PN = "2";
BODY = "Q_RES","I39": #LOCATION = "PR3967" !CDS_LOCATION = "PR3967" &SEC = "1" #&CDS_SEC = "1";
"A":   PN = "1"  !CDS_PN = "1";
"B":   PN = "2"  !CDS_PN = "2";
BODY = "Q_RES","I43": #LOCATION = "PR4527" !CDS_LOCATION = "PR4527" &SEC = "1" #&CDS_SEC = "1";
"A":   PN = "1"  !CDS_PN = "1";
"B":   PN = "2"  !CDS_PN = "2";
BODY = "Q_CAP","I45": #LOCATION = "PC2216" !CDS_LOCATION = "PC2216" &SEC = "1" #&CDS_SEC = "1";
"A":   PN = "1"  !CDS_PN = "1";
"B":   PN = "2"  !CDS_PN = "2";
BODY = "SCHOTTKY_AC","I46": #LOCATION = "PD113" !CDS_LOCATION = "PD113" &SEC = "1" #&CDS_SEC = "1";
"A":   PN = "A"  !CDS_PN = "A";
"C":   PN = "C"  !CDS_PN = "C";
BODY = "Q_RES","I48": #LOCATION = "R3977" !CDS_LOCATION = "R3977" &SEC = "1" #&CDS_SEC = "1";
"A":   PN = "1"  !CDS_PN = "1";
"B":   PN = "2"  !CDS_PN = "2";
BODY = "Q_RES","I61": #LOCATION = "PR3966" !CDS_LOCATION = "PR3966" &SEC = "1" #&CDS_SEC = "1";
"A":   PN = "1"  !CDS_PN = "1";
"B":   PN = "2"  !CDS_PN = "2";
BODY = "MAX15090BEWIT","I62": #LOCATION = "PU294" !CDS_LOCATION = "PU294" &SEC = "1" #&CDS_SEC = "1";
"CB":   PN = "B1"  !CDS_PN = "B1";
"CDLY":   PN = "A7"  !CDS_PN = "A7";
"EN#":   PN = "B7"  !CDS_PN = "B7";
"FAULT#":   PN = "C7"  !CDS_PN = "C7";
"GATE":   PN = "A6"  !CDS_PN = "A6";
"GND_B2":   PN = "B2"  !CDS_PN = "B2";
"GND_C1":   PN = "C1"  !CDS_PN = "C1";
"GND_C2":   PN = "C2"  !CDS_PN = "C2";
"IN_A3":   PN = "A3"  !CDS_PN = "A3";
"IN_A5":   PN = "A5"  !CDS_PN = "A5";
"IN_B3":   PN = "B3"  !CDS_PN = "B3";
"IN_B5":   PN = "B5"  !CDS_PN = "B5";
"IN_C3":   PN = "C3"  !CDS_PN = "C3";
"IN_C5":   PN = "C5"  !CDS_PN = "C5";
"IN_D5":   PN = "D5"  !CDS_PN = "D5";
"ISENSE":   PN = "A1"  !CDS_PN = "A1";
"OUT_A4":   PN = "A4"  !CDS_PN = "A4";
"OUT_B4":   PN = "B4"  !CDS_PN = "B4";
"OUT_B6":   PN = "B6"  !CDS_PN = "B6";
"OUT_C4":   PN = "C4"  !CDS_PN = "C4";
"OUT_C6":   PN = "C6"  !CDS_PN = "C6";
"OUT_D4":   PN = "D4"  !CDS_PN = "D4";
"OUT_D6":   PN = "D6"  !CDS_PN = "D6";
"OV":   PN = "D3"  !CDS_PN = "D3";
"PG":   PN = "D7"  !CDS_PN = "D7";
"REG":   PN = "D1"  !CDS_PN = "D1";
"UV":   PN = "D2"  !CDS_PN = "D2";
"VCC":   PN = "A2"  !CDS_PN = "A2";
BODY = "Q_RES","I67": #LOCATION = "R3974" !CDS_LOCATION = "R3974" &SEC = "1" #&CDS_SEC = "1";
"A":   PN = "1"  !CDS_PN = "1";
"B":   PN = "2"  !CDS_PN = "2";
BODY = "Q_RES","I70": #LOCATION = "PR4528" !CDS_LOCATION = "PR4528" &SEC = "1" #&CDS_SEC = "1";
"A":   PN = "1"  !CDS_PN = "1";
"B":   PN = "2"  !CDS_PN = "2";
BODY = "SCHOTTKY_AC","I71": #LOCATION = "PD112" !CDS_LOCATION = "PD112" &SEC = "1" #&CDS_SEC = "1";
"A":   PN = "A"  !CDS_PN = "A";
"C":   PN = "C"  !CDS_PN = "C";
BODY = "Q_RES","I1": LOCATION = "R4063" #&CDS_LOCATION = "R4063" &SEC = "1" #&CDS_SEC = "1";
"A":   PN = "1"  !CDS_PN = "1";
"B":   PN = "2"  !CDS_PN = "2";
BODY = "MOSFET_NCH_DUAL","I4": LOCATION = "Q126" #&CDS_LOCATION = "Q126" &SEC = "2" #&CDS_SEC = "2";
"D2":   PN = "3"  !CDS_PN = "3";
"G2":   PN = "5"  !CDS_PN = "5";
"S2":   PN = "4"  !CDS_PN = "4";
BODY = "Q_RES","I6": LOCATION = "R4072" #&CDS_LOCATION = "R4072" &SEC = "1" #&CDS_SEC = "1";
"A":   PN = "1"  !CDS_PN = "1";
"B":   PN = "2"  !CDS_PN = "2";
BODY = "Q_RES","I9": LOCATION = "R4073" #&CDS_LOCATION = "R4073" &SEC = "1" #&CDS_SEC = "1";
"A":   PN = "1"  !CDS_PN = "1";
"B":   PN = "2"  !CDS_PN = "2";
BODY = "Q_RES","I13": #LOCATION = "PR3965" !CDS_LOCATION = "PR3965" &SEC = "1" #&CDS_SEC = "1";
"A":   PN = "1"  !CDS_PN = "1";
"B":   PN = "2"  !CDS_PN = "2";
BODY = "Q_RES","I14": #LOCATION = "PR3964" !CDS_LOCATION = "PR3964" &SEC = "1" #&CDS_SEC = "1";
"A":   PN = "1"  !CDS_PN = "1";
"B":   PN = "2"  !CDS_PN = "2";
BODY = "Q_CAP","I17": #LOCATION = "PC2208" !CDS_LOCATION = "PC2208" &SEC = "1" #&CDS_SEC = "1";
"A":   PN = "1"  !CDS_PN = "1";
"B":   PN = "2"  !CDS_PN = "2";
BODY = "Q_CAP","I60": #LOCATION = "PC2209" !CDS_LOCATION = "PC2209" &SEC = "1" #&CDS_SEC = "1";
"A":   PN = "1"  !CDS_PN = "1";
"B":   PN = "2"  !CDS_PN = "2";
BODY = "Q_RES","I65": LOCATION = "R3975" #&CDS_LOCATION = "R3975" &SEC = "1" #&CDS_SEC = "1";
"A":   PN = "1"  !CDS_PN = "1";
"B":   PN = "2"  !CDS_PN = "2";
BODY = "Q_CAP","I66": #LOCATION = "PC2215" !CDS_LOCATION = "PC2215" &SEC = "1" #&CDS_SEC = "1";
"A":   PN = "1"  !CDS_PN = "1";
"B":   PN = "2"  !CDS_PN = "2";
BODY = "Q_RES","I68": LOCATION = "R3972" #&CDS_LOCATION = "R3972" &SEC = "1" #&CDS_SEC = "1";
"A":   PN = "1"  !CDS_PN = "1";
"B":   PN = "2"  !CDS_PN = "2";
BODY = "Q_RES","I22": LOCATION = "R4074" #&CDS_LOCATION = "R4074" &SEC = "1" #&CDS_SEC = "1";
"A":   PN = "1"  !CDS_PN = "1";
"B":   PN = "2"  !CDS_PN = "2";
BODY = "Q_RES","I28": #LOCATION = "PR3962" !CDS_LOCATION = "PR3962" &SEC = "1" #&CDS_SEC = "1";
"A":   PN = "1"  !CDS_PN = "1";
"B":   PN = "2"  !CDS_PN = "2";
BODY = "Q_CAP","I31": #LOCATION = "PC2207" !CDS_LOCATION = "PC2207" &SEC = "1" #&CDS_SEC = "1";
"A":   PN = "1"  !CDS_PN = "1";
"B":   PN = "2"  !CDS_PN = "2";
BODY = "Q_CAP","I37": #LOCATION = "PC2210" !CDS_LOCATION = "PC2210" &SEC = "1" #&CDS_SEC = "1";
"A":   PN = "1"  !CDS_PN = "1";
"B":   PN = "2"  !CDS_PN = "2";
BODY = "Q_RES","I41": #LOCATION = "PR3971" !CDS_LOCATION = "PR3971" &SEC = "1" #&CDS_SEC = "1";
"A":   PN = "1"  !CDS_PN = "1";
"B":   PN = "2"  !CDS_PN = "2";
BODY = "Q_RES","I44": LOCATION = "R3973" #&CDS_LOCATION = "R3973" &SEC = "1" #&CDS_SEC = "1";
"A":   PN = "1"  !CDS_PN = "1";
"B":   PN = "2"  !CDS_PN = "2";
BODY = "Q_RES","I50": #LOCATION = "R3979" !CDS_LOCATION = "R3979" &SEC = "1" #&CDS_SEC = "1";
"A":   PN = "1"  !CDS_PN = "1";
"B":   PN = "2"  !CDS_PN = "2";
BODY = "Q_CAP","I69": #LOCATION = "PC2214" !CDS_LOCATION = "PC2214" &SEC = "1" #&CDS_SEC = "1";
"A":   PN = "1"  !CDS_PN = "1";
"B":   PN = "2"  !CDS_PN = "2";
BODY = "Q_CAP","I75": #LOCATION = "PC2217" !CDS_LOCATION = "PC2217" &SEC = "1" #&CDS_SEC = "1";
"A":   PN = "1"  !CDS_PN = "1";
"B":   PN = "2"  !CDS_PN = "2";
BODY = "Q_RES","I76": #LOCATION = "R3978" !CDS_LOCATION = "R3978" &SEC = "1" #&CDS_SEC = "1";
"A":   PN = "1"  !CDS_PN = "1";
"B":   PN = "2"  !CDS_PN = "2";
BODY = "Q_CAP","I78": #LOCATION = "PC2219" !CDS_LOCATION = "PC2219" &SEC = "1" #&CDS_SEC = "1";
"A":   PN = "1"  !CDS_PN = "1";
"B":   PN = "2"  !CDS_PN = "2";
BODY = "MOSFET_NCH_DUAL","I3": LOCATION = "Q126" #&CDS_LOCATION = "Q126" &SEC = "1" #&CDS_SEC = "1";
"D1":   PN = "6"  !CDS_PN = "6";
"G1":   PN = "2"  !CDS_PN = "2";
"S1":   PN = "1"  !CDS_PN = "1";
BODY = "MOSFET_NCH_DUAL","I10": LOCATION = "Q127" #&CDS_LOCATION = "Q127" &SEC = "1" #&CDS_SEC = "1";
"D1":   PN = "6"  !CDS_PN = "6";
"G1":   PN = "2"  !CDS_PN = "2";
"S1":   PN = "1"  !CDS_PN = "1";
BODY = "Q_RES","I15": LOCATION = "R3959" #&CDS_LOCATION = "R3959" &SEC = "1" #&CDS_SEC = "1";
"A":   PN = "1"  !CDS_PN = "1";
"B":   PN = "2"  !CDS_PN = "2";
BODY = "Q_RES","I18": #LOCATION = "PR3963" !CDS_LOCATION = "PR3963" &SEC = "1" #&CDS_SEC = "1";
"A":   PN = "1"  !CDS_PN = "1";
"B":   PN = "2"  !CDS_PN = "2";
BODY = "MOSFET_NCH_DUAL","I24": LOCATION = "Q127" #&CDS_LOCATION = "Q127" &SEC = "2" #&CDS_SEC = "2";
"D2":   PN = "3"  !CDS_PN = "3";
"G2":   PN = "5"  !CDS_PN = "5";
"S2":   PN = "4"  !CDS_PN = "4";
BODY = "Q_RES","I26": LOCATION = "R3958" #&CDS_LOCATION = "R3958" &SEC = "1" #&CDS_SEC = "1";
"A":   PN = "1"  !CDS_PN = "1";
"B":   PN = "2"  !CDS_PN = "2";
BODY = "Q_RES","I32": #LOCATION = "PR3960" !CDS_LOCATION = "PR3960" &SEC = "1" #&CDS_SEC = "1";
"A":   PN = "1"  !CDS_PN = "1";
"B":   PN = "2"  !CDS_PN = "2";
BODY = "MAX15090BEWIT","I35": #LOCATION = "PU295" !CDS_LOCATION = "PU295" &SEC = "1" #&CDS_SEC = "1";
"CB":   PN = "B1"  !CDS_PN = "B1";
"CDLY":   PN = "A7"  !CDS_PN = "A7";
"EN#":   PN = "B7"  !CDS_PN = "B7";
"FAULT#":   PN = "C7"  !CDS_PN = "C7";
"GATE":   PN = "A6"  !CDS_PN = "A6";
"GND_B2":   PN = "B2"  !CDS_PN = "B2";
"GND_C1":   PN = "C1"  !CDS_PN = "C1";
"GND_C2":   PN = "C2"  !CDS_PN = "C2";
"IN_A3":   PN = "A3"  !CDS_PN = "A3";
"IN_A5":   PN = "A5"  !CDS_PN = "A5";
"IN_B3":   PN = "B3"  !CDS_PN = "B3";
"IN_B5":   PN = "B5"  !CDS_PN = "B5";
"IN_C3":   PN = "C3"  !CDS_PN = "C3";
"IN_C5":   PN = "C5"  !CDS_PN = "C5";
"IN_D5":   PN = "D5"  !CDS_PN = "D5";
"ISENSE":   PN = "A1"  !CDS_PN = "A1";
"OUT_A4":   PN = "A4"  !CDS_PN = "A4";
"OUT_B4":   PN = "B4"  !CDS_PN = "B4";
"OUT_B6":   PN = "B6"  !CDS_PN = "B6";
"OUT_C4":   PN = "C4"  !CDS_PN = "C4";
"OUT_C6":   PN = "C6"  !CDS_PN = "C6";
"OUT_D4":   PN = "D4"  !CDS_PN = "D4";
"OUT_D6":   PN = "D6"  !CDS_PN = "D6";
"OV":   PN = "D3"  !CDS_PN = "D3";
"PG":   PN = "D7"  !CDS_PN = "D7";
"REG":   PN = "D1"  !CDS_PN = "D1";
"UV":   PN = "D2"  !CDS_PN = "D2";
"VCC":   PN = "A2"  !CDS_PN = "A2";
BODY = "Q_CAP","I38": #LOCATION = "PC2212" !CDS_LOCATION = "PC2212" &SEC = "1" #&CDS_SEC = "1";
"A":   PN = "1"  !CDS_PN = "1";
"B":   PN = "2"  !CDS_PN = "2";
BODY = "Q_CAP","I42": #LOCATION = "PC2213" !CDS_LOCATION = "PC2213" &SEC = "1" #&CDS_SEC = "1";
"A":   PN = "1"  !CDS_PN = "1";
"B":   PN = "2"  !CDS_PN = "2";
BODY = "Q_CAP","I52": #LOCATION = "PC2218" !CDS_LOCATION = "PC2218" &SEC = "1" #&CDS_SEC = "1";
"A":   PN = "1"  !CDS_PN = "1";
"B":   PN = "2"  !CDS_PN = "2";
BODY = "Q_CAP","I53": #LOCATION = "PC2220" !CDS_LOCATION = "PC2220" &SEC = "1" #&CDS_SEC = "1";
"A":   PN = "1"  !CDS_PN = "1";
"B":   PN = "2"  !CDS_PN = "2";
BODY = "Q_CAP","I57": #LOCATION = "PC2211" !CDS_LOCATION = "PC2211" &SEC = "1" #&CDS_SEC = "1";
"A":   PN = "1"  !CDS_PN = "1";
"B":   PN = "2"  !CDS_PN = "2";
BODY = "Q_RES","I59": #LOCATION = "PR3968" !CDS_LOCATION = "PR3968" &SEC = "1" #&CDS_SEC = "1";
"A":   PN = "1"  !CDS_PN = "1";
"B":   PN = "2"  !CDS_PN = "2";
BODY = "Q_RES","I64": #LOCATION = "PR3970" !CDS_LOCATION = "PR3970" &SEC = "1" #&CDS_SEC = "1";
"A":   PN = "1"  !CDS_PN = "1";
"B":   PN = "2"  !CDS_PN = "2";
BODY = "Q_RES","I73": #LOCATION = "R3976" !CDS_LOCATION = "R3976" &SEC = "1" #&CDS_SEC = "1";
"A":   PN = "1"  !CDS_PN = "1";
"B":   PN = "2"  !CDS_PN = "2";
BODY = "Q_CAP","I79": #LOCATION = "PC2280" !CDS_LOCATION = "PC2280" &SEC = "1" #&CDS_SEC = "1";
"A":   PN = "1"  !CDS_PN = "1";
"B":   PN = "2"  !CDS_PN = "2";
BODY = "DIODE_TVS","I84": #LOCATION = "PD114" !CDS_LOCATION = "PD114" &SEC = "1" #&CDS_SEC = "1";
"A":   PN = "A"  !CDS_PN = "A";
"C":   PN = "C"  !CDS_PN = "C";
BODY = "Q_RES","I85": #LOCATION = "PR3961" !CDS_LOCATION = "PR3961" &SEC = "1" #&CDS_SEC = "1";
"A":   PN = "1"  !CDS_PN = "1";
"B":   PN = "2"  !CDS_PN = "2";
DRAWING = "@s9s_mb_2u_lib.s9s_mb_2u(sch_1):page323";
BODY = "Q_CAP","I3": #LOCATION = "PC2197" !CDS_LOCATION = "PC2197" &SEC = "1" #&CDS_SEC = "1";
"A":   PN = "1"  !CDS_PN = "1";
"B":   PN = "2"  !CDS_PN = "2";
BODY = "Q_CAP","I9": #LOCATION = "PC2200" !CDS_LOCATION = "PC2200" &SEC = "1" #&CDS_SEC = "1";
"A":   PN = "1"  !CDS_PN = "1";
"B":   PN = "2"  !CDS_PN = "2";
BODY = "Q_CAP","I34": #LOCATION = "PC2204" !CDS_LOCATION = "PC2204" &SEC = "1" #&CDS_SEC = "1";
"A":   PN = "1"  !CDS_PN = "1";
"B":   PN = "2"  !CDS_PN = "2";
BODY = "Q_RES","I45": LOCATION = "R3943" #&CDS_LOCATION = "R3943" &SEC = "1" #&CDS_SEC = "1";
"A":   PN = "1"  !CDS_PN = "1";
"B":   PN = "2"  !CDS_PN = "2";
BODY = "Q_RES","I4": #LOCATION = "PR3945" !CDS_LOCATION = "PR3945" &SEC = "1" #&CDS_SEC = "1";
"A":   PN = "1"  !CDS_PN = "1";
"B":   PN = "2"  !CDS_PN = "2";
BODY = "Q_RES","I5": LOCATION = "R3946" #&CDS_LOCATION = "R3946" &SEC = "1" #&CDS_SEC = "1";
"A":   PN = "1"  !CDS_PN = "1";
"B":   PN = "2"  !CDS_PN = "2";
BODY = "Q_CAP","I30": #LOCATION = "PC2201" !CDS_LOCATION = "PC2201" &SEC = "1" #&CDS_SEC = "1";
"A":   PN = "1"  !CDS_PN = "1";
"B":   PN = "2"  !CDS_PN = "2";
BODY = "Q_CAP","I32": #LOCATION = "PC2203" !CDS_LOCATION = "PC2203" &SEC = "1" #&CDS_SEC = "1";
"A":   PN = "1"  !CDS_PN = "1";
"B":   PN = "2"  !CDS_PN = "2";
BODY = "MP5016GQHLZ","I31": #LOCATION = "PU293" !CDS_LOCATION = "PU293" &SEC = "1" #&CDS_SEC = "1";
"DV_DT":   PN = "10"  !CDS_PN = "10";
"EN":   PN = "9"  !CDS_PN = "9";
"GATE":   PN = "8"  !CDS_PN = "8";
"GND":   PN = "3"  !CDS_PN = "3";
"ILIMIT":   PN = "4"  !CDS_PN = "4";
"MODE":   PN = "5"  !CDS_PN = "5";
"SOURCE":   PN = "6_7"  !CDS_PN = "6_7";
"VCC":   PN = "1_2"  !CDS_PN = "1_2";
BODY = "Q_CAP","I37": #LOCATION = "PC2196" !CDS_LOCATION = "PC2196" &SEC = "1" #&CDS_SEC = "1";
"A":   PN = "1"  !CDS_PN = "1";
"B":   PN = "2"  !CDS_PN = "2";
BODY = "Q_RES","I40": #LOCATION = "PR3944" !CDS_LOCATION = "PR3944" &SEC = "1" #&CDS_SEC = "1";
"A":   PN = "1"  !CDS_PN = "1";
"B":   PN = "2"  !CDS_PN = "2";
BODY = "Q_CAP","I42": #LOCATION = "PC2341" !CDS_LOCATION = "PC2341" &SEC = "1" #&CDS_SEC = "1";
"A":   PN = "1"  !CDS_PN = "1";
"B":   PN = "2"  !CDS_PN = "2";
BODY = "Q_CAP","I47": #LOCATION = "PC2281" !CDS_LOCATION = "PC2281" &SEC = "1" #&CDS_SEC = "1";
"A":   PN = "1"  !CDS_PN = "1";
"B":   PN = "2"  !CDS_PN = "2";
BODY = "RS31312R","I49": #LOCATION = "PU292" !CDS_LOCATION = "PU292" &SEC = "1" #&CDS_SEC = "1";
"AVIN":   PN = "12"  !CDS_PN = "12";
"EN":   PN = "1"  !CDS_PN = "1";
"ENTM":   PN = "3"  !CDS_PN = "3";
"FLTB":   PN = "9"  !CDS_PN = "9";
"GND":   PN = "7"  !CDS_PN = "7";
"IMON":   PN = "8"  !CDS_PN = "8";
"ISET":   PN = "5"  !CDS_PN = "5";
"LOADEN":   PN = "2"  !CDS_PN = "2";
"OV":   PN = "11"  !CDS_PN = "11";
"PG":   PN = "10"  !CDS_PN = "10";
"SS":   PN = "6"  !CDS_PN = "6";
"TIMER":   PN = "4"  !CDS_PN = "4";
"VIN_21_22":   PN = "21_22"  !CDS_PN = "21_22";
"VIN_23":   PN = "23"  !CDS_PN = "23";
"VIN_24":   PN = "24"  !CDS_PN = "24";
"VIN_25":   PN = "25"  !CDS_PN = "25";
"VIN_26":   PN = "26"  !CDS_PN = "26";
"VOUT_13":   PN = "13"  !CDS_PN = "13";
"VOUT_14":   PN = "14"  !CDS_PN = "14";
"VOUT_15":   PN = "15"  !CDS_PN = "15";
"VOUT_16":   PN = "16"  !CDS_PN = "16";
"VOUT_17":   PN = "17"  !CDS_PN = "17";
"VOUT_18":   PN = "18"  !CDS_PN = "18";
"VOUT_19":   PN = "19"  !CDS_PN = "19";
"VOUT_20":   PN = "20"  !CDS_PN = "20";
BODY = "Q_CAP","I51": #LOCATION = "PC2198" !CDS_LOCATION = "PC2198" &SEC = "1" #&CDS_SEC = "1";
"A":   PN = "1"  !CDS_PN = "1";
"B":   PN = "2"  !CDS_PN = "2";
BODY = "Q_RES","I54": #LOCATION = "PR3951" !CDS_LOCATION = "PR3951" &SEC = "1" #&CDS_SEC = "1";
"A":   PN = "1"  !CDS_PN = "1";
"B":   PN = "2"  !CDS_PN = "2";
BODY = "Q_CAP","I56": #LOCATION = "PC2202" !CDS_LOCATION = "PC2202" &SEC = "1" #&CDS_SEC = "1";
"A":   PN = "1"  !CDS_PN = "1";
"B":   PN = "2"  !CDS_PN = "2";
BODY = "Q_RES","I6": #LOCATION = "PR3947" !CDS_LOCATION = "PR3947" &SEC = "1" #&CDS_SEC = "1";
"A":   PN = "1"  !CDS_PN = "1";
"B":   PN = "2"  !CDS_PN = "2";
BODY = "Q_RES","I43": #LOCATION = "PR4541" !CDS_LOCATION = "PR4541" &SEC = "1" #&CDS_SEC = "1";
"A":   PN = "1"  !CDS_PN = "1";
"B":   PN = "2"  !CDS_PN = "2";
BODY = "Q_RES","I53": #LOCATION = "PR3949" !CDS_LOCATION = "PR3949" &SEC = "1" #&CDS_SEC = "1";
"A":   PN = "1"  !CDS_PN = "1";
"B":   PN = "2"  !CDS_PN = "2";
BODY = "Q_RES","I55": #LOCATION = "PR3950" !CDS_LOCATION = "PR3950" &SEC = "1" #&CDS_SEC = "1";
"A":   PN = "1"  !CDS_PN = "1";
"B":   PN = "2"  !CDS_PN = "2";
BODY = "Q_RES","I58": #LOCATION = "PR3954" !CDS_LOCATION = "PR3954" &SEC = "1" #&CDS_SEC = "1";
"A":   PN = "1"  !CDS_PN = "1";
"B":   PN = "2"  !CDS_PN = "2";
BODY = "Q_RES","I62": #LOCATION = "PR3952" !CDS_LOCATION = "PR3952" &SEC = "1" #&CDS_SEC = "1";
"A":   PN = "1"  !CDS_PN = "1";
"B":   PN = "2"  !CDS_PN = "2";
BODY = "Q_RES","I63": #LOCATION = "PR3953" !CDS_LOCATION = "PR3953" &SEC = "1" #&CDS_SEC = "1";
"A":   PN = "1"  !CDS_PN = "1";
"B":   PN = "2"  !CDS_PN = "2";
BODY = "Q_RES","I64": #LOCATION = "R3948" !CDS_LOCATION = "R3948" &SEC = "1" #&CDS_SEC = "1";
"A":   PN = "1"  !CDS_PN = "1";
"B":   PN = "2"  !CDS_PN = "2";
BODY = "Q_RES","I66": LOCATION = "R3956" #&CDS_LOCATION = "R3956" &SEC = "1" #&CDS_SEC = "1";
"A":   PN = "1"  !CDS_PN = "1";
"B":   PN = "2"  !CDS_PN = "2";
BODY = "Q_RES","I67": LOCATION = "R3955" #&CDS_LOCATION = "R3955" &SEC = "1" #&CDS_SEC = "1";
"A":   PN = "1"  !CDS_PN = "1";
"B":   PN = "2"  !CDS_PN = "2";
BODY = "Q_CAP","I69": #LOCATION = "PC2205" !CDS_LOCATION = "PC2205" &SEC = "1" #&CDS_SEC = "1";
"A":   PN = "1"  !CDS_PN = "1";
"B":   PN = "2"  !CDS_PN = "2";
BODY = "Q_RES","I70": #LOCATION = "PR3957" !CDS_LOCATION = "PR3957" &SEC = "1" #&CDS_SEC = "1";
"A":   PN = "1"  !CDS_PN = "1";
"B":   PN = "2"  !CDS_PN = "2";
BODY = "Q_CAP","I73": #LOCATION = "PC2206" !CDS_LOCATION = "PC2206" &SEC = "1" #&CDS_SEC = "1";
"A":   PN = "1"  !CDS_PN = "1";
"B":   PN = "2"  !CDS_PN = "2";
DRAWING = "@s9s_mb_2u_lib.s9s_mb_2u(sch_1):page325";
BODY = "Q_CAP","I11": #LOCATION = "PC2349" !CDS_LOCATION = "PC2349" &SEC = "1" #&CDS_SEC = "1";
"A":   PN = "1"  !CDS_PN = "1";
"B":   PN = "2"  !CDS_PN = "2";
BODY = "Q_RES","I12": #LOCATION = "PR3987" !CDS_LOCATION = "PR3987" &SEC = "1" #&CDS_SEC = "1";
"A":   PN = "1"  !CDS_PN = "1";
"B":   PN = "2"  !CDS_PN = "2";
BODY = "Q_RES","I13": #LOCATION = "PR3991" !CDS_LOCATION = "PR3991" &SEC = "1" #&CDS_SEC = "1";
"A":   PN = "1"  !CDS_PN = "1";
"B":   PN = "2"  !CDS_PN = "2";
BODY = "Q_RES","I16": #LOCATION = "PR3989" !CDS_LOCATION = "PR3989" &SEC = "1" #&CDS_SEC = "1";
"A":   PN = "1"  !CDS_PN = "1";
"B":   PN = "2"  !CDS_PN = "2";
BODY = "Q_RES","I21": #LOCATION = "PR3980" !CDS_LOCATION = "PR3980" &SEC = "1" #&CDS_SEC = "1";
"A":   PN = "1"  !CDS_PN = "1";
"B":   PN = "2"  !CDS_PN = "2";
BODY = "Q_RES","I34": #LOCATION = "PR3990" !CDS_LOCATION = "PR3990" &SEC = "1" #&CDS_SEC = "1";
"A":   PN = "1"  !CDS_PN = "1";
"B":   PN = "2"  !CDS_PN = "2";
BODY = "Q_RES","I39": #LOCATION = "PR3995" !CDS_LOCATION = "PR3995" &SEC = "1" #&CDS_SEC = "1";
"A":   PN = "1"  !CDS_PN = "1";
"B":   PN = "2"  !CDS_PN = "2";
BODY = "MP5991GLUZ","I17": #LOCATION = "PU297" !CDS_LOCATION = "PU297" #SEC = "1" !CDS_SEC = "1";
"CS":   PN = "23"  !CDS_PN = "23";
"D_OC":   PN = "3"  !CDS_PN = "3";
"FLT_TYPE":   PN = "6"  !CDS_PN = "6";
"GND":   PN = "20"  !CDS_PN = "20";
"GOK":   PN = "5"  !CDS_PN = "5";
"IMON":   PN = "22"  !CDS_PN = "22";
"MODE":   PN = "8"  !CDS_PN = "8";
"NC1":   PN = "7"  !CDS_PN = "7";
"OCREF":   PN = "24"  !CDS_PN = "24";
"ON":   PN = "4"  !CDS_PN = "4";
"SCREF_OCWREF":   PN = "17"  !CDS_PN = "17";
"SS":   PN = "19"  !CDS_PN = "19";
"VDD33":   PN = "21"  !CDS_PN = "21";
"VIN1":   PN = "9"  !CDS_PN = "9";
"VIN2":   PN = "10"  !CDS_PN = "10";
"VIN3":   PN = "11"  !CDS_PN = "11";
"VIN4":   PN = "12"  !CDS_PN = "12";
"VIN5":   PN = "13"  !CDS_PN = "13";
"VIN6":   PN = "14"  !CDS_PN = "14";
"VIN7":   PN = "15"  !CDS_PN = "15";
"VIN8":   PN = "16"  !CDS_PN = "16";
"VIN9":   PN = "33"  !CDS_PN = "33";
"VOUT1":   PN = "1"  !CDS_PN = "1";
"VOUT2":   PN = "2"  !CDS_PN = "2";
"VOUT3":   PN = "25"  !CDS_PN = "25";
"VOUT4":   PN = "26"  !CDS_PN = "26";
"VOUT5":   PN = "27"  !CDS_PN = "27";
"VOUT6":   PN = "28"  !CDS_PN = "28";
"VOUT7":   PN = "29"  !CDS_PN = "29";
"VOUT8":   PN = "30"  !CDS_PN = "30";
"VOUT9":   PN = "31"  !CDS_PN = "31";
"VOUT10":   PN = "32"  !CDS_PN = "32";
"VTEMP":   PN = "18"  !CDS_PN = "18";
BODY = "Q_RES","I49": #LOCATION = "PR3993" !CDS_LOCATION = "PR3993" &SEC = "1" #&CDS_SEC = "1";
"A":   PN = "1"  !CDS_PN = "1";
"B":   PN = "2"  !CDS_PN = "2";
BODY = "Q_CAP","I4": #LOCATION = "PC2223" !CDS_LOCATION = "PC2223" &SEC = "1" #&CDS_SEC = "1";
"A":   PN = "1"  !CDS_PN = "1";
"B":   PN = "2"  !CDS_PN = "2";
BODY = "Q_RES","I30": #LOCATION = "PR3986" !CDS_LOCATION = "PR3986" &SEC = "1" #&CDS_SEC = "1";
"A":   PN = "1"  !CDS_PN = "1";
"B":   PN = "2"  !CDS_PN = "2";
BODY = "MP5991GLUZ","I35": #LOCATION = "PU296" !CDS_LOCATION = "PU296" #SEC = "1" !CDS_SEC = "1";
"CS":   PN = "23"  !CDS_PN = "23";
"D_OC":   PN = "3"  !CDS_PN = "3";
"FLT_TYPE":   PN = "6"  !CDS_PN = "6";
"GND":   PN = "20"  !CDS_PN = "20";
"GOK":   PN = "5"  !CDS_PN = "5";
"IMON":   PN = "22"  !CDS_PN = "22";
"MODE":   PN = "8"  !CDS_PN = "8";
"NC1":   PN = "7"  !CDS_PN = "7";
"OCREF":   PN = "24"  !CDS_PN = "24";
"ON":   PN = "4"  !CDS_PN = "4";
"SCREF_OCWREF":   PN = "17"  !CDS_PN = "17";
"SS":   PN = "19"  !CDS_PN = "19";
"VDD33":   PN = "21"  !CDS_PN = "21";
"VIN1":   PN = "9"  !CDS_PN = "9";
"VIN2":   PN = "10"  !CDS_PN = "10";
"VIN3":   PN = "11"  !CDS_PN = "11";
"VIN4":   PN = "12"  !CDS_PN = "12";
"VIN5":   PN = "13"  !CDS_PN = "13";
"VIN6":   PN = "14"  !CDS_PN = "14";
"VIN7":   PN = "15"  !CDS_PN = "15";
"VIN8":   PN = "16"  !CDS_PN = "16";
"VIN9":   PN = "33"  !CDS_PN = "33";
"VOUT1":   PN = "1"  !CDS_PN = "1";
"VOUT2":   PN = "2"  !CDS_PN = "2";
"VOUT3":   PN = "25"  !CDS_PN = "25";
"VOUT4":   PN = "26"  !CDS_PN = "26";
"VOUT5":   PN = "27"  !CDS_PN = "27";
"VOUT6":   PN = "28"  !CDS_PN = "28";
"VOUT7":   PN = "29"  !CDS_PN = "29";
"VOUT8":   PN = "30"  !CDS_PN = "30";
"VOUT9":   PN = "31"  !CDS_PN = "31";
"VOUT10":   PN = "32"  !CDS_PN = "32";
"VTEMP":   PN = "18"  !CDS_PN = "18";
BODY = "Q_RES","I40": #LOCATION = "PR3994" !CDS_LOCATION = "PR3994" &SEC = "1" #&CDS_SEC = "1";
"A":   PN = "1"  !CDS_PN = "1";
"B":   PN = "2"  !CDS_PN = "2";
BODY = "Q_RES","I50": #LOCATION = "PR3992" !CDS_LOCATION = "PR3992" &SEC = "1" #&CDS_SEC = "1";
"A":   PN = "1"  !CDS_PN = "1";
"B":   PN = "2"  !CDS_PN = "2";
BODY = "Q_CAP","I38": #LOCATION = "PC2227" !CDS_LOCATION = "PC2227" &SEC = "1" #&CDS_SEC = "1";
"A":   PN = "1"  !CDS_PN = "1";
"B":   PN = "2"  !CDS_PN = "2";
BODY = "Q_CAP","I19": #LOCATION = "PC3272" !CDS_LOCATION = "PC3272" &SEC = "1" #&CDS_SEC = "1";
"A":   PN = "1"  !CDS_PN = "1";
"B":   PN = "2"  !CDS_PN = "2";
BODY = "Q_CAP","I23": #LOCATION = "PC2224" !CDS_LOCATION = "PC2224" &SEC = "1" #&CDS_SEC = "1";
"A":   PN = "1"  !CDS_PN = "1";
"B":   PN = "2"  !CDS_PN = "2";
BODY = "Q_CAP","I29": #LOCATION = "PC2350" !CDS_LOCATION = "PC2350" &SEC = "1" #&CDS_SEC = "1";
"A":   PN = "1"  !CDS_PN = "1";
"B":   PN = "2"  !CDS_PN = "2";
BODY = "Q_RES","I32": #LOCATION = "PR3982" !CDS_LOCATION = "PR3982" &SEC = "1" #&CDS_SEC = "1";
"A":   PN = "1"  !CDS_PN = "1";
"B":   PN = "2"  !CDS_PN = "2";
BODY = "Q_CAP","I2": #LOCATION = "PC2225" !CDS_LOCATION = "PC2225" &SEC = "1" #&CDS_SEC = "1";
"A":   PN = "1"  !CDS_PN = "1";
"B":   PN = "2"  !CDS_PN = "2";
BODY = "Q_RES","I5": #LOCATION = "PR3981" !CDS_LOCATION = "PR3981" &SEC = "1" #&CDS_SEC = "1";
"A":   PN = "1"  !CDS_PN = "1";
"B":   PN = "2"  !CDS_PN = "2";
BODY = "Q_RES","I14": #LOCATION = "PR3984" !CDS_LOCATION = "PR3984" &SEC = "1" #&CDS_SEC = "1";
"A":   PN = "1"  !CDS_PN = "1";
"B":   PN = "2"  !CDS_PN = "2";
BODY = "Q_RES","I33": #LOCATION = "PR3988" !CDS_LOCATION = "PR3988" &SEC = "1" #&CDS_SEC = "1";
"A":   PN = "1"  !CDS_PN = "1";
"B":   PN = "2"  !CDS_PN = "2";
BODY = "Q_CAP","I48": #LOCATION = "PC2226" !CDS_LOCATION = "PC2226" &SEC = "1" #&CDS_SEC = "1";
"A":   PN = "1"  !CDS_PN = "1";
"B":   PN = "2"  !CDS_PN = "2";
DRAWING = "@s9s_mb_2u_lib.s9s_mb_2u(sch_1):page229";
BODY = "Q_RES","I63": #LOCATION = "PR4004" !CDS_LOCATION = "PR4004" &SEC = "1" #&CDS_SEC = "1";
"A":   PN = "1"  !CDS_PN = "1";
"B":   PN = "2"  !CDS_PN = "2";
BODY = "Q_RES","I67": #LOCATION = "PR4000" !CDS_LOCATION = "PR4000" &SEC = "1" #&CDS_SEC = "1";
"A":   PN = "1"  !CDS_PN = "1";
"B":   PN = "2"  !CDS_PN = "2";
BODY = "Q_RES","I72": #LOCATION = "PR4008" !CDS_LOCATION = "PR4008" &SEC = "1" #&CDS_SEC = "1";
"A":   PN = "1"  !CDS_PN = "1";
"B":   PN = "2"  !CDS_PN = "2";
BODY = "Q_RES","I12": #LOCATION = "PR4540" !CDS_LOCATION = "PR4540" &SEC = "1" #&CDS_SEC = "1";
"A":   PN = "1"  !CDS_PN = "1";
"B":   PN = "2"  !CDS_PN = "2";
BODY = "Q_RES","I14": LOCATION = "R3998" #&CDS_LOCATION = "R3998" &SEC = "1" #&CDS_SEC = "1";
"A":   PN = "1"  !CDS_PN = "1";
"B":   PN = "2"  !CDS_PN = "2";
BODY = "Q_RES","I17": LOCATION = "R3996" #&CDS_LOCATION = "R3996" &SEC = "1" #&CDS_SEC = "1";
"A":   PN = "1"  !CDS_PN = "1";
"B":   PN = "2"  !CDS_PN = "2";
BODY = "Q_RES","I18": LOCATION = "R1857" #&CDS_LOCATION = "R1857" &SEC = "1" #&CDS_SEC = "1";
"A":   PN = "1"  !CDS_PN = "1";
"B":   PN = "2"  !CDS_PN = "2";
BODY = "MOSFET_NCH_DUAL","I21": LOCATION = "Q125" #&CDS_LOCATION = "Q125" &SEC = "1" #&CDS_SEC = "1";
"D1":   PN = "6"  !CDS_PN = "6";
"G1":   PN = "2"  !CDS_PN = "2";
"S1":   PN = "1"  !CDS_PN = "1";
BODY = "Q_RES","I34": #LOCATION = "PR4005" !CDS_LOCATION = "PR4005" &SEC = "1" #&CDS_SEC = "1";
"A":   PN = "1"  !CDS_PN = "1";
"B":   PN = "2"  !CDS_PN = "2";
BODY = "Q_CAP","I37": #LOCATION = "PC2231" !CDS_LOCATION = "PC2231" &SEC = "1" #&CDS_SEC = "1";
"A":   PN = "1"  !CDS_PN = "1";
"B":   PN = "2"  !CDS_PN = "2";
BODY = "Q_CAP","I42": #LOCATION = "PC2235" !CDS_LOCATION = "PC2235" &SEC = "1" #&CDS_SEC = "1";
"A":   PN = "1"  !CDS_PN = "1";
"B":   PN = "2"  !CDS_PN = "2";
BODY = "Q_RES","I48": #LOCATION = "PR4007" !CDS_LOCATION = "PR4007" &SEC = "1" #&CDS_SEC = "1";
"A":   PN = "1"  !CDS_PN = "1";
"B":   PN = "2"  !CDS_PN = "2";
BODY = "Q_RES","I50": #LOCATION = "PR4011" !CDS_LOCATION = "PR4011" &SEC = "1" #&CDS_SEC = "1";
"A":   PN = "1"  !CDS_PN = "1";
"B":   PN = "2"  !CDS_PN = "2";
BODY = "Q_RES","I2": LOCATION = "R1854" #&CDS_LOCATION = "R1854" &SEC = "1" #&CDS_SEC = "1";
"A":   PN = "1"  !CDS_PN = "1";
"B":   PN = "2"  !CDS_PN = "2";
BODY = "Q_RES","I3": LOCATION = "R1856" #&CDS_LOCATION = "R1856" &SEC = "1" #&CDS_SEC = "1";
"A":   PN = "1"  !CDS_PN = "1";
"B":   PN = "2"  !CDS_PN = "2";
BODY = "Q_CAP","I8": #LOCATION = "PC2229" !CDS_LOCATION = "PC2229" &SEC = "1" #&CDS_SEC = "1";
"A":   PN = "1"  !CDS_PN = "1";
"B":   PN = "2"  !CDS_PN = "2";
BODY = "Q_RES","I11": #LOCATION = "PR3999" !CDS_LOCATION = "PR3999" &SEC = "1" #&CDS_SEC = "1";
"A":   PN = "1"  !CDS_PN = "1";
"B":   PN = "2"  !CDS_PN = "2";
BODY = "Q_RES","I20": LOCATION = "R4062" #&CDS_LOCATION = "R4062" &SEC = "1" #&CDS_SEC = "1";
"A":   PN = "1"  !CDS_PN = "1";
"B":   PN = "2"  !CDS_PN = "2";
BODY = "Q_RES","I27": LOCATION = "R3997" #&CDS_LOCATION = "R3997" &SEC = "1" #&CDS_SEC = "1";
"A":   PN = "1"  !CDS_PN = "1";
"B":   PN = "2"  !CDS_PN = "2";
BODY = "DIODE_TVS","I29": #LOCATION = "PD115" !CDS_LOCATION = "PD115" &SEC = "1" #&CDS_SEC = "1";
"A":   PN = "A"  !CDS_PN = "A";
"C":   PN = "C"  !CDS_PN = "C";
BODY = "Q_CAP","I31": #LOCATION = "PC2230" !CDS_LOCATION = "PC2230" &SEC = "1" #&CDS_SEC = "1";
"A":   PN = "1"  !CDS_PN = "1";
"B":   PN = "2"  !CDS_PN = "2";
BODY = "Q_CAP","I33": #LOCATION = "PC2232" !CDS_LOCATION = "PC2232" &SEC = "1" #&CDS_SEC = "1";
"A":   PN = "1"  !CDS_PN = "1";
"B":   PN = "2"  !CDS_PN = "2";
BODY = "Q_RES","I51": #LOCATION = "PR4009" !CDS_LOCATION = "PR4009" &SEC = "1" #&CDS_SEC = "1";
"A":   PN = "1"  !CDS_PN = "1";
"B":   PN = "2"  !CDS_PN = "2";
BODY = "Q_RES","I52": #LOCATION = "PR4010" !CDS_LOCATION = "PR4010" &SEC = "1" #&CDS_SEC = "1";
"A":   PN = "1"  !CDS_PN = "1";
"B":   PN = "2"  !CDS_PN = "2";
BODY = "Q_CAP","I53": #LOCATION = "PC2239" !CDS_LOCATION = "PC2239" &SEC = "1" #&CDS_SEC = "1";
"A":   PN = "1"  !CDS_PN = "1";
"B":   PN = "2"  !CDS_PN = "2";
BODY = "Q_CAP","I66": #LOCATION = "PC2234" !CDS_LOCATION = "PC2234" &SEC = "1" #&CDS_SEC = "1";
"A":   PN = "1"  !CDS_PN = "1";
"B":   PN = "2"  !CDS_PN = "2";
BODY = "Q_CAP","I68": #LOCATION = "PC2233" !CDS_LOCATION = "PC2233" &SEC = "1" #&CDS_SEC = "1";
"A":   PN = "1"  !CDS_PN = "1";
"B":   PN = "2"  !CDS_PN = "2";
BODY = "Q_CAP","I73": #LOCATION = "PC2236" !CDS_LOCATION = "PC2236" &SEC = "1" #&CDS_SEC = "1";
"A":   PN = "1"  !CDS_PN = "1";
"B":   PN = "2"  !CDS_PN = "2";
BODY = "Q_RES","I74": #LOCATION = "PR4012" !CDS_LOCATION = "PR4012" &SEC = "1" #&CDS_SEC = "1";
"A":   PN = "1"  !CDS_PN = "1";
"B":   PN = "2"  !CDS_PN = "2";
BODY = "Q_RES","I79": #LOCATION = "R4013" !CDS_LOCATION = "R4013" &SEC = "1" #&CDS_SEC = "1";
"A":   PN = "1"  !CDS_PN = "1";
"B":   PN = "2"  !CDS_PN = "2";
BODY = "Q_RES","I81": #LOCATION = "R4015" !CDS_LOCATION = "R4015" &SEC = "1" #&CDS_SEC = "1";
"A":   PN = "1"  !CDS_PN = "1";
"B":   PN = "2"  !CDS_PN = "2";
BODY = "Q_CAP","I7": #LOCATION = "PC2340" !CDS_LOCATION = "PC2340" &SEC = "1" #&CDS_SEC = "1";
"A":   PN = "1"  !CDS_PN = "1";
"B":   PN = "2"  !CDS_PN = "2";
BODY = "Q_RES","I70": #LOCATION = "PR4003" !CDS_LOCATION = "PR4003" &SEC = "1" #&CDS_SEC = "1";
"A":   PN = "1"  !CDS_PN = "1";
"B":   PN = "2"  !CDS_PN = "2";
BODY = "Q_RES","I76": #LOCATION = "PR4526" !CDS_LOCATION = "PR4526" &SEC = "1" #&CDS_SEC = "1";
"A":   PN = "1"  !CDS_PN = "1";
"B":   PN = "2"  !CDS_PN = "2";
BODY = "Q_CAP","I83": #LOCATION = "PC2238" !CDS_LOCATION = "PC2238" &SEC = "1" #&CDS_SEC = "1";
"A":   PN = "1"  !CDS_PN = "1";
"B":   PN = "2"  !CDS_PN = "2";
BODY = "MOSFET_NCH_GDS_ESD_PROTECTED","I9": LOCATION = "Q39" #&CDS_LOCATION = "Q39" &SEC = "1" #&CDS_SEC = "1";
"D":   PN = "D"  !CDS_PN = "D";
"G":   PN = "G"  !CDS_PN = "G";
"S":   PN = "S"  !CDS_PN = "S";
BODY = "Q_RES","I24": LOCATION = "R4071" #&CDS_LOCATION = "R4071" &SEC = "1" #&CDS_SEC = "1";
"A":   PN = "1"  !CDS_PN = "1";
"B":   PN = "2"  !CDS_PN = "2";
BODY = "MOSFET_NCH_DUAL","I26": LOCATION = "Q125" #&CDS_LOCATION = "Q125" &SEC = "2" #&CDS_SEC = "2";
"D2":   PN = "3"  !CDS_PN = "3";
"G2":   PN = "5"  !CDS_PN = "5";
"S2":   PN = "4"  !CDS_PN = "4";
BODY = "Q_RES","I39": #LOCATION = "PR4006" !CDS_LOCATION = "PR4006" &SEC = "1" #&CDS_SEC = "1";
"A":   PN = "1"  !CDS_PN = "1";
"B":   PN = "2"  !CDS_PN = "2";
BODY = "Q_RES","I44": LOCATION = "R4709" #&CDS_LOCATION = "R4709" &SEC = "1" #&CDS_SEC = "1";
"A":   PN = "1"  !CDS_PN = "1";
"B":   PN = "2"  !CDS_PN = "2";
BODY = "Q_RES","I54": #LOCATION = "PR4014" !CDS_LOCATION = "PR4014" &SEC = "1" #&CDS_SEC = "1";
"A":   PN = "1"  !CDS_PN = "1";
"B":   PN = "2"  !CDS_PN = "2";
BODY = "Q_CAP","I57": #LOCATION = "PC2241" !CDS_LOCATION = "PC2241" &SEC = "1" #&CDS_SEC = "1";
"A":   PN = "1"  !CDS_PN = "1";
"B":   PN = "2"  !CDS_PN = "2";
BODY = "Q_RES","I61": #LOCATION = "PR4002" !CDS_LOCATION = "PR4002" &SEC = "1" #&CDS_SEC = "1";
"A":   PN = "1"  !CDS_PN = "1";
"B":   PN = "2"  !CDS_PN = "2";
BODY = "Q_RES","I64": #LOCATION = "PR4001" !CDS_LOCATION = "PR4001" &SEC = "1" #&CDS_SEC = "1";
"A":   PN = "1"  !CDS_PN = "1";
"B":   PN = "2"  !CDS_PN = "2";
BODY = "MAX15090BEWIT","I69": #LOCATION = "PU300" !CDS_LOCATION = "PU300" &SEC = "1" #&CDS_SEC = "1";
"CB":   PN = "B1"  !CDS_PN = "B1";
"CDLY":   PN = "A7"  !CDS_PN = "A7";
"EN#":   PN = "B7"  !CDS_PN = "B7";
"FAULT#":   PN = "C7"  !CDS_PN = "C7";
"GATE":   PN = "A6"  !CDS_PN = "A6";
"GND_B2":   PN = "B2"  !CDS_PN = "B2";
"GND_C1":   PN = "C1"  !CDS_PN = "C1";
"GND_C2":   PN = "C2"  !CDS_PN = "C2";
"IN_A3":   PN = "A3"  !CDS_PN = "A3";
"IN_A5":   PN = "A5"  !CDS_PN = "A5";
"IN_B3":   PN = "B3"  !CDS_PN = "B3";
"IN_B5":   PN = "B5"  !CDS_PN = "B5";
"IN_C3":   PN = "C3"  !CDS_PN = "C3";
"IN_C5":   PN = "C5"  !CDS_PN = "C5";
"IN_D5":   PN = "D5"  !CDS_PN = "D5";
"ISENSE":   PN = "A1"  !CDS_PN = "A1";
"OUT_A4":   PN = "A4"  !CDS_PN = "A4";
"OUT_B4":   PN = "B4"  !CDS_PN = "B4";
"OUT_B6":   PN = "B6"  !CDS_PN = "B6";
"OUT_C4":   PN = "C4"  !CDS_PN = "C4";
"OUT_C6":   PN = "C6"  !CDS_PN = "C6";
"OUT_D4":   PN = "D4"  !CDS_PN = "D4";
"OUT_D6":   PN = "D6"  !CDS_PN = "D6";
"OV":   PN = "D3"  !CDS_PN = "D3";
"PG":   PN = "D7"  !CDS_PN = "D7";
"REG":   PN = "D1"  !CDS_PN = "D1";
"UV":   PN = "D2"  !CDS_PN = "D2";
"VCC":   PN = "A2"  !CDS_PN = "A2";
BODY = "Q_CAP","I75": #LOCATION = "PC2237" !CDS_LOCATION = "PC2237" &SEC = "1" #&CDS_SEC = "1";
"A":   PN = "1"  !CDS_PN = "1";
"B":   PN = "2"  !CDS_PN = "2";
BODY = "Q_RES","I77": LOCATION = "R4708" #&CDS_LOCATION = "R4708" &SEC = "1" #&CDS_SEC = "1";
"A":   PN = "1"  !CDS_PN = "1";
"B":   PN = "2"  !CDS_PN = "2";
BODY = "SCHOTTKY_AC","I82": #LOCATION = "PD116" !CDS_LOCATION = "PD116" &SEC = "1" #&CDS_SEC = "1";
"A":   PN = "A"  !CDS_PN = "A";
"C":   PN = "C"  !CDS_PN = "C";
BODY = "Q_CAP","I84": #LOCATION = "PC2240" !CDS_LOCATION = "PC2240" &SEC = "1" #&CDS_SEC = "1";
"A":   PN = "1"  !CDS_PN = "1";
"B":   PN = "2"  !CDS_PN = "2";
BODY = "Q_CAP","I88": #LOCATION = "PC2242" !CDS_LOCATION = "PC2242" &SEC = "1" #&CDS_SEC = "1";
"A":   PN = "1"  !CDS_PN = "1";
"B":   PN = "2"  !CDS_PN = "2";
BODY = "RS31312R","I90": #LOCATION = "PU299" !CDS_LOCATION = "PU299" &SEC = "1" #&CDS_SEC = "1";
"AVIN":   PN = "12"  !CDS_PN = "12";
"EN":   PN = "1"  !CDS_PN = "1";
"ENTM":   PN = "3"  !CDS_PN = "3";
"FLTB":   PN = "9"  !CDS_PN = "9";
"GND":   PN = "7"  !CDS_PN = "7";
"IMON":   PN = "8"  !CDS_PN = "8";
"ISET":   PN = "5"  !CDS_PN = "5";
"LOADEN":   PN = "2"  !CDS_PN = "2";
"OV":   PN = "11"  !CDS_PN = "11";
"PG":   PN = "10"  !CDS_PN = "10";
"SS":   PN = "6"  !CDS_PN = "6";
"TIMER":   PN = "4"  !CDS_PN = "4";
"VIN_21_22":   PN = "21_22"  !CDS_PN = "21_22";
"VIN_23":   PN = "23"  !CDS_PN = "23";
"VIN_24":   PN = "24"  !CDS_PN = "24";
"VIN_25":   PN = "25"  !CDS_PN = "25";
"VIN_26":   PN = "26"  !CDS_PN = "26";
"VOUT_13":   PN = "13"  !CDS_PN = "13";
"VOUT_14":   PN = "14"  !CDS_PN = "14";
"VOUT_15":   PN = "15"  !CDS_PN = "15";
"VOUT_16":   PN = "16"  !CDS_PN = "16";
"VOUT_17":   PN = "17"  !CDS_PN = "17";
"VOUT_18":   PN = "18"  !CDS_PN = "18";
"VOUT_19":   PN = "19"  !CDS_PN = "19";
"VOUT_20":   PN = "20"  !CDS_PN = "20";
BODY = "Q_RES","I91": LOCATION = "R4770" #&CDS_LOCATION = "R4770" &SEC = "1" #&CDS_SEC = "1";
"A":   PN = "1"  !CDS_PN = "1";
"B":   PN = "2"  !CDS_PN = "2";
BODY = "Q_RES","I92": #LOCATION = "R3836" !CDS_LOCATION = "R3836" &SEC = "1" #&CDS_SEC = "1";
"A":   PN = "1"  !CDS_PN = "1";
"B":   PN = "2"  !CDS_PN = "2";
DRAWING = "@s9s_mb_2u_lib.s9s_mb_2u(sch_1):page321";
BODY = "Q_RES","I77": LOCATION = "R4029" #&CDS_LOCATION = "R4029" &SEC = "1" #&CDS_SEC = "1";
"A":   PN = "1"  !CDS_PN = "1";
"B":   PN = "2"  !CDS_PN = "2";
BODY = "Q_RES","I78": LOCATION = "R4021" #&CDS_LOCATION = "R4021" &SEC = "1" #&CDS_SEC = "1";
"A":   PN = "1"  !CDS_PN = "1";
"B":   PN = "2"  !CDS_PN = "2";
BODY = "Q_RES","I79": LOCATION = "R4022" #&CDS_LOCATION = "R4022" &SEC = "1" #&CDS_SEC = "1";
"A":   PN = "1"  !CDS_PN = "1";
"B":   PN = "2"  !CDS_PN = "2";
BODY = "Q_RES","I80": LOCATION = "R4023" #&CDS_LOCATION = "R4023" &SEC = "1" #&CDS_SEC = "1";
"A":   PN = "1"  !CDS_PN = "1";
"B":   PN = "2"  !CDS_PN = "2";
BODY = "Q_CAP","I83": LOCATION = "C2249" #&CDS_LOCATION = "C2249" &SEC = "1" #&CDS_SEC = "1";
"A":   PN = "1"  !CDS_PN = "1";
"B":   PN = "2"  !CDS_PN = "2";
BODY = "Q_CAP","I85": LOCATION = "C2243" #&CDS_LOCATION = "C2243" &SEC = "1" #&CDS_SEC = "1";
"A":   PN = "1"  !CDS_PN = "1";
"B":   PN = "2"  !CDS_PN = "2";
BODY = "GTL2014PW","I91": LOCATION = "U301" #&CDS_LOCATION = "U301" #SEC = "1" !CDS_SEC = "1";
"A0":   PN = "13"  !CDS_PN = "13";
"A1":   PN = "12"  !CDS_PN = "12";
"A2":   PN = "10"  !CDS_PN = "10";
"A3":   PN = "9"  !CDS_PN = "9";
"B0":   PN = "2"  !CDS_PN = "2";
"B1":   PN = "3"  !CDS_PN = "3";
"B2":   PN = "5"  !CDS_PN = "5";
"B3":   PN = "6"  !CDS_PN = "6";
"DIR":   PN = "1"  !CDS_PN = "1";
"GND_0":   PN = "7"  !CDS_PN = "7";
"GND_1":   PN = "8"  !CDS_PN = "8";
"GND_2":   PN = "11"  !CDS_PN = "11";
"VCC":   PN = "14"  !CDS_PN = "14";
"VREF":   PN = "4"  !CDS_PN = "4";
BODY = "Q_RES","I97": #LOCATION = "R4016" !CDS_LOCATION = "R4016" &SEC = "1" #&CDS_SEC = "1";
"A":   PN = "1"  !CDS_PN = "1";
"B":   PN = "2"  !CDS_PN = "2";
BODY = "Q_RES","I98": #LOCATION = "R4019" !CDS_LOCATION = "R4019" &SEC = "1" #&CDS_SEC = "1";
"A":   PN = "1"  !CDS_PN = "1";
"B":   PN = "2"  !CDS_PN = "2";
BODY = "Q_RES","I101": LOCATION = "R4621" #&CDS_LOCATION = "R4621" &SEC = "1" #&CDS_SEC = "1";
"A":   PN = "1"  !CDS_PN = "1";
"B":   PN = "2"  !CDS_PN = "2";
DRAWING = "@s9s_mb_2u_lib.s9s_mb_2u(sch_1):page322";
BODY = "Q_CAP","I9": LOCATION = "C2246" #&CDS_LOCATION = "C2246" &SEC = "1" #&CDS_SEC = "1";
"A":   PN = "1"  !CDS_PN = "1";
"B":   PN = "2"  !CDS_PN = "2";
BODY = "GTL2014PW","I27": LOCATION = "U304" #&CDS_LOCATION = "U304" #SEC = "1" !CDS_SEC = "1";
"A0":   PN = "13"  !CDS_PN = "13";
"A1":   PN = "12"  !CDS_PN = "12";
"A2":   PN = "10"  !CDS_PN = "10";
"A3":   PN = "9"  !CDS_PN = "9";
"B0":   PN = "2"  !CDS_PN = "2";
"B1":   PN = "3"  !CDS_PN = "3";
"B2":   PN = "5"  !CDS_PN = "5";
"B3":   PN = "6"  !CDS_PN = "6";
"DIR":   PN = "1"  !CDS_PN = "1";
"GND_0":   PN = "7"  !CDS_PN = "7";
"GND_1":   PN = "8"  !CDS_PN = "8";
"GND_2":   PN = "11"  !CDS_PN = "11";
"VCC":   PN = "14"  !CDS_PN = "14";
"VREF":   PN = "4"  !CDS_PN = "4";
BODY = "Q_RES","I36": LOCATION = "R4045" #&CDS_LOCATION = "R4045" &SEC = "1" #&CDS_SEC = "1";
"A":   PN = "1"  !CDS_PN = "1";
"B":   PN = "2"  !CDS_PN = "2";
BODY = "Q_RES","I37": LOCATION = "R4044" #&CDS_LOCATION = "R4044" &SEC = "1" #&CDS_SEC = "1";
"A":   PN = "1"  !CDS_PN = "1";
"B":   PN = "2"  !CDS_PN = "2";
BODY = "Q_RES","I38": LOCATION = "R4043" #&CDS_LOCATION = "R4043" &SEC = "1" #&CDS_SEC = "1";
"A":   PN = "1"  !CDS_PN = "1";
"B":   PN = "2"  !CDS_PN = "2";
BODY = "Q_RES","I39": LOCATION = "R4042" #&CDS_LOCATION = "R4042" &SEC = "1" #&CDS_SEC = "1";
"A":   PN = "1"  !CDS_PN = "1";
"B":   PN = "2"  !CDS_PN = "2";
BODY = "GTL2014PW","I44": LOCATION = "U305" #&CDS_LOCATION = "U305" #SEC = "1" !CDS_SEC = "1";
"A0":   PN = "13"  !CDS_PN = "13";
"A1":   PN = "12"  !CDS_PN = "12";
"A2":   PN = "10"  !CDS_PN = "10";
"A3":   PN = "9"  !CDS_PN = "9";
"B0":   PN = "2"  !CDS_PN = "2";
"B1":   PN = "3"  !CDS_PN = "3";
"B2":   PN = "5"  !CDS_PN = "5";
"B3":   PN = "6"  !CDS_PN = "6";
"DIR":   PN = "1"  !CDS_PN = "1";
"GND_0":   PN = "7"  !CDS_PN = "7";
"GND_1":   PN = "8"  !CDS_PN = "8";
"GND_2":   PN = "11"  !CDS_PN = "11";
"VCC":   PN = "14"  !CDS_PN = "14";
"VREF":   PN = "4"  !CDS_PN = "4";
BODY = "Q_RES","I52": LOCATION = "R4046" #&CDS_LOCATION = "R4046" &SEC = "1" #&CDS_SEC = "1";
"A":   PN = "1"  !CDS_PN = "1";
"B":   PN = "2"  !CDS_PN = "2";
BODY = "Q_RES","I53": LOCATION = "R4047" #&CDS_LOCATION = "R4047" &SEC = "1" #&CDS_SEC = "1";
"A":   PN = "1"  !CDS_PN = "1";
"B":   PN = "2"  !CDS_PN = "2";
BODY = "Q_RES","I54": LOCATION = "R4049" #&CDS_LOCATION = "R4049" &SEC = "1" #&CDS_SEC = "1";
"A":   PN = "1"  !CDS_PN = "1";
"B":   PN = "2"  !CDS_PN = "2";
BODY = "Q_RES","I55": LOCATION = "R4048" #&CDS_LOCATION = "R4048" &SEC = "1" #&CDS_SEC = "1";
"A":   PN = "1"  !CDS_PN = "1";
"B":   PN = "2"  !CDS_PN = "2";
BODY = "Q_CAP","I59": LOCATION = "C2247" #&CDS_LOCATION = "C2247" &SEC = "1" #&CDS_SEC = "1";
"A":   PN = "1"  !CDS_PN = "1";
"B":   PN = "2"  !CDS_PN = "2";
BODY = "Q_RES","I66": LOCATION = "R4053" #&CDS_LOCATION = "R4053" &SEC = "1" #&CDS_SEC = "1";
"A":   PN = "1"  !CDS_PN = "1";
"B":   PN = "2"  !CDS_PN = "2";
BODY = "Q_RES","I67": LOCATION = "R4054" #&CDS_LOCATION = "R4054" &SEC = "1" #&CDS_SEC = "1";
"A":   PN = "1"  !CDS_PN = "1";
"B":   PN = "2"  !CDS_PN = "2";
BODY = "GTL2014PW","I80": LOCATION = "U306" #&CDS_LOCATION = "U306" #SEC = "1" !CDS_SEC = "1";
"A0":   PN = "13"  !CDS_PN = "13";
"A1":   PN = "12"  !CDS_PN = "12";
"A2":   PN = "10"  !CDS_PN = "10";
"A3":   PN = "9"  !CDS_PN = "9";
"B0":   PN = "2"  !CDS_PN = "2";
"B1":   PN = "3"  !CDS_PN = "3";
"B2":   PN = "5"  !CDS_PN = "5";
"B3":   PN = "6"  !CDS_PN = "6";
"DIR":   PN = "1"  !CDS_PN = "1";
"GND_0":   PN = "7"  !CDS_PN = "7";
"GND_1":   PN = "8"  !CDS_PN = "8";
"GND_2":   PN = "11"  !CDS_PN = "11";
"VCC":   PN = "14"  !CDS_PN = "14";
"VREF":   PN = "4"  !CDS_PN = "4";
BODY = "Q_CAP","I83": LOCATION = "C2248" #&CDS_LOCATION = "C2248" &SEC = "1" #&CDS_SEC = "1";
"A":   PN = "1"  !CDS_PN = "1";
"B":   PN = "2"  !CDS_PN = "2";
BODY = "Q_RES","I91": LOCATION = "R4055" #&CDS_LOCATION = "R4055" &SEC = "1" #&CDS_SEC = "1";
"A":   PN = "1"  !CDS_PN = "1";
"B":   PN = "2"  !CDS_PN = "2";
BODY = "Q_RES","I94": LOCATION = "R4051" #&CDS_LOCATION = "R4051" &SEC = "1" #&CDS_SEC = "1";
"A":   PN = "1"  !CDS_PN = "1";
"B":   PN = "2"  !CDS_PN = "2";
BODY = "Q_CAP","I101": LOCATION = "C2252" #&CDS_LOCATION = "C2252" &SEC = "1" #&CDS_SEC = "1";
"A":   PN = "1"  !CDS_PN = "1";
"B":   PN = "2"  !CDS_PN = "2";
BODY = "Q_CAP","I106": LOCATION = "C2253" #&CDS_LOCATION = "C2253" &SEC = "1" #&CDS_SEC = "1";
"A":   PN = "1"  !CDS_PN = "1";
"B":   PN = "2"  !CDS_PN = "2";
BODY = "Q_CAP","I111": LOCATION = "C2254" #&CDS_LOCATION = "C2254" &SEC = "1" #&CDS_SEC = "1";
"A":   PN = "1"  !CDS_PN = "1";
"B":   PN = "2"  !CDS_PN = "2";
BODY = "Q_RES","I128": #LOCATION = "R4036" !CDS_LOCATION = "R4036" &SEC = "1" #&CDS_SEC = "1";
"A":   PN = "1"  !CDS_PN = "1";
"B":   PN = "2"  !CDS_PN = "2";
BODY = "Q_RES","I129": #LOCATION = "R4039" !CDS_LOCATION = "R4039" &SEC = "1" #&CDS_SEC = "1";
"A":   PN = "1"  !CDS_PN = "1";
"B":   PN = "2"  !CDS_PN = "2";
BODY = "Q_RES","I130": #LOCATION = "R4037" !CDS_LOCATION = "R4037" &SEC = "1" #&CDS_SEC = "1";
"A":   PN = "1"  !CDS_PN = "1";
"B":   PN = "2"  !CDS_PN = "2";
BODY = "Q_RES","I131": #LOCATION = "R4040" !CDS_LOCATION = "R4040" &SEC = "1" #&CDS_SEC = "1";
"A":   PN = "1"  !CDS_PN = "1";
"B":   PN = "2"  !CDS_PN = "2";
BODY = "Q_RES","I157": LOCATION = "R344" #&CDS_LOCATION = "R344" &SEC = "1" #&CDS_SEC = "1";
"A":   PN = "1"  !CDS_PN = "1";
"B":   PN = "2"  !CDS_PN = "2";
BODY = "Q_RES","I158": LOCATION = "R345" #&CDS_LOCATION = "R345" &SEC = "1" #&CDS_SEC = "1";
"A":   PN = "1"  !CDS_PN = "1";
"B":   PN = "2"  !CDS_PN = "2";
BODY = "Q_RES","I159": LOCATION = "R336" #&CDS_LOCATION = "R336" &SEC = "1" #&CDS_SEC = "1";
"A":   PN = "1"  !CDS_PN = "1";
"B":   PN = "2"  !CDS_PN = "2";
BODY = "Q_RES","I160": LOCATION = "R337" #&CDS_LOCATION = "R337" &SEC = "1" #&CDS_SEC = "1";
"A":   PN = "1"  !CDS_PN = "1";
"B":   PN = "2"  !CDS_PN = "2";
BODY = "Q_RES","I163": LOCATION = "R341" #&CDS_LOCATION = "R341" &SEC = "1" #&CDS_SEC = "1";
"A":   PN = "1"  !CDS_PN = "1";
"B":   PN = "2"  !CDS_PN = "2";
BODY = "Q_RES","I164": LOCATION = "R340" #&CDS_LOCATION = "R340" &SEC = "1" #&CDS_SEC = "1";
"A":   PN = "1"  !CDS_PN = "1";
"B":   PN = "2"  !CDS_PN = "2";
BODY = "Q_RES","I169": LOCATION = "R4390" #&CDS_LOCATION = "R4390" &SEC = "1" #&CDS_SEC = "1";
"A":   PN = "1"  !CDS_PN = "1";
"B":   PN = "2"  !CDS_PN = "2";
BODY = "Q_RES","I171": #LOCATION = "R346" !CDS_LOCATION = "R346" &SEC = "1" #&CDS_SEC = "1";
"A":   PN = "1"  !CDS_PN = "1";
"B":   PN = "2"  !CDS_PN = "2";
BODY = "Q_RES","I172": #LOCATION = "R342" !CDS_LOCATION = "R342" &SEC = "1" #&CDS_SEC = "1";
"A":   PN = "1"  !CDS_PN = "1";
"B":   PN = "2"  !CDS_PN = "2";
BODY = "Q_RES","I173": #LOCATION = "R338" !CDS_LOCATION = "R338" &SEC = "1" #&CDS_SEC = "1";
"A":   PN = "1"  !CDS_PN = "1";
"B":   PN = "2"  !CDS_PN = "2";
BODY = "Q_RES","I174": LOCATION = "R4388" #&CDS_LOCATION = "R4388" &SEC = "1" #&CDS_SEC = "1";
"A":   PN = "1"  !CDS_PN = "1";
"B":   PN = "2"  !CDS_PN = "2";
BODY = "Q_RES","I177": LOCATION = "R4389" #&CDS_LOCATION = "R4389" &SEC = "1" #&CDS_SEC = "1";
"A":   PN = "1"  !CDS_PN = "1";
"B":   PN = "2"  !CDS_PN = "2";
BODY = "Q_RES","I181": #LOCATION = "R4041" !CDS_LOCATION = "R4041" &SEC = "1" #&CDS_SEC = "1";
"A":   PN = "1"  !CDS_PN = "1";
"B":   PN = "2"  !CDS_PN = "2";
BODY = "Q_RES","I182": #LOCATION = "R4038" !CDS_LOCATION = "R4038" &SEC = "1" #&CDS_SEC = "1";
"A":   PN = "1"  !CDS_PN = "1";
"B":   PN = "2"  !CDS_PN = "2";
BODY = "Q_RES","I183": LOCATION = "R4392" #&CDS_LOCATION = "R4392" &SEC = "1" #&CDS_SEC = "1";
"A":   PN = "1"  !CDS_PN = "1";
"B":   PN = "2"  !CDS_PN = "2";
BODY = "Q_RES","I184": LOCATION = "R4050" #&CDS_LOCATION = "R4050" &SEC = "1" #&CDS_SEC = "1";
"A":   PN = "1"  !CDS_PN = "1";
"B":   PN = "2"  !CDS_PN = "2";
BODY = "Q_RES","I187": LOCATION = "R4052" #&CDS_LOCATION = "R4052" &SEC = "1" #&CDS_SEC = "1";
"A":   PN = "1"  !CDS_PN = "1";
"B":   PN = "2"  !CDS_PN = "2";
BODY = "Q_RES","I188": LOCATION = "R4393" #&CDS_LOCATION = "R4393" &SEC = "1" #&CDS_SEC = "1";
"A":   PN = "1"  !CDS_PN = "1";
"B":   PN = "2"  !CDS_PN = "2";
BODY = "Q_RES","I189": LOCATION = "R4394" #&CDS_LOCATION = "R4394" &SEC = "1" #&CDS_SEC = "1";
"A":   PN = "1"  !CDS_PN = "1";
"B":   PN = "2"  !CDS_PN = "2";
BODY = "Q_RES","I190": LOCATION = "R4391" #&CDS_LOCATION = "R4391" &SEC = "1" #&CDS_SEC = "1";
"A":   PN = "1"  !CDS_PN = "1";
"B":   PN = "2"  !CDS_PN = "2";
DRAWING = "@s9s_mb_2u_lib.s9s_mb_2u(sch_1):page153";
BODY = "Q_RES","I22": #LOCATION = "R1908" !CDS_LOCATION = "R1908" &SEC = "1" #&CDS_SEC = "1";
"A":   PN = "1"  !CDS_PN = "1";
"B":   PN = "2"  !CDS_PN = "2";
BODY = "Q_RES","I45": LOCATION = "R4752" #&CDS_LOCATION = "R4752" &SEC = "1" #&CDS_SEC = "1";
"A":   PN = "1"  !CDS_PN = "1";
"B":   PN = "2"  !CDS_PN = "2";
BODY = "Q_RES","I47": LOCATION = "R1147" #&CDS_LOCATION = "R1147" &SEC = "1" #&CDS_SEC = "1";
"A":   PN = "1"  !CDS_PN = "1";
"B":   PN = "2"  !CDS_PN = "2";
BODY = "Q_RES","I49": LOCATION = "PR5484" #&CDS_LOCATION = "PR5484" &SEC = "1" #&CDS_SEC = "1";
"A":   PN = "1"  !CDS_PN = "1";
"B":   PN = "2"  !CDS_PN = "2";
BODY = "Q_CAP","I54": #LOCATION = "PC2087" !CDS_LOCATION = "PC2087" &SEC = "1" #&CDS_SEC = "1";
"A":   PN = "1"  !CDS_PN = "1";
"B":   PN = "2"  !CDS_PN = "2";
BODY = "Q_CAP","I55": #LOCATION = "PC2085" !CDS_LOCATION = "PC2085" &SEC = "1" #&CDS_SEC = "1";
"A":   PN = "1"  !CDS_PN = "1";
"B":   PN = "2"  !CDS_PN = "2";
BODY = "Q_RES","I70": #LOCATION = "PR3789" !CDS_LOCATION = "PR3789" &SEC = "1" #&CDS_SEC = "1";
"A":   PN = "1"  !CDS_PN = "1";
"B":   PN = "2"  !CDS_PN = "2";
BODY = "Q_RES","I74": LOCATION = "R1150" #&CDS_LOCATION = "R1150" &SEC = "1" #&CDS_SEC = "1";
"A":   PN = "1"  !CDS_PN = "1";
"B":   PN = "2"  !CDS_PN = "2";
BODY = "Q_RES","I76": LOCATION = "R4762" #&CDS_LOCATION = "R4762" &SEC = "1" #&CDS_SEC = "1";
"A":   PN = "1"  !CDS_PN = "1";
"B":   PN = "2"  !CDS_PN = "2";
BODY = "Q_RES","I80": #LOCATION = "PR3781" !CDS_LOCATION = "PR3781" &SEC = "1" #&CDS_SEC = "1";
"A":   PN = "1"  !CDS_PN = "1";
"B":   PN = "2"  !CDS_PN = "2";
BODY = "Q_CAP","I81": #LOCATION = "PC2088" !CDS_LOCATION = "PC2088" &SEC = "1" #&CDS_SEC = "1";
"A":   PN = "1"  !CDS_PN = "1";
"B":   PN = "2"  !CDS_PN = "2";
BODY = "Q_CAP","I93": #LOCATION = "PC2092" !CDS_LOCATION = "PC2092" &SEC = "1" #&CDS_SEC = "1";
"A":   PN = "1"  !CDS_PN = "1";
"B":   PN = "2"  !CDS_PN = "2";
BODY = "Q_CAP","I96": #LOCATION = "PC2082" !CDS_LOCATION = "PC2082" &SEC = "1" #&CDS_SEC = "1";
"A":   PN = "1"  !CDS_PN = "1";
"B":   PN = "2"  !CDS_PN = "2";
BODY = "Q_CAP","I107": #LOCATION = "PC2089" !CDS_LOCATION = "PC2089" &SEC = "1" #&CDS_SEC = "1";
"A":   PN = "1"  !CDS_PN = "1";
"B":   PN = "2"  !CDS_PN = "2";
BODY = "Q_RES","I4": LOCATION = "R4061" #&CDS_LOCATION = "R4061" &SEC = "1" #&CDS_SEC = "1";
"A":   PN = "1"  !CDS_PN = "1";
"B":   PN = "2"  !CDS_PN = "2";
BODY = "MOSFET_NCH_DUAL","I17": LOCATION = "Q123" #&CDS_LOCATION = "Q123" &SEC = "2" #&CDS_SEC = "2";
"D2":   PN = "3"  !CDS_PN = "3";
"G2":   PN = "5"  !CDS_PN = "5";
"S2":   PN = "4"  !CDS_PN = "4";
BODY = "Q_RES","I20": LOCATION = "R4069" #&CDS_LOCATION = "R4069" &SEC = "1" #&CDS_SEC = "1";
"A":   PN = "1"  !CDS_PN = "1";
"B":   PN = "2"  !CDS_PN = "2";
BODY = "74LVC2G07DW7","I23": LOCATION = "U212" #&CDS_LOCATION = "U212" &SEC = "1" #&CDS_SEC = "1";
"1A":   PN = "1"  !CDS_PN = "1";
"1Y":   PN = "6"  !CDS_PN = "6";
"2A":   PN = "3"  !CDS_PN = "3";
"2Y":   PN = "4"  !CDS_PN = "4";
"GND":   PN = "2"  !CDS_PN = "2";
"VCC":   PN = "5"  !CDS_PN = "5";
BODY = "74LVC2G07DW7","I26": LOCATION = "U211" #&CDS_LOCATION = "U211" &SEC = "1" #&CDS_SEC = "1";
"1A":   PN = "1"  !CDS_PN = "1";
"1Y":   PN = "6"  !CDS_PN = "6";
"2A":   PN = "3"  !CDS_PN = "3";
"2Y":   PN = "4"  !CDS_PN = "4";
"GND":   PN = "2"  !CDS_PN = "2";
"VCC":   PN = "5"  !CDS_PN = "5";
BODY = "Q_CAP","I27": LOCATION = "C593" #&CDS_LOCATION = "C593" &SEC = "1" #&CDS_SEC = "1";
"A":   PN = "1"  !CDS_PN = "1";
"B":   PN = "2"  !CDS_PN = "2";
BODY = "DIODE_TVS","I38": #LOCATION = "PD101" !CDS_LOCATION = "PD101" &SEC = "1" #&CDS_SEC = "1";
"A":   PN = "A"  !CDS_PN = "A";
"C":   PN = "C"  !CDS_PN = "C";
BODY = "Q_RES","I41": #LOCATION = "PR3787" !CDS_LOCATION = "PR3787" &SEC = "1" #&CDS_SEC = "1";
"A":   PN = "1"  !CDS_PN = "1";
"B":   PN = "2"  !CDS_PN = "2";
BODY = "Q_RES","I50": LOCATION = "R1149" #&CDS_LOCATION = "R1149" &SEC = "1" #&CDS_SEC = "1";
"A":   PN = "1"  !CDS_PN = "1";
"B":   PN = "2"  !CDS_PN = "2";
BODY = "Q_RES","I58": #LOCATION = "PR3791" !CDS_LOCATION = "PR3791" &SEC = "1" #&CDS_SEC = "1";
"A":   PN = "1"  !CDS_PN = "1";
"B":   PN = "2"  !CDS_PN = "2";
BODY = "Q_RES","I62": LOCATION = "R4070" #&CDS_LOCATION = "R4070" &SEC = "1" #&CDS_SEC = "1";
"A":   PN = "1"  !CDS_PN = "1";
"B":   PN = "2"  !CDS_PN = "2";
BODY = "Q_CAP","I71": #LOCATION = "PC2086" !CDS_LOCATION = "PC2086" &SEC = "1" #&CDS_SEC = "1";
"A":   PN = "1"  !CDS_PN = "1";
"B":   PN = "2"  !CDS_PN = "2";
BODY = "Q_CAP","I72": #LOCATION = "PC2093" !CDS_LOCATION = "PC2093" &SEC = "1" #&CDS_SEC = "1";
"A":   PN = "1"  !CDS_PN = "1";
"B":   PN = "2"  !CDS_PN = "2";
BODY = "Q_RES","I82": #LOCATION = "R3144" !CDS_LOCATION = "R3144" &SEC = "1" #&CDS_SEC = "1";
"A":   PN = "1"  !CDS_PN = "1";
"B":   PN = "2"  !CDS_PN = "2";
BODY = "Q_RES","I87": LOCATION = "R3869" #&CDS_LOCATION = "R3869" &SEC = "1" #&CDS_SEC = "1";
"A":   PN = "1"  !CDS_PN = "1";
"B":   PN = "2"  !CDS_PN = "2";
BODY = "Q_RES","I88": LOCATION = "R3870" #&CDS_LOCATION = "R3870" &SEC = "1" #&CDS_SEC = "1";
"A":   PN = "1"  !CDS_PN = "1";
"B":   PN = "2"  !CDS_PN = "2";
BODY = "Q_RES","I90": #LOCATION = "R3799" !CDS_LOCATION = "R3799" &SEC = "1" #&CDS_SEC = "1";
"A":   PN = "1"  !CDS_PN = "1";
"B":   PN = "2"  !CDS_PN = "2";
BODY = "Q_RES","I92": #LOCATION = "R3797" !CDS_LOCATION = "R3797" &SEC = "1" #&CDS_SEC = "1";
"A":   PN = "1"  !CDS_PN = "1";
"B":   PN = "2"  !CDS_PN = "2";
BODY = "Q_CAP","I101": #LOCATION = "PC2144" !CDS_LOCATION = "PC2144" &SEC = "1" #&CDS_SEC = "1";
"A":   PN = "1"  !CDS_PN = "1";
"B":   PN = "2"  !CDS_PN = "2";
BODY = "Q_RES","I102": LOCATION = "PR5481" #&CDS_LOCATION = "PR5481" &SEC = "1" #&CDS_SEC = "1";
"A":   PN = "1"  !CDS_PN = "1";
"B":   PN = "2"  !CDS_PN = "2";
BODY = "Q_RES","I103": #LOCATION = "PR4525" !CDS_LOCATION = "PR4525" &SEC = "1" #&CDS_SEC = "1";
"A":   PN = "1"  !CDS_PN = "1";
"B":   PN = "2"  !CDS_PN = "2";
BODY = "SCHOTTKY_AC","I104": #LOCATION = "PD103" !CDS_LOCATION = "PD103" &SEC = "1" #&CDS_SEC = "1";
"A":   PN = "A"  !CDS_PN = "A";
"C":   PN = "C"  !CDS_PN = "C";
BODY = "Q_RES","I105": LOCATION = "R3794" #&CDS_LOCATION = "R3794" &SEC = "1" #&CDS_SEC = "1";
"A":   PN = "1"  !CDS_PN = "1";
"B":   PN = "2"  !CDS_PN = "2";
BODY = "Q_RES","I7": #LOCATION = "R1906" !CDS_LOCATION = "R1906" &SEC = "1" #&CDS_SEC = "1";
"A":   PN = "1"  !CDS_PN = "1";
"B":   PN = "2"  !CDS_PN = "2";
BODY = "MOSFET_NCH_DUAL","I9": LOCATION = "Q123" #&CDS_LOCATION = "Q123" &SEC = "1" #&CDS_SEC = "1";
"D1":   PN = "6"  !CDS_PN = "6";
"G1":   PN = "2"  !CDS_PN = "2";
"S1":   PN = "1"  !CDS_PN = "1";
BODY = "Q_RES","I13": #LOCATION = "R1905" !CDS_LOCATION = "R1905" &SEC = "1" #&CDS_SEC = "1";
"A":   PN = "1"  !CDS_PN = "1";
"B":   PN = "2"  !CDS_PN = "2";
BODY = "Q_RES","I15": LOCATION = "R4068" #&CDS_LOCATION = "R4068" &SEC = "1" #&CDS_SEC = "1";
"A":   PN = "1"  !CDS_PN = "1";
"B":   PN = "2"  !CDS_PN = "2";
BODY = "Q_RES","I19": LOCATION = "R5487" #&CDS_LOCATION = "R5487" &SEC = "1" #&CDS_SEC = "1";
"A":   PN = "1"  !CDS_PN = "1";
"B":   PN = "2"  !CDS_PN = "2";
BODY = "MOSFET_NCH_DUAL","I21": LOCATION = "Q124" #&CDS_LOCATION = "Q124" &SEC = "1" #&CDS_SEC = "1";
"D1":   PN = "6"  !CDS_PN = "6";
"G1":   PN = "2"  !CDS_PN = "2";
"S1":   PN = "1"  !CDS_PN = "1";
BODY = "Q_RES","I25": #LOCATION = "R1907" !CDS_LOCATION = "R1907" &SEC = "1" #&CDS_SEC = "1";
"A":   PN = "1"  !CDS_PN = "1";
"B":   PN = "2"  !CDS_PN = "2";
BODY = "Q_CAP","I30": LOCATION = "C592" #&CDS_LOCATION = "C592" &SEC = "1" #&CDS_SEC = "1";
"A":   PN = "1"  !CDS_PN = "1";
"B":   PN = "2"  !CDS_PN = "2";
BODY = "Q_RES","I33": #LOCATION = "PR3788" !CDS_LOCATION = "PR3788" &SEC = "1" #&CDS_SEC = "1";
"A":   PN = "1"  !CDS_PN = "1";
"B":   PN = "2"  !CDS_PN = "2";
BODY = "MOSFET_NCH_DUAL","I36": #LOCATION = "Q124" !CDS_LOCATION = "Q124" &SEC = "2" #&CDS_SEC = "2";
"D2":   PN = "3"  !CDS_PN = "3";
"G2":   PN = "5"  !CDS_PN = "5";
"S2":   PN = "4"  !CDS_PN = "4";
BODY = "Q_RES","I39": LOCATION = "R3784" #&CDS_LOCATION = "R3784" &SEC = "1" #&CDS_SEC = "1";
"A":   PN = "1"  !CDS_PN = "1";
"B":   PN = "2"  !CDS_PN = "2";
BODY = "Q_RES","I42": #LOCATION = "PR3786" !CDS_LOCATION = "PR3786" &SEC = "1" #&CDS_SEC = "1";
"A":   PN = "1"  !CDS_PN = "1";
"B":   PN = "2"  !CDS_PN = "2";
BODY = "Q_CAP","I44": #LOCATION = "PC2079" !CDS_LOCATION = "PC2079" &SEC = "1" #&CDS_SEC = "1";
"A":   PN = "1"  !CDS_PN = "1";
"B":   PN = "2"  !CDS_PN = "2";
BODY = "Q_RES","I46": LOCATION = "R1148" #&CDS_LOCATION = "R1148" &SEC = "1" #&CDS_SEC = "1";
"A":   PN = "1"  !CDS_PN = "1";
"B":   PN = "2"  !CDS_PN = "2";
BODY = "MAX15090BEWIT","I51": #LOCATION = "PU203" !CDS_LOCATION = "PU203" &SEC = "1" #&CDS_SEC = "1";
"CB":   PN = "B1"  !CDS_PN = "B1";
"CDLY":   PN = "A7"  !CDS_PN = "A7";
"EN#":   PN = "B7"  !CDS_PN = "B7";
"FAULT#":   PN = "C7"  !CDS_PN = "C7";
"GATE":   PN = "A6"  !CDS_PN = "A6";
"GND_B2":   PN = "B2"  !CDS_PN = "B2";
"GND_C1":   PN = "C1"  !CDS_PN = "C1";
"GND_C2":   PN = "C2"  !CDS_PN = "C2";
"IN_A3":   PN = "A3"  !CDS_PN = "A3";
"IN_A5":   PN = "A5"  !CDS_PN = "A5";
"IN_B3":   PN = "B3"  !CDS_PN = "B3";
"IN_B5":   PN = "B5"  !CDS_PN = "B5";
"IN_C3":   PN = "C3"  !CDS_PN = "C3";
"IN_C5":   PN = "C5"  !CDS_PN = "C5";
"IN_D5":   PN = "D5"  !CDS_PN = "D5";
"ISENSE":   PN = "A1"  !CDS_PN = "A1";
"OUT_A4":   PN = "A4"  !CDS_PN = "A4";
"OUT_B4":   PN = "B4"  !CDS_PN = "B4";
"OUT_B6":   PN = "B6"  !CDS_PN = "B6";
"OUT_C4":   PN = "C4"  !CDS_PN = "C4";
"OUT_C6":   PN = "C6"  !CDS_PN = "C6";
"OUT_D4":   PN = "D4"  !CDS_PN = "D4";
"OUT_D6":   PN = "D6"  !CDS_PN = "D6";
"OV":   PN = "D3"  !CDS_PN = "D3";
"PG":   PN = "D7"  !CDS_PN = "D7";
"REG":   PN = "D1"  !CDS_PN = "D1";
"UV":   PN = "D2"  !CDS_PN = "D2";
"VCC":   PN = "A2"  !CDS_PN = "A2";
BODY = "Q_RES","I56": #LOCATION = "PR3792" !CDS_LOCATION = "PR3792" &SEC = "1" #&CDS_SEC = "1";
"A":   PN = "1"  !CDS_PN = "1";
"B":   PN = "2"  !CDS_PN = "2";
BODY = "Q_RES","I60": #LOCATION = "PR3780" !CDS_LOCATION = "PR3780" &SEC = "1" #&CDS_SEC = "1";
"A":   PN = "1"  !CDS_PN = "1";
"B":   PN = "2"  !CDS_PN = "2";
BODY = "MAX15090BEWIT","I61": #LOCATION = "PU202" !CDS_LOCATION = "PU202" &SEC = "1" #&CDS_SEC = "1";
"CB":   PN = "B1"  !CDS_PN = "B1";
"CDLY":   PN = "A7"  !CDS_PN = "A7";
"EN#":   PN = "B7"  !CDS_PN = "B7";
"FAULT#":   PN = "C7"  !CDS_PN = "C7";
"GATE":   PN = "A6"  !CDS_PN = "A6";
"GND_B2":   PN = "B2"  !CDS_PN = "B2";
"GND_C1":   PN = "C1"  !CDS_PN = "C1";
"GND_C2":   PN = "C2"  !CDS_PN = "C2";
"IN_A3":   PN = "A3"  !CDS_PN = "A3";
"IN_A5":   PN = "A5"  !CDS_PN = "A5";
"IN_B3":   PN = "B3"  !CDS_PN = "B3";
"IN_B5":   PN = "B5"  !CDS_PN = "B5";
"IN_C3":   PN = "C3"  !CDS_PN = "C3";
"IN_C5":   PN = "C5"  !CDS_PN = "C5";
"IN_D5":   PN = "D5"  !CDS_PN = "D5";
"ISENSE":   PN = "A1"  !CDS_PN = "A1";
"OUT_A4":   PN = "A4"  !CDS_PN = "A4";
"OUT_B4":   PN = "B4"  !CDS_PN = "B4";
"OUT_B6":   PN = "B6"  !CDS_PN = "B6";
"OUT_C4":   PN = "C4"  !CDS_PN = "C4";
"OUT_C6":   PN = "C6"  !CDS_PN = "C6";
"OUT_D4":   PN = "D4"  !CDS_PN = "D4";
"OUT_D6":   PN = "D6"  !CDS_PN = "D6";
"OV":   PN = "D3"  !CDS_PN = "D3";
"PG":   PN = "D7"  !CDS_PN = "D7";
"REG":   PN = "D1"  !CDS_PN = "D1";
"UV":   PN = "D2"  !CDS_PN = "D2";
"VCC":   PN = "A2"  !CDS_PN = "A2";
BODY = "Q_RES","I64": LOCATION = "R3785" #&CDS_LOCATION = "R3785" &SEC = "1" #&CDS_SEC = "1";
"A":   PN = "1"  !CDS_PN = "1";
"B":   PN = "2"  !CDS_PN = "2";
BODY = "Q_CAP","I66": LOCATION = "PC5328" #&CDS_LOCATION = "PC5328" &SEC = "1" #&CDS_SEC = "1";
"A":   PN = "1"  !CDS_PN = "1";
"B":   PN = "2"  !CDS_PN = "2";
BODY = "Q_RES","I68": #LOCATION = "PR3790" !CDS_LOCATION = "PR3790" &SEC = "1" #&CDS_SEC = "1";
"A":   PN = "1"  !CDS_PN = "1";
"B":   PN = "2"  !CDS_PN = "2";
BODY = "Q_RES","I73": #LOCATION = "PR3798" !CDS_LOCATION = "PR3798" &SEC = "1" #&CDS_SEC = "1";
"A":   PN = "1"  !CDS_PN = "1";
"B":   PN = "2"  !CDS_PN = "2";
BODY = "Q_CAP","I83": LOCATION = "PC4056" #&CDS_LOCATION = "PC4056" &SEC = "1" #&CDS_SEC = "1";
"A":   PN = "1"  !CDS_PN = "1";
"B":   PN = "2"  !CDS_PN = "2";
BODY = "Q_RES","I84": #LOCATION = "PR4524" !CDS_LOCATION = "PR4524" &SEC = "1" #&CDS_SEC = "1";
"A":   PN = "1"  !CDS_PN = "1";
"B":   PN = "2"  !CDS_PN = "2";
BODY = "SCHOTTKY_AC","I86": #LOCATION = "PD102" !CDS_LOCATION = "PD102" &SEC = "1" #&CDS_SEC = "1";
"A":   PN = "A"  !CDS_PN = "A";
"C":   PN = "C"  !CDS_PN = "C";
BODY = "Q_CAP","I94": #LOCATION = "PC2080" !CDS_LOCATION = "PC2080" &SEC = "1" #&CDS_SEC = "1";
"A":   PN = "1"  !CDS_PN = "1";
"B":   PN = "2"  !CDS_PN = "2";
BODY = "Q_RES","I108": #LOCATION = "R3796" !CDS_LOCATION = "R3796" &SEC = "1" #&CDS_SEC = "1";
"A":   PN = "1"  !CDS_PN = "1";
"B":   PN = "2"  !CDS_PN = "2";
BODY = "Q_RES","I110": #LOCATION = "R3783" !CDS_LOCATION = "R3783" &SEC = "1" #&CDS_SEC = "1";
"A":   PN = "1"  !CDS_PN = "1";
"B":   PN = "2"  !CDS_PN = "2";
BODY = "Q_CAP","I111": #LOCATION = "PC2091" !CDS_LOCATION = "PC2091" &SEC = "1" #&CDS_SEC = "1";
"A":   PN = "1"  !CDS_PN = "1";
"B":   PN = "2"  !CDS_PN = "2";
BODY = "Q_CAP","I113": #LOCATION = "PC2081" !CDS_LOCATION = "PC2081" &SEC = "1" #&CDS_SEC = "1";
"A":   PN = "1"  !CDS_PN = "1";
"B":   PN = "2"  !CDS_PN = "2";
DRAWING = "@s9s_mb_2u_lib.s9s_mb_2u(sch_1):page246";
BODY = "Q_CAP","I2": LOCATION = "C1172" #&CDS_LOCATION = "C1172" &SEC = "1" #&CDS_SEC = "1";
"A":   PN = "1"  !CDS_PN = "1";
"B":   PN = "2"  !CDS_PN = "2";
BODY = "RT9818C44GV","I4": LOCATION = "U99" #&CDS_LOCATION = "U99" &SEC = "1" #&CDS_SEC = "1";
"GND":   PN = "2"  !CDS_PN = "2";
"RESET#":   PN = "1"  !CDS_PN = "1";
"VDD":   PN = "3"  !CDS_PN = "3";
BODY = "Q_RES","I6": LOCATION = "R1655" #&CDS_LOCATION = "R1655" &SEC = "1" #&CDS_SEC = "1";
"A":   PN = "1"  !CDS_PN = "1";
"B":   PN = "2"  !CDS_PN = "2";
BODY = "Q_RES","I9": LOCATION = "R1640" #&CDS_LOCATION = "R1640" &SEC = "1" #&CDS_SEC = "1";
"A":   PN = "1"  !CDS_PN = "1";
"B":   PN = "2"  !CDS_PN = "2";
BODY = "Q_RES","I10": LOCATION = "R1607" #&CDS_LOCATION = "R1607" &SEC = "1" #&CDS_SEC = "1";
"A":   PN = "1"  !CDS_PN = "1";
"B":   PN = "2"  !CDS_PN = "2";
BODY = "Q_CAP","I11": LOCATION = "C1042" #&CDS_LOCATION = "C1042" &SEC = "1" #&CDS_SEC = "1";
"A":   PN = "1"  !CDS_PN = "1";
"B":   PN = "2"  !CDS_PN = "2";
BODY = "Q_RES","I14": LOCATION = "R1641" #&CDS_LOCATION = "R1641" &SEC = "1" #&CDS_SEC = "1";
"A":   PN = "1"  !CDS_PN = "1";
"B":   PN = "2"  !CDS_PN = "2";
BODY = "Q_RES","I17": LOCATION = "R1643" #&CDS_LOCATION = "R1643" &SEC = "1" #&CDS_SEC = "1";
"A":   PN = "1"  !CDS_PN = "1";
"B":   PN = "2"  !CDS_PN = "2";
BODY = "Q_RES","I22": LOCATION = "R1642" #&CDS_LOCATION = "R1642" &SEC = "1" #&CDS_SEC = "1";
"A":   PN = "1"  !CDS_PN = "1";
"B":   PN = "2"  !CDS_PN = "2";
BODY = "Q_CAP","I24": LOCATION = "C1170" #&CDS_LOCATION = "C1170" &SEC = "1" #&CDS_SEC = "1";
"A":   PN = "1"  !CDS_PN = "1";
"B":   PN = "2"  !CDS_PN = "2";
BODY = "Q_CAP","I25": LOCATION = "C1171" #&CDS_LOCATION = "C1171" &SEC = "1" #&CDS_SEC = "1";
"A":   PN = "1"  !CDS_PN = "1";
"B":   PN = "2"  !CDS_PN = "2";
BODY = "Q_RES","I27": LOCATION = "R1654" #&CDS_LOCATION = "R1654" &SEC = "1" #&CDS_SEC = "1";
"A":   PN = "1"  !CDS_PN = "1";
"B":   PN = "2"  !CDS_PN = "2";
BODY = "MOSFET_NCH_1D3S","I30": #LOCATION = "Q57" !CDS_LOCATION = "Q57" &SEC = "1" #&CDS_SEC = "1";
"1":   PN = "1"  !CDS_PN = "1";
"2":   PN = "2"  !CDS_PN = "2";
"3":   PN = "3"  !CDS_PN = "3";
"4":   PN = "4"  !CDS_PN = "4";
"5":   PN = "5"  !CDS_PN = "5";
BODY = "BAT547F","I32": LOCATION = "D7" #&CDS_LOCATION = "D7" &SEC = "1" #&CDS_SEC = "1";
"1":   PN = "1"  !CDS_PN = "1";
"3":   PN = "3"  !CDS_PN = "3";
BODY = "Q_CAP","I44": LOCATION = "C1227" #&CDS_LOCATION = "C1227" &SEC = "1" #&CDS_SEC = "1";
"A":   PN = "1"  !CDS_PN = "1";
"B":   PN = "2"  !CDS_PN = "2";
BODY = "Q_CAP","I45": LOCATION = "C1331" #&CDS_LOCATION = "C1331" &SEC = "1" #&CDS_SEC = "1";
"A":   PN = "1"  !CDS_PN = "1";
"B":   PN = "2"  !CDS_PN = "2";
BODY = "Q_CAP","I48": LOCATION = "C1332" #&CDS_LOCATION = "C1332" &SEC = "1" #&CDS_SEC = "1";
"A":   PN = "1"  !CDS_PN = "1";
"B":   PN = "2"  !CDS_PN = "2";
BODY = "Q_CAP","I49": LOCATION = "C1333" #&CDS_LOCATION = "C1333" &SEC = "1" #&CDS_SEC = "1";
"A":   PN = "1"  !CDS_PN = "1";
"B":   PN = "2"  !CDS_PN = "2";
BODY = "Q_CAP","I50": LOCATION = "C1338" #&CDS_LOCATION = "C1338" &SEC = "1" #&CDS_SEC = "1";
"A":   PN = "1"  !CDS_PN = "1";
"B":   PN = "2"  !CDS_PN = "2";
BODY = "MOSFET_NCH_1D3S","I51": #LOCATION = "Q56" !CDS_LOCATION = "Q56" &SEC = "1" #&CDS_SEC = "1";
"1":   PN = "1"  !CDS_PN = "1";
"2":   PN = "2"  !CDS_PN = "2";
"3":   PN = "3"  !CDS_PN = "3";
"4":   PN = "4"  !CDS_PN = "4";
"5":   PN = "5"  !CDS_PN = "5";
BODY = "Q_CAP","I58": LOCATION = "C1339" #&CDS_LOCATION = "C1339" &SEC = "1" #&CDS_SEC = "1";
"A":   PN = "1"  !CDS_PN = "1";
"B":   PN = "2"  !CDS_PN = "2";
BODY = "Q_CAP","I61": LOCATION = "C1340" #&CDS_LOCATION = "C1340" &SEC = "1" #&CDS_SEC = "1";
"A":   PN = "1"  !CDS_PN = "1";
"B":   PN = "2"  !CDS_PN = "2";
BODY = "MOSFET_NCH_GDS_ESD_PROTECTED","I67": #LOCATION = "U324" !CDS_LOCATION = "U324" &SEC = "1" #&CDS_SEC = "1";
"D":   PN = "D"  !CDS_PN = "D";
"G":   PN = "G"  !CDS_PN = "G";
"S":   PN = "S"  !CDS_PN = "S";
BODY = "Q_CAP","I68": #LOCATION = "C1226" !CDS_LOCATION = "C1226" &SEC = "1" #&CDS_SEC = "1";
"A":   PN = "1"  !CDS_PN = "1";
"B":   PN = "2"  !CDS_PN = "2";
BODY = "MOSFET_NCH_DUAL","I69": #LOCATION = "Q37" !CDS_LOCATION = "Q37" #SEC = "1" !CDS_SEC = "1";
"D1":   PN = "6"  !CDS_PN = "6";
"G1":   PN = "2"  !CDS_PN = "2";
"S1":   PN = "1"  !CDS_PN = "1";
BODY = "MOSFET_NCH_DUAL","I76": #LOCATION = "Q37" !CDS_LOCATION = "Q37" &SEC = "2" #&CDS_SEC = "2";
"D2":   PN = "3"  !CDS_PN = "3";
"G2":   PN = "5"  !CDS_PN = "5";
"S2":   PN = "4"  !CDS_PN = "4";
BODY = "Q_RES","I77": #LOCATION = "R4638" !CDS_LOCATION = "R4638" &SEC = "1" #&CDS_SEC = "1";
"A":   PN = "1"  !CDS_PN = "1";
"B":   PN = "2"  !CDS_PN = "2";
BODY = "Q_RES","I78": #LOCATION = "R4639" !CDS_LOCATION = "R4639" &SEC = "1" #&CDS_SEC = "1";
"A":   PN = "1"  !CDS_PN = "1";
"B":   PN = "2"  !CDS_PN = "2";
BODY = "Q_RES","I79": #LOCATION = "R4640" !CDS_LOCATION = "R4640" &SEC = "1" #&CDS_SEC = "1";
"A":   PN = "1"  !CDS_PN = "1";
"B":   PN = "2"  !CDS_PN = "2";
BODY = "Q_RES","I80": #LOCATION = "R4641" !CDS_LOCATION = "R4641" &SEC = "1" #&CDS_SEC = "1";
"A":   PN = "1"  !CDS_PN = "1";
"B":   PN = "2"  !CDS_PN = "2";
BODY = "Q_RES","I89": LOCATION = "R1706" #&CDS_LOCATION = "R1706" &SEC = "1" #&CDS_SEC = "1";
"A":   PN = "1"  !CDS_PN = "1";
"B":   PN = "2"  !CDS_PN = "2";
BODY = "Q_RES","I91": LOCATION = "R4677" #&CDS_LOCATION = "R4677" &SEC = "1" #&CDS_SEC = "1";
"A":   PN = "1"  !CDS_PN = "1";
"B":   PN = "2"  !CDS_PN = "2";
BODY = "Q_CAP","I94": LOCATION = "C2359" #&CDS_LOCATION = "C2359" &SEC = "1" #&CDS_SEC = "1";
"A":   PN = "1"  !CDS_PN = "1";
"B":   PN = "2"  !CDS_PN = "2";
BODY = "Q_RES","I96": LOCATION = "R4679" #&CDS_LOCATION = "R4679" &SEC = "1" #&CDS_SEC = "1";
"A":   PN = "1"  !CDS_PN = "1";
"B":   PN = "2"  !CDS_PN = "2";
BODY = "MOSFET_NCH_DUAL","I98": #LOCATION = "Q236" !CDS_LOCATION = "Q236" &SEC = "2" #&CDS_SEC = "2";
"D2":   PN = "3"  !CDS_PN = "3";
"G2":   PN = "5"  !CDS_PN = "5";
"S2":   PN = "4"  !CDS_PN = "4";
BODY = "MOSFET_NCH_DUAL","I99": #LOCATION = "Q236" !CDS_LOCATION = "Q236" &SEC = "1" #&CDS_SEC = "1";
"D1":   PN = "6"  !CDS_PN = "6";
"G1":   PN = "2"  !CDS_PN = "2";
"S1":   PN = "1"  !CDS_PN = "1";
BODY = "Q_RES","I102": LOCATION = "R4680" #&CDS_LOCATION = "R4680" &SEC = "1" #&CDS_SEC = "1";
"A":   PN = "1"  !CDS_PN = "1";
"B":   PN = "2"  !CDS_PN = "2";
BODY = "Q_RES","I104": LOCATION = "R4678" #&CDS_LOCATION = "R4678" &SEC = "1" #&CDS_SEC = "1";
"A":   PN = "1"  !CDS_PN = "1";
"B":   PN = "2"  !CDS_PN = "2";
BODY = "APX80929SAG7","I105": LOCATION = "U330" #&CDS_LOCATION = "U330" &SEC = "1" #&CDS_SEC = "1";
"GND":   PN = "1"  !CDS_PN = "1";
"RESET_L":   PN = "2"  !CDS_PN = "2";
"VCC":   PN = "3"  !CDS_PN = "3";
BODY = "Q_CAP","I107": LOCATION = "C2360" #&CDS_LOCATION = "C2360" &SEC = "1" #&CDS_SEC = "1";
"A":   PN = "1"  !CDS_PN = "1";
"B":   PN = "2"  !CDS_PN = "2";
BODY = "Q_RES","I109": LOCATION = "R4681" #&CDS_LOCATION = "R4681" &SEC = "1" #&CDS_SEC = "1";
"A":   PN = "1"  !CDS_PN = "1";
"B":   PN = "2"  !CDS_PN = "2";
BODY = "Q_RES","I112": LOCATION = "R4682" #&CDS_LOCATION = "R4682" &SEC = "1" #&CDS_SEC = "1";
"A":   PN = "1"  !CDS_PN = "1";
"B":   PN = "2"  !CDS_PN = "2";
DRAWING = "@s9s_mb_2u_lib.s9s_mb_2u(sch_1):page261";
BODY = "ISL99390FRZTR5935","I12": #LOCATION = "PU44_P0_2" !CDS_LOCATION = "PU44_P0_2" #SEC = "1" !CDS_SEC = "1";
"AGND":   PN = "2"  !CDS_PN = "2";
"BOOT":   PN = "33"  !CDS_PN = "33";
"DNC":   PN = "31"  !CDS_PN = "31";
"EN":   PN = "35"  !CDS_PN = "35";
"GL1":   PN = "6"  !CDS_PN = "6";
"GL2":   PN = "41"  !CDS_PN = "41";
"IOUT":   PN = "38"  !CDS_PN = "38";
"LSET":   PN = "37"  !CDS_PN = "37";
"PGND1":   PN = "5"  !CDS_PN = "5";
"PGND2":   PN = "7_9-20_24"  !CDS_PN = "7_9-20_24";
"PGND3":   PN = "40"  !CDS_PN = "40";
"PHASE":   PN = "32"  !CDS_PN = "32";
"PVCC":   PN = "4"  !CDS_PN = "4";
"PWM":   PN = "34"  !CDS_PN = "34";
"REFIN":   PN = "39"  !CDS_PN = "39";
"SW":   PN = "10_19"  !CDS_PN = "10_19";
"TOUT_FLT":   PN = "36"  !CDS_PN = "36";
"VCC":   PN = "3"  !CDS_PN = "3";
"VIN1":   PN = "25_29"  !CDS_PN = "25_29";
"VIN2":   PN = "30"  !CDS_PN = "30";
"VOS":   PN = "1"  !CDS_PN = "1";
BODY = "Q_CAP","I25": #LOCATION = "PC1347" !CDS_LOCATION = "PC1347" &SEC = "1" #&CDS_SEC = "1";
"A":   PN = "1"  !CDS_PN = "1";
"B":   PN = "2"  !CDS_PN = "2";
BODY = "Q_RES","I26": #LOCATION = "PR101" !CDS_LOCATION = "PR101" &SEC = "1" #&CDS_SEC = "1";
"A":   PN = "1"  !CDS_PN = "1";
"B":   PN = "2"  !CDS_PN = "2";
BODY = "Q_RES","I31": #LOCATION = "PR1777" !CDS_LOCATION = "PR1777" &SEC = "1" #&CDS_SEC = "1";
"A":   PN = "1"  !CDS_PN = "1";
"B":   PN = "2"  !CDS_PN = "2";
BODY = "Q_CAP","I32": #LOCATION = "PC190_P0_2" !CDS_LOCATION = "PC190_P0_2" &SEC = "1" #&CDS_SEC = "1";
"A":   PN = "1"  !CDS_PN = "1";
"B":   PN = "2"  !CDS_PN = "2";
BODY = "Q_RES","I34": #LOCATION = "PR1775" !CDS_LOCATION = "PR1775" &SEC = "1" #&CDS_SEC = "1";
"A":   PN = "1"  !CDS_PN = "1";
"B":   PN = "2"  !CDS_PN = "2";
BODY = "Q_CAP","I35": #LOCATION = "PC192_P0_2" !CDS_LOCATION = "PC192_P0_2" &SEC = "1" #&CDS_SEC = "1";
"A":   PN = "1"  !CDS_PN = "1";
"B":   PN = "2"  !CDS_PN = "2";
BODY = "Q_CAP","I36": #LOCATION = "PC196_P0_2" !CDS_LOCATION = "PC196_P0_2" &SEC = "1" #&CDS_SEC = "1";
"A":   PN = "1"  !CDS_PN = "1";
"B":   PN = "2"  !CDS_PN = "2";
BODY = "Q_CAP","I37": #LOCATION = "PC198_P0_2" !CDS_LOCATION = "PC198_P0_2" &SEC = "1" #&CDS_SEC = "1";
"A":   PN = "1"  !CDS_PN = "1";
"B":   PN = "2"  !CDS_PN = "2";
BODY = "Q_CAP","I38": #LOCATION = "PC194" !CDS_LOCATION = "PC194" &SEC = "1" #&CDS_SEC = "1";
"A":   PN = "1"  !CDS_PN = "1";
"B":   PN = "2"  !CDS_PN = "2";
BODY = "Q_INDUCTOR","I39": #LOCATION = "PL5" !CDS_LOCATION = "PL5" &SEC = "1" #&CDS_SEC = "1";
"1":   PN = "1"  !CDS_PN = "1";
"2":   PN = "2"  !CDS_PN = "2";
BODY = "Q_CAP","I40": #LOCATION = "PC203_P0_2" !CDS_LOCATION = "PC203_P0_2" &SEC = "1" #&CDS_SEC = "1";
"A":   PN = "1"  !CDS_PN = "1";
"B":   PN = "2"  !CDS_PN = "2";
BODY = "Q_CAP","I45": #LOCATION = "PC189_P0_1" !CDS_LOCATION = "PC189_P0_1" &SEC = "1" #&CDS_SEC = "1";
"A":   PN = "1"  !CDS_PN = "1";
"B":   PN = "2"  !CDS_PN = "2";
BODY = "Q_RES","I46": #LOCATION = "PR1776" !CDS_LOCATION = "PR1776" &SEC = "1" #&CDS_SEC = "1";
"A":   PN = "1"  !CDS_PN = "1";
"B":   PN = "2"  !CDS_PN = "2";
BODY = "Q_RES","I47": #LOCATION = "PR1774" !CDS_LOCATION = "PR1774" &SEC = "1" #&CDS_SEC = "1";
"A":   PN = "1"  !CDS_PN = "1";
"B":   PN = "2"  !CDS_PN = "2";
BODY = "Q_CAP","I48": #LOCATION = "PC191_P0_1" !CDS_LOCATION = "PC191_P0_1" &SEC = "1" #&CDS_SEC = "1";
"A":   PN = "1"  !CDS_PN = "1";
"B":   PN = "2"  !CDS_PN = "2";
BODY = "Q_CAP","I49": #LOCATION = "PC195_P0_1" !CDS_LOCATION = "PC195_P0_1" &SEC = "1" #&CDS_SEC = "1";
"A":   PN = "1"  !CDS_PN = "1";
"B":   PN = "2"  !CDS_PN = "2";
BODY = "Q_CAP","I50": #LOCATION = "PC197_P0_1" !CDS_LOCATION = "PC197_P0_1" &SEC = "1" #&CDS_SEC = "1";
"A":   PN = "1"  !CDS_PN = "1";
"B":   PN = "2"  !CDS_PN = "2";
BODY = "Q_CAP","I51": #LOCATION = "PC193" !CDS_LOCATION = "PC193" &SEC = "1" #&CDS_SEC = "1";
"A":   PN = "1"  !CDS_PN = "1";
"B":   PN = "2"  !CDS_PN = "2";
BODY = "Q_INDUCTOR","I52": #LOCATION = "PL4" !CDS_LOCATION = "PL4" &SEC = "1" #&CDS_SEC = "1";
"1":   PN = "1"  !CDS_PN = "1";
"2":   PN = "2"  !CDS_PN = "2";
BODY = "Q_CAP","I56": #LOCATION = "PC202_P0_1" !CDS_LOCATION = "PC202_P0_1" &SEC = "1" #&CDS_SEC = "1";
"A":   PN = "1"  !CDS_PN = "1";
"B":   PN = "2"  !CDS_PN = "2";
BODY = "Q_CAPP","I66": #LOCATION = "PC1574" !CDS_LOCATION = "PC1574" &SEC = "1" #&CDS_SEC = "1";
"A":   PN = "1"  !CDS_PN = "1";
"B":   PN = "2"  !CDS_PN = "2";
BODY = "Q_CAPP","I67": #LOCATION = "PC1576" !CDS_LOCATION = "PC1576" &SEC = "1" #&CDS_SEC = "1";
"A":   PN = "1"  !CDS_PN = "1";
"B":   PN = "2"  !CDS_PN = "2";
BODY = "Q_CAPP","I68": #LOCATION = "PC1573" !CDS_LOCATION = "PC1573" &SEC = "1" #&CDS_SEC = "1";
"A":   PN = "1"  !CDS_PN = "1";
"B":   PN = "2"  !CDS_PN = "2";
BODY = "Q_CAPP","I74": #LOCATION = "PC207" !CDS_LOCATION = "PC207" &SEC = "1" #&CDS_SEC = "1";
"A":   PN = "1"  !CDS_PN = "1";
"B":   PN = "2"  !CDS_PN = "2";
BODY = "Q_RES","I14": #LOCATION = "PR102" !CDS_LOCATION = "PR102" &SEC = "1" #&CDS_SEC = "1";
"A":   PN = "1"  !CDS_PN = "1";
"B":   PN = "2"  !CDS_PN = "2";
BODY = "Q_CAP","I29": #LOCATION = "PC2947" !CDS_LOCATION = "PC2947" &SEC = "1" #&CDS_SEC = "1";
"A":   PN = "1"  !CDS_PN = "1";
"B":   PN = "2"  !CDS_PN = "2";
BODY = "Q_CAP","I41": #LOCATION = "PC205_P0_2" !CDS_LOCATION = "PC205_P0_2" &SEC = "1" #&CDS_SEC = "1";
"A":   PN = "1"  !CDS_PN = "1";
"B":   PN = "2"  !CDS_PN = "2";
BODY = "Q_CAP","I60": #LOCATION = "PC1655" !CDS_LOCATION = "PC1655" &SEC = "1" #&CDS_SEC = "1";
"A":   PN = "1"  !CDS_PN = "1";
"B":   PN = "2"  !CDS_PN = "2";
BODY = "Q_INDUCTOR","I62": #LOCATION = "PL6" !CDS_LOCATION = "PL6" &SEC = "1" #&CDS_SEC = "1";
"1":   PN = "1"  !CDS_PN = "1";
"2":   PN = "2"  !CDS_PN = "2";
BODY = "Q_CAPP","I69": #LOCATION = "PC1575" !CDS_LOCATION = "PC1575" &SEC = "1" #&CDS_SEC = "1";
"A":   PN = "1"  !CDS_PN = "1";
"B":   PN = "2"  !CDS_PN = "2";
BODY = "Q_CAPP","I75": #LOCATION = "PC208" !CDS_LOCATION = "PC208" &SEC = "1" #&CDS_SEC = "1";
"A":   PN = "1"  !CDS_PN = "1";
"B":   PN = "2"  !CDS_PN = "2";
BODY = "ISL99390FRZTR5935","I79": #LOCATION = "PU43_P0_1" !CDS_LOCATION = "PU43_P0_1" #SEC = "1" !CDS_SEC = "1";
"AGND":   PN = "2"  !CDS_PN = "2";
"BOOT":   PN = "33"  !CDS_PN = "33";
"DNC":   PN = "31"  !CDS_PN = "31";
"EN":   PN = "35"  !CDS_PN = "35";
"GL1":   PN = "6"  !CDS_PN = "6";
"GL2":   PN = "41"  !CDS_PN = "41";
"IOUT":   PN = "38"  !CDS_PN = "38";
"LSET":   PN = "37"  !CDS_PN = "37";
"PGND1":   PN = "5"  !CDS_PN = "5";
"PGND2":   PN = "7_9-20_24"  !CDS_PN = "7_9-20_24";
"PGND3":   PN = "40"  !CDS_PN = "40";
"PHASE":   PN = "32"  !CDS_PN = "32";
"PVCC":   PN = "4"  !CDS_PN = "4";
"PWM":   PN = "34"  !CDS_PN = "34";
"REFIN":   PN = "39"  !CDS_PN = "39";
"SW":   PN = "10_19"  !CDS_PN = "10_19";
"TOUT_FLT":   PN = "36"  !CDS_PN = "36";
"VCC":   PN = "3"  !CDS_PN = "3";
"VIN1":   PN = "25_29"  !CDS_PN = "25_29";
"VIN2":   PN = "30"  !CDS_PN = "30";
"VOS":   PN = "1"  !CDS_PN = "1";
BODY = "Q_RES","I2": #LOCATION = "PR1707" !CDS_LOCATION = "PR1707" &SEC = "1" #&CDS_SEC = "1";
"A":   PN = "1"  !CDS_PN = "1";
"B":   PN = "2"  !CDS_PN = "2";
BODY = "Q_RES","I5": #LOCATION = "PR1708" !CDS_LOCATION = "PR1708" &SEC = "1" #&CDS_SEC = "1";
"A":   PN = "1"  !CDS_PN = "1";
"B":   PN = "2"  !CDS_PN = "2";
BODY = "Q_CAP","I11": #LOCATION = "PC1346" !CDS_LOCATION = "PC1346" &SEC = "1" #&CDS_SEC = "1";
"A":   PN = "1"  !CDS_PN = "1";
"B":   PN = "2"  !CDS_PN = "2";
BODY = "Q_CAP","I13": #LOCATION = "PC188" !CDS_LOCATION = "PC188" &SEC = "1" #&CDS_SEC = "1";
"A":   PN = "1"  !CDS_PN = "1";
"B":   PN = "2"  !CDS_PN = "2";
BODY = "Q_CAP","I16": #LOCATION = "PC2946" !CDS_LOCATION = "PC2946" &SEC = "1" #&CDS_SEC = "1";
"A":   PN = "1"  !CDS_PN = "1";
"B":   PN = "2"  !CDS_PN = "2";
BODY = "Q_CAP","I24": #LOCATION = "PC187" !CDS_LOCATION = "PC187" &SEC = "1" #&CDS_SEC = "1";
"A":   PN = "1"  !CDS_PN = "1";
"B":   PN = "2"  !CDS_PN = "2";
BODY = "Q_CAP","I54": #LOCATION = "PC199_P0_1" !CDS_LOCATION = "PC199_P0_1" &SEC = "1" #&CDS_SEC = "1";
"A":   PN = "1"  !CDS_PN = "1";
"B":   PN = "2"  !CDS_PN = "2";
BODY = "Q_CAP","I57": #LOCATION = "PC204_P0_1" !CDS_LOCATION = "PC204_P0_1" &SEC = "1" #&CDS_SEC = "1";
"A":   PN = "1"  !CDS_PN = "1";
"B":   PN = "2"  !CDS_PN = "2";
BODY = "Q_RES","I63": #LOCATION = "PR4226" !CDS_LOCATION = "PR4226" &SEC = "1" #&CDS_SEC = "1";
"A":   PN = "1"  !CDS_PN = "1";
"B":   PN = "2"  !CDS_PN = "2";
BODY = "Q_CAPP","I70": #LOCATION = "PC1579" !CDS_LOCATION = "PC1579" &SEC = "1" #&CDS_SEC = "1";
"A":   PN = "1"  !CDS_PN = "1";
"B":   PN = "2"  !CDS_PN = "2";
DRAWING = "@s9s_mb_2u_lib.s9s_mb_2u(sch_1):page265";
BODY = "Q_RES","I3": #LOCATION = "PR2718" !CDS_LOCATION = "PR2718" &SEC = "1" #&CDS_SEC = "1";
"A":   PN = "1"  !CDS_PN = "1";
"B":   PN = "2"  !CDS_PN = "2";
BODY = "ISL99390FRZTR5935","I8": #LOCATION = "PU36" !CDS_LOCATION = "PU36" #SEC = "1" !CDS_SEC = "1";
"AGND":   PN = "2"  !CDS_PN = "2";
"BOOT":   PN = "33"  !CDS_PN = "33";
"DNC":   PN = "31"  !CDS_PN = "31";
"EN":   PN = "35"  !CDS_PN = "35";
"GL1":   PN = "6"  !CDS_PN = "6";
"GL2":   PN = "41"  !CDS_PN = "41";
"IOUT":   PN = "38"  !CDS_PN = "38";
"LSET":   PN = "37"  !CDS_PN = "37";
"PGND1":   PN = "5"  !CDS_PN = "5";
"PGND2":   PN = "7_9-20_24"  !CDS_PN = "7_9-20_24";
"PGND3":   PN = "40"  !CDS_PN = "40";
"PHASE":   PN = "32"  !CDS_PN = "32";
"PVCC":   PN = "4"  !CDS_PN = "4";
"PWM":   PN = "34"  !CDS_PN = "34";
"REFIN":   PN = "39"  !CDS_PN = "39";
"SW":   PN = "10_19"  !CDS_PN = "10_19";
"TOUT_FLT":   PN = "36"  !CDS_PN = "36";
"VCC":   PN = "3"  !CDS_PN = "3";
"VIN1":   PN = "25_29"  !CDS_PN = "25_29";
"VIN2":   PN = "30"  !CDS_PN = "30";
"VOS":   PN = "1"  !CDS_PN = "1";
BODY = "Q_CAP","I11": #LOCATION = "PC633" !CDS_LOCATION = "PC633" &SEC = "1" #&CDS_SEC = "1";
"A":   PN = "1"  !CDS_PN = "1";
"B":   PN = "2"  !CDS_PN = "2";
BODY = "Q_RES","I17": #LOCATION = "PR1785" !CDS_LOCATION = "PR1785" &SEC = "1" #&CDS_SEC = "1";
"A":   PN = "1"  !CDS_PN = "1";
"B":   PN = "2"  !CDS_PN = "2";
BODY = "Q_CAP","I18": #LOCATION = "PC634" !CDS_LOCATION = "PC634" &SEC = "1" #&CDS_SEC = "1";
"A":   PN = "1"  !CDS_PN = "1";
"B":   PN = "2"  !CDS_PN = "2";
BODY = "Q_RES","I19": #LOCATION = "PR1784" !CDS_LOCATION = "PR1784" &SEC = "1" #&CDS_SEC = "1";
"A":   PN = "1"  !CDS_PN = "1";
"B":   PN = "2"  !CDS_PN = "2";
BODY = "Q_CAP","I20": #LOCATION = "PC635" !CDS_LOCATION = "PC635" &SEC = "1" #&CDS_SEC = "1";
"A":   PN = "1"  !CDS_PN = "1";
"B":   PN = "2"  !CDS_PN = "2";
BODY = "Q_CAP","I21": #LOCATION = "PC637" !CDS_LOCATION = "PC637" &SEC = "1" #&CDS_SEC = "1";
"A":   PN = "1"  !CDS_PN = "1";
"B":   PN = "2"  !CDS_PN = "2";
BODY = "Q_CAP","I22": #LOCATION = "PC636" !CDS_LOCATION = "PC636" &SEC = "1" #&CDS_SEC = "1";
"A":   PN = "1"  !CDS_PN = "1";
"B":   PN = "2"  !CDS_PN = "2";
BODY = "Q_CAP","I23": #LOCATION = "PC638" !CDS_LOCATION = "PC638" &SEC = "1" #&CDS_SEC = "1";
"A":   PN = "1"  !CDS_PN = "1";
"B":   PN = "2"  !CDS_PN = "2";
BODY = "Q_CAP","I25": #LOCATION = "PC641" !CDS_LOCATION = "PC641" &SEC = "1" #&CDS_SEC = "1";
"A":   PN = "1"  !CDS_PN = "1";
"B":   PN = "2"  !CDS_PN = "2";
BODY = "Q_CAPP","I26": #LOCATION = "PC1910" !CDS_LOCATION = "PC1910" &SEC = "1" #&CDS_SEC = "1";
"A":   PN = "1"  !CDS_PN = "1";
"B":   PN = "2"  !CDS_PN = "2";
BODY = "Q_CAP","I28": #LOCATION = "PC642" !CDS_LOCATION = "PC642" &SEC = "1" #&CDS_SEC = "1";
"A":   PN = "1"  !CDS_PN = "1";
"B":   PN = "2"  !CDS_PN = "2";
BODY = "Q_CAP","I29": #LOCATION = "PC1" !CDS_LOCATION = "PC1" &SEC = "1" #&CDS_SEC = "1";
"A":   PN = "1"  !CDS_PN = "1";
"B":   PN = "2"  !CDS_PN = "2";
BODY = "Q_CAPP","I34": #LOCATION = "PC1645" !CDS_LOCATION = "PC1645" &SEC = "1" #&CDS_SEC = "1";
"A":   PN = "1"  !CDS_PN = "1";
"B":   PN = "2"  !CDS_PN = "2";
BODY = "Q_RES","I37": #LOCATION = "PR4237" !CDS_LOCATION = "PR4237" &SEC = "1" #&CDS_SEC = "1";
"A":   PN = "1"  !CDS_PN = "1";
"B":   PN = "2"  !CDS_PN = "2";
BODY = "Q_RES","I12": #LOCATION = "PR380" !CDS_LOCATION = "PR380" &SEC = "1" #&CDS_SEC = "1";
"A":   PN = "1"  !CDS_PN = "1";
"B":   PN = "2"  !CDS_PN = "2";
BODY = "Q_CAP","I14": #LOCATION = "PC2948" !CDS_LOCATION = "PC2948" &SEC = "1" #&CDS_SEC = "1";
"A":   PN = "1"  !CDS_PN = "1";
"B":   PN = "2"  !CDS_PN = "2";
BODY = "Q_CAP","I24": #LOCATION = "PC639" !CDS_LOCATION = "PC639" &SEC = "1" #&CDS_SEC = "1";
"A":   PN = "1"  !CDS_PN = "1";
"B":   PN = "2"  !CDS_PN = "2";
BODY = "Q_CAPP","I27": #LOCATION = "PC1644" !CDS_LOCATION = "PC1644" &SEC = "1" #&CDS_SEC = "1";
"A":   PN = "1"  !CDS_PN = "1";
"B":   PN = "2"  !CDS_PN = "2";
BODY = "Q_CAP","I7": #LOCATION = "PC1354" !CDS_LOCATION = "PC1354" &SEC = "1" #&CDS_SEC = "1";
"A":   PN = "1"  !CDS_PN = "1";
"B":   PN = "2"  !CDS_PN = "2";
BODY = "Q_INDUCTOR","I30": #LOCATION = "PL35" !CDS_LOCATION = "PL35" &SEC = "1" #&CDS_SEC = "1";
"1":   PN = "1"  !CDS_PN = "1";
"2":   PN = "2"  !CDS_PN = "2";
DRAWING = "@s9s_mb_2u_lib.s9s_mb_2u(sch_1):page268";
BODY = "Q_RES","I19": #LOCATION = "PR1" !CDS_LOCATION = "PR1" &SEC = "1" #&CDS_SEC = "1";
"A":   PN = "1"  !CDS_PN = "1";
"B":   PN = "2"  !CDS_PN = "2";
BODY = "Q_CAP","I26": #LOCATION = "PC1275" !CDS_LOCATION = "PC1275" &SEC = "1" #&CDS_SEC = "1";
"A":   PN = "1"  !CDS_PN = "1";
"B":   PN = "2"  !CDS_PN = "2";
BODY = "Q_RES","I36": #LOCATION = "PR501" !CDS_LOCATION = "PR501" &SEC = "1" #&CDS_SEC = "1";
"A":   PN = "1"  !CDS_PN = "1";
"B":   PN = "2"  !CDS_PN = "2";
BODY = "Q_RES","I40": #LOCATION = "PR4698" !CDS_LOCATION = "PR4698" &SEC = "1" #&CDS_SEC = "1";
"A":   PN = "1"  !CDS_PN = "1";
"B":   PN = "2"  !CDS_PN = "2";
BODY = "Q_RES","I27": #LOCATION = "PR4271" !CDS_LOCATION = "PR4271" #SEC = "1" !CDS_SEC = "1";
"A":   PN = "1"  !CDS_PN = "1";
"B":   PN = "2"  !CDS_PN = "2";
BODY = "Q_CAP","I31": #LOCATION = "C1296" !CDS_LOCATION = "C1296" &SEC = "1" #&CDS_SEC = "1";
"A":   PN = "1"  !CDS_PN = "1";
"B":   PN = "2"  !CDS_PN = "2";
BODY = "Q_RES","I11": #LOCATION = "R1445" !CDS_LOCATION = "R1445" &SEC = "1" #&CDS_SEC = "1";
"A":   PN = "1"  !CDS_PN = "1";
"B":   PN = "2"  !CDS_PN = "2";
BODY = "Q_CAP","I25": #LOCATION = "PC27" !CDS_LOCATION = "PC27" &SEC = "1" #&CDS_SEC = "1";
"A":   PN = "1"  !CDS_PN = "1";
"B":   PN = "2"  !CDS_PN = "2";
BODY = "Q_CAP","I35": #LOCATION = "PC237" !CDS_LOCATION = "PC237" &SEC = "1" #&CDS_SEC = "1";
"A":   PN = "1"  !CDS_PN = "1";
"B":   PN = "2"  !CDS_PN = "2";
BODY = "Q_CAP","I42": #LOCATION = "PC1278" !CDS_LOCATION = "PC1278" &SEC = "1" #&CDS_SEC = "1";
"A":   PN = "1"  !CDS_PN = "1";
"B":   PN = "2"  !CDS_PN = "2";
BODY = "Q_RES","I33": #LOCATION = "R1652" !CDS_LOCATION = "R1652" &SEC = "1" #&CDS_SEC = "1";
"A":   PN = "1"  !CDS_PN = "1";
"B":   PN = "2"  !CDS_PN = "2";
BODY = "Q_CAP","I39": #LOCATION = "PC1420" !CDS_LOCATION = "PC1420" &SEC = "1" #&CDS_SEC = "1";
"A":   PN = "1"  !CDS_PN = "1";
"B":   PN = "2"  !CDS_PN = "2";
BODY = "Q_RES","I41": #LOCATION = "PR4683" !CDS_LOCATION = "PR4683" &SEC = "1" #&CDS_SEC = "1";
"A":   PN = "1"  !CDS_PN = "1";
"B":   PN = "2"  !CDS_PN = "2";
BODY = "Q_CAP","I4": #LOCATION = "C1307" !CDS_LOCATION = "C1307" &SEC = "1" #&CDS_SEC = "1";
"A":   PN = "1"  !CDS_PN = "1";
"B":   PN = "2"  !CDS_PN = "2";
BODY = "Q_RES","I10": #LOCATION = "PR3339" !CDS_LOCATION = "PR3339" &SEC = "1" #&CDS_SEC = "1";
"A":   PN = "1"  !CDS_PN = "1";
"B":   PN = "2"  !CDS_PN = "2";
BODY = "Q_CAP","I15": #LOCATION = "PC1273" !CDS_LOCATION = "PC1273" &SEC = "1" #&CDS_SEC = "1";
"A":   PN = "1"  !CDS_PN = "1";
"B":   PN = "2"  !CDS_PN = "2";
BODY = "Q_CAP","I23": #LOCATION = "PC1274" !CDS_LOCATION = "PC1274" &SEC = "1" #&CDS_SEC = "1";
"A":   PN = "1"  !CDS_PN = "1";
"B":   PN = "2"  !CDS_PN = "2";
BODY = "Q_RES","I28": #LOCATION = "PR50" !CDS_LOCATION = "PR50" #SEC = "1" !CDS_SEC = "1";
"A":   PN = "1"  !CDS_PN = "1";
"B":   PN = "2"  !CDS_PN = "2";
BODY = "Q_RES","I32": #LOCATION = "R2409" !CDS_LOCATION = "R2409" &SEC = "1" #&CDS_SEC = "1";
"A":   PN = "1"  !CDS_PN = "1";
"B":   PN = "2"  !CDS_PN = "2";
BODY = "Q_CAP","I43": #LOCATION = "PC1279" !CDS_LOCATION = "PC1279" &SEC = "1" #&CDS_SEC = "1";
"A":   PN = "1"  !CDS_PN = "1";
"B":   PN = "2"  !CDS_PN = "2";
BODY = "Q_RES","I5": #LOCATION = "R2338" !CDS_LOCATION = "R2338" &SEC = "1" #&CDS_SEC = "1";
"A":   PN = "1"  !CDS_PN = "1";
"B":   PN = "2"  !CDS_PN = "2";
BODY = "Q_CAP","I7": #LOCATION = "PC2221" !CDS_LOCATION = "PC2221" #SEC = "1" !CDS_SEC = "1";
"A":   PN = "1"  !CDS_PN = "1";
"B":   PN = "2"  !CDS_PN = "2";
BODY = "Q_RES","I9": #LOCATION = "PR1301" !CDS_LOCATION = "PR1301" &SEC = "1" #&CDS_SEC = "1";
"A":   PN = "1"  !CDS_PN = "1";
"B":   PN = "2"  !CDS_PN = "2";
BODY = "Q_CAP","I13": #LOCATION = "PC1272" !CDS_LOCATION = "PC1272" &SEC = "1" #&CDS_SEC = "1";
"A":   PN = "1"  !CDS_PN = "1";
"B":   PN = "2"  !CDS_PN = "2";
BODY = "Q_RES","I21": #LOCATION = "PR1303" !CDS_LOCATION = "PR1303" &SEC = "1" #&CDS_SEC = "1";
"A":   PN = "1"  !CDS_PN = "1";
"B":   PN = "2"  !CDS_PN = "2";
BODY = "RS53317LR","I22": #LOCATION = "PU81" !CDS_LOCATION = "PU81" #SEC = "1" !CDS_SEC = "1";
"AGND":   PN = "7"  !CDS_PN = "7";
"BST":   PN = "10"  !CDS_PN = "10";
"CS":   PN = "4"  !CDS_PN = "4";
"EN":   PN = "5"  !CDS_PN = "5";
"FB":   PN = "6"  !CDS_PN = "6";
"MODE":   PN = "12"  !CDS_PN = "12";
"PGND1":   PN = "1"  !CDS_PN = "1";
"PGND2":   PN = "14"  !CDS_PN = "14";
"PGOOD":   PN = "9"  !CDS_PN = "9";
"REF":   PN = "8"  !CDS_PN = "8";
"SW1":   PN = "2"  !CDS_PN = "2";
"SW2":   PN = "11"  !CDS_PN = "11";
"VCC":   PN = "13"  !CDS_PN = "13";
"VIN":   PN = "3"  !CDS_PN = "3";
BODY = "Q_INDUCTOR","I29": #LOCATION = "PL120" !CDS_LOCATION = "PL120" &SEC = "1" #&CDS_SEC = "1";
"1":   PN = "1"  !CDS_PN = "1";
"2":   PN = "2"  !CDS_PN = "2";
BODY = "Q_CAP","I37": #LOCATION = "PC1276" !CDS_LOCATION = "PC1276" &SEC = "1" #&CDS_SEC = "1";
"A":   PN = "1"  !CDS_PN = "1";
"B":   PN = "2"  !CDS_PN = "2";
BODY = "Q_CAP","I38": #LOCATION = "PC1277" !CDS_LOCATION = "PC1277" &SEC = "1" #&CDS_SEC = "1";
"A":   PN = "1"  !CDS_PN = "1";
"B":   PN = "2"  !CDS_PN = "2";
BODY = "Q_CAP","I47": #LOCATION = "PC1206" !CDS_LOCATION = "PC1206" &SEC = "1" #&CDS_SEC = "1";
"A":   PN = "1"  !CDS_PN = "1";
"B":   PN = "2"  !CDS_PN = "2";
DRAWING = "@s9s_mb_2u_lib.s9s_mb_2u(sch_1):page282";
BODY = "Q_RES","I29": #LOCATION = "R2593" !CDS_LOCATION = "R2593" &SEC = "1" #&CDS_SEC = "1";
"A":   PN = "1"  !CDS_PN = "1";
"B":   PN = "2"  !CDS_PN = "2";
BODY = "Q_RES","I33": #LOCATION = "R1718" !CDS_LOCATION = "R1718" &SEC = "1" #&CDS_SEC = "1";
"A":   PN = "1"  !CDS_PN = "1";
"B":   PN = "2"  !CDS_PN = "2";
BODY = "Q_RES","I38": #LOCATION = "R2582" !CDS_LOCATION = "R2582" #SEC = "1" !CDS_SEC = "1";
"A":   PN = "1"  !CDS_PN = "1";
"B":   PN = "2"  !CDS_PN = "2";
BODY = "Q_RES","I46": #LOCATION = "R2575" !CDS_LOCATION = "R2575" &SEC = "1" #&CDS_SEC = "1";
"A":   PN = "1"  !CDS_PN = "1";
"B":   PN = "2"  !CDS_PN = "2";
BODY = "Q_RES","I48": #LOCATION = "PR218" !CDS_LOCATION = "PR218" &SEC = "1" #&CDS_SEC = "1";
"A":   PN = "1"  !CDS_PN = "1";
"B":   PN = "2"  !CDS_PN = "2";
BODY = "Q_CAP","I50": #LOCATION = "PC390" !CDS_LOCATION = "PC390" &SEC = "1" #&CDS_SEC = "1";
"A":   PN = "1"  !CDS_PN = "1";
"B":   PN = "2"  !CDS_PN = "2";
BODY = "ISL69260IRAZT","I53": #LOCATION = "PU18" !CDS_LOCATION = "PU18" &SEC = "1" #&CDS_SEC = "1";
"ADDR_CFG":   PN = "34"  !CDS_PN = "34";
"CFP":   PN = "33"  !CDS_PN = "33";
"CS0":   PN = "30"  !CDS_PN = "30";
"CS1":   PN = "29"  !CDS_PN = "29";
"CS2":   PN = "28"  !CDS_PN = "28";
"CS3":   PN = "27"  !CDS_PN = "27";
"CS4":   PN = "26"  !CDS_PN = "26";
"CS5":   PN = "25"  !CDS_PN = "25";
"CS6":   PN = "24"  !CDS_PN = "24";
"CS7":   PN = "23"  !CDS_PN = "23";
"EN0":   PN = "13"  !CDS_PN = "13";
"EN1":   PN = "20"  !CDS_PN = "20";
"PG0":   PN = "12"  !CDS_PN = "12";
"PG1":   PN = "16"  !CDS_PN = "16";
"PMSCL":   PN = "10"  !CDS_PN = "10";
"PMSDA":   PN = "9"  !CDS_PN = "9";
"PWM0":   PN = "1"  !CDS_PN = "1";
"PWM1":   PN = "2"  !CDS_PN = "2";
"PWM2":   PN = "3"  !CDS_PN = "3";
"PWM3":   PN = "4"  !CDS_PN = "4";
"PWM4":   PN = "5"  !CDS_PN = "5";
"PWM5":   PN = "6"  !CDS_PN = "6";
"PWM6":   PN = "7"  !CDS_PN = "7";
"PWM7":   PN = "8"  !CDS_PN = "8";
"RGND0":   PN = "22"  !CDS_PN = "22";
"RGND1":   PN = "31"  !CDS_PN = "31";
"SVCLK":   PN = "17"  !CDS_PN = "17";
"SVDATA":   PN = "18"  !CDS_PN = "18";
"TEMP0":   PN = "35"  !CDS_PN = "35";
"TEMP1||ISYS":   PN = "36"  !CDS_PN = "36";
"TH_GND":   PN = "TH"  !CDS_PN = "TH";
"VCC":   PN = "39"  !CDS_PN = "39";
"VCCS":   PN = "40"  !CDS_PN = "40";
"VSEN0":   PN = "21"  !CDS_PN = "21";
"VSEN1":   PN = "32"  !CDS_PN = "32";
"NPINALERT#||NPSYSCRIT#":   PN = "15"  !CDS_PN = "15";
"NPMALERT#":   PN = "11"  !CDS_PN = "11";
"NSVALERT#":   PN = "19"  !CDS_PN = "19";
"NVRHOT#":   PN = "14"  !CDS_PN = "14";
"VINSEN||VSYS":   PN = "38"  !CDS_PN = "38";
"VMON||IINSEN||VSYS||ISYS":   PN = "37"  !CDS_PN = "37";
BODY = "Q_RES","I58": #LOCATION = "R2557" !CDS_LOCATION = "R2557" #SEC = "1" !CDS_SEC = "1";
"A":   PN = "1"  !CDS_PN = "1";
"B":   PN = "2"  !CDS_PN = "2";
BODY = "Q_RES","I60": #LOCATION = "PR1315" !CDS_LOCATION = "PR1315" &SEC = "1" #&CDS_SEC = "1";
"A":   PN = "1"  !CDS_PN = "1";
"B":   PN = "2"  !CDS_PN = "2";
BODY = "Q_RES","I61": #LOCATION = "PR410" !CDS_LOCATION = "PR410" &SEC = "1" #&CDS_SEC = "1";
"A":   PN = "1"  !CDS_PN = "1";
"B":   PN = "2"  !CDS_PN = "2";
BODY = "Q_RES","I63": #LOCATION = "PR4256" !CDS_LOCATION = "PR4256" &SEC = "1" #&CDS_SEC = "1";
"A":   PN = "1"  !CDS_PN = "1";
"B":   PN = "2"  !CDS_PN = "2";
BODY = "Q_RES","I36": #LOCATION = "PR559" !CDS_LOCATION = "PR559" &SEC = "1" #&CDS_SEC = "1";
"A":   PN = "1"  !CDS_PN = "1";
"B":   PN = "2"  !CDS_PN = "2";
BODY = "Q_CAP","I45": #LOCATION = "C2454" !CDS_LOCATION = "C2454" &SEC = "1" #&CDS_SEC = "1";
"A":   PN = "1"  !CDS_PN = "1";
"B":   PN = "2"  !CDS_PN = "2";
BODY = "Q_RES","I81": #LOCATION = "PR705" !CDS_LOCATION = "PR705" &SEC = "1" #&CDS_SEC = "1";
"A":   PN = "1"  !CDS_PN = "1";
"B":   PN = "2"  !CDS_PN = "2";
BODY = "Q_CAP","I13": #LOCATION = "PC386" !CDS_LOCATION = "PC386" &SEC = "1" #&CDS_SEC = "1";
"A":   PN = "1"  !CDS_PN = "1";
"B":   PN = "2"  !CDS_PN = "2";
BODY = "Q_RES","I18": #LOCATION = "PR215" !CDS_LOCATION = "PR215" &SEC = "1" #&CDS_SEC = "1";
"A":   PN = "1"  !CDS_PN = "1";
"B":   PN = "2"  !CDS_PN = "2";
BODY = "Q_RES","I20": #LOCATION = "PR217" !CDS_LOCATION = "PR217" &SEC = "1" #&CDS_SEC = "1";
"A":   PN = "1"  !CDS_PN = "1";
"B":   PN = "2"  !CDS_PN = "2";
BODY = "Q_RES","I21": #LOCATION = "PR216" !CDS_LOCATION = "PR216" &SEC = "1" #&CDS_SEC = "1";
"A":   PN = "1"  !CDS_PN = "1";
"B":   PN = "2"  !CDS_PN = "2";
BODY = "Q_CAP","I28": #LOCATION = "C1337" !CDS_LOCATION = "C1337" &SEC = "1" #&CDS_SEC = "1";
"A":   PN = "1"  !CDS_PN = "1";
"B":   PN = "2"  !CDS_PN = "2";
BODY = "Q_RES","I39": #LOCATION = "R4595" !CDS_LOCATION = "R4595" &SEC = "1" #&CDS_SEC = "1";
"A":   PN = "1"  !CDS_PN = "1";
"B":   PN = "2"  !CDS_PN = "2";
BODY = "Q_CAP","I51": #LOCATION = "PC814" !CDS_LOCATION = "PC814" &SEC = "1" #&CDS_SEC = "1";
"A":   PN = "1"  !CDS_PN = "1";
"B":   PN = "2"  !CDS_PN = "2";
BODY = "Q_CAP","I57": #LOCATION = "PC393" !CDS_LOCATION = "PC393" &SEC = "1" #&CDS_SEC = "1";
"A":   PN = "1"  !CDS_PN = "1";
"B":   PN = "2"  !CDS_PN = "2";
BODY = "Q_CAP","I68": #LOCATION = "PC392" !CDS_LOCATION = "PC392" &SEC = "1" #&CDS_SEC = "1";
"A":   PN = "1"  !CDS_PN = "1";
"B":   PN = "2"  !CDS_PN = "2";
BODY = "Q_CAP","I69": #LOCATION = "PC391" !CDS_LOCATION = "PC391" &SEC = "1" #&CDS_SEC = "1";
"A":   PN = "1"  !CDS_PN = "1";
"B":   PN = "2"  !CDS_PN = "2";
BODY = "Q_RES","I70": #LOCATION = "PR4251" !CDS_LOCATION = "PR4251" &SEC = "1" #&CDS_SEC = "1";
"A":   PN = "1"  !CDS_PN = "1";
"B":   PN = "2"  !CDS_PN = "2";
BODY = "Q_CAP","I74": #LOCATION = "PC1289" !CDS_LOCATION = "PC1289" &SEC = "1" #&CDS_SEC = "1";
"A":   PN = "1"  !CDS_PN = "1";
"B":   PN = "2"  !CDS_PN = "2";
BODY = "Q_RES","I85": #LOCATION = "R223" !CDS_LOCATION = "R223" &SEC = "1" #&CDS_SEC = "1";
"A":   PN = "1"  !CDS_PN = "1";
"B":   PN = "2"  !CDS_PN = "2";
BODY = "Q_RES","I8": #LOCATION = "PR202" !CDS_LOCATION = "PR202" &SEC = "1" #&CDS_SEC = "1";
"A":   PN = "1"  !CDS_PN = "1";
"B":   PN = "2"  !CDS_PN = "2";
BODY = "Q_RES","I9": #LOCATION = "PR1400" !CDS_LOCATION = "PR1400" &SEC = "1" #&CDS_SEC = "1";
"A":   PN = "1"  !CDS_PN = "1";
"B":   PN = "2"  !CDS_PN = "2";
BODY = "Q_RES","I10": #LOCATION = "PR1410" !CDS_LOCATION = "PR1410" &SEC = "1" #&CDS_SEC = "1";
"A":   PN = "1"  !CDS_PN = "1";
"B":   PN = "2"  !CDS_PN = "2";
BODY = "Q_RES","I11": #LOCATION = "PR214" !CDS_LOCATION = "PR214" &SEC = "1" #&CDS_SEC = "1";
"A":   PN = "1"  !CDS_PN = "1";
"B":   PN = "2"  !CDS_PN = "2";
BODY = "Q_RES","I15": #LOCATION = "PR558" !CDS_LOCATION = "PR558" &SEC = "1" #&CDS_SEC = "1";
"A":   PN = "1"  !CDS_PN = "1";
"B":   PN = "2"  !CDS_PN = "2";
BODY = "Q_SHORT","I16": #LOCATION = "PJ48" !CDS_LOCATION = "PJ48" &SEC = "1" #&CDS_SEC = "1";
"1":   PN = "1"  !CDS_PN = "1";
"2":   PN = "2"  !CDS_PN = "2";
BODY = "Q_CAP","I22": #LOCATION = "PC389" !CDS_LOCATION = "PC389" &SEC = "1" #&CDS_SEC = "1";
"A":   PN = "1"  !CDS_PN = "1";
"B":   PN = "2"  !CDS_PN = "2";
BODY = "Q_CAP","I24": #LOCATION = "C1336" !CDS_LOCATION = "C1336" &SEC = "1" #&CDS_SEC = "1";
"A":   PN = "1"  !CDS_PN = "1";
"B":   PN = "2"  !CDS_PN = "2";
BODY = "Q_RES","I40": #LOCATION = "R2580" !CDS_LOCATION = "R2580" &SEC = "1" #&CDS_SEC = "1";
"A":   PN = "1"  !CDS_PN = "1";
"B":   PN = "2"  !CDS_PN = "2";
BODY = "Q_RES","I41": #LOCATION = "R2579" !CDS_LOCATION = "R2579" &SEC = "1" #&CDS_SEC = "1";
"A":   PN = "1"  !CDS_PN = "1";
"B":   PN = "2"  !CDS_PN = "2";
BODY = "Q_RES","I42": #LOCATION = "R2578" !CDS_LOCATION = "R2578" &SEC = "1" #&CDS_SEC = "1";
"A":   PN = "1"  !CDS_PN = "1";
"B":   PN = "2"  !CDS_PN = "2";
BODY = "Q_RES","I43": #LOCATION = "R2577" !CDS_LOCATION = "R2577" &SEC = "1" #&CDS_SEC = "1";
"A":   PN = "1"  !CDS_PN = "1";
"B":   PN = "2"  !CDS_PN = "2";
BODY = "Q_RES","I44": #LOCATION = "R2576" !CDS_LOCATION = "R2576" &SEC = "1" #&CDS_SEC = "1";
"A":   PN = "1"  !CDS_PN = "1";
"B":   PN = "2"  !CDS_PN = "2";
BODY = "Q_RES","I59": #LOCATION = "PR4257" !CDS_LOCATION = "PR4257" &SEC = "1" #&CDS_SEC = "1";
"A":   PN = "1"  !CDS_PN = "1";
"B":   PN = "2"  !CDS_PN = "2";
BODY = "Q_RES","I62": #LOCATION = "PR4255" !CDS_LOCATION = "PR4255" &SEC = "1" #&CDS_SEC = "1";
"A":   PN = "1"  !CDS_PN = "1";
"B":   PN = "2"  !CDS_PN = "2";
BODY = "Q_RES","I64": #LOCATION = "PR4252" !CDS_LOCATION = "PR4252" &SEC = "1" #&CDS_SEC = "1";
"A":   PN = "1"  !CDS_PN = "1";
"B":   PN = "2"  !CDS_PN = "2";
BODY = "Q_RES","I65": #LOCATION = "PR4253" !CDS_LOCATION = "PR4253" &SEC = "1" #&CDS_SEC = "1";
"A":   PN = "1"  !CDS_PN = "1";
"B":   PN = "2"  !CDS_PN = "2";
BODY = "Q_RES","I66": #LOCATION = "PR4254" !CDS_LOCATION = "PR4254" &SEC = "1" #&CDS_SEC = "1";
"A":   PN = "1"  !CDS_PN = "1";
"B":   PN = "2"  !CDS_PN = "2";
BODY = "Q_CAP","I77": #LOCATION = "PC394" !CDS_LOCATION = "PC394" &SEC = "1" #&CDS_SEC = "1";
"A":   PN = "1"  !CDS_PN = "1";
"B":   PN = "2"  !CDS_PN = "2";
BODY = "Q_RES","I78": #LOCATION = "PR220" !CDS_LOCATION = "PR220" &SEC = "1" #&CDS_SEC = "1";
"A":   PN = "1"  !CDS_PN = "1";
"B":   PN = "2"  !CDS_PN = "2";
BODY = "Q_RES","I95": #LOCATION = "PR203" !CDS_LOCATION = "PR203" &SEC = "1" #&CDS_SEC = "1";
"A":   PN = "1"  !CDS_PN = "1";
"B":   PN = "2"  !CDS_PN = "2";
BODY = "Q_CAP","I96": #LOCATION = "PC2368" !CDS_LOCATION = "PC2368" &SEC = "1" #&CDS_SEC = "1";
"A":   PN = "1"  !CDS_PN = "1";
"B":   PN = "2"  !CDS_PN = "2";
DRAWING = "@s9s_mb_2u_lib.s9s_mb_2u(sch_1):page286";
BODY = "Q_CAP","I6": #LOCATION = "C1308" !CDS_LOCATION = "C1308" &SEC = "1" #&CDS_SEC = "1";
"A":   PN = "1"  !CDS_PN = "1";
"B":   PN = "2"  !CDS_PN = "2";
BODY = "Q_RES","I26": #LOCATION = "PR51" !CDS_LOCATION = "PR51" #SEC = "1" !CDS_SEC = "1";
"A":   PN = "1"  !CDS_PN = "1";
"B":   PN = "2"  !CDS_PN = "2";
BODY = "Q_INDUCTOR","I27": #LOCATION = "PL121" !CDS_LOCATION = "PL121" &SEC = "1" #&CDS_SEC = "1";
"1":   PN = "1"  !CDS_PN = "1";
"2":   PN = "2"  !CDS_PN = "2";
BODY = "Q_RES","I29": #LOCATION = "R2387" !CDS_LOCATION = "R2387" &SEC = "1" #&CDS_SEC = "1";
"A":   PN = "1"  !CDS_PN = "1";
"B":   PN = "2"  !CDS_PN = "2";
BODY = "Q_RES","I31": #LOCATION = "R2584" !CDS_LOCATION = "R2584" &SEC = "1" #&CDS_SEC = "1";
"A":   PN = "1"  !CDS_PN = "1";
"B":   PN = "2"  !CDS_PN = "2";
BODY = "Q_CAP","I16": #LOCATION = "PC1282" !CDS_LOCATION = "PC1282" &SEC = "1" #&CDS_SEC = "1";
"A":   PN = "1"  !CDS_PN = "1";
"B":   PN = "2"  !CDS_PN = "2";
BODY = "Q_CAP","I23": #LOCATION = "PC28" !CDS_LOCATION = "PC28" &SEC = "1" #&CDS_SEC = "1";
"A":   PN = "1"  !CDS_PN = "1";
"B":   PN = "2"  !CDS_PN = "2";
BODY = "Q_RES","I42": #LOCATION = "PR4700" !CDS_LOCATION = "PR4700" &SEC = "1" #&CDS_SEC = "1";
"A":   PN = "1"  !CDS_PN = "1";
"B":   PN = "2"  !CDS_PN = "2";
BODY = "Q_CAP","I44": #LOCATION = "PC1287" !CDS_LOCATION = "PC1287" &SEC = "1" #&CDS_SEC = "1";
"A":   PN = "1"  !CDS_PN = "1";
"B":   PN = "2"  !CDS_PN = "2";
BODY = "Q_CAP","I9": #LOCATION = "PC1280" !CDS_LOCATION = "PC1280" &SEC = "1" #&CDS_SEC = "1";
"A":   PN = "1"  !CDS_PN = "1";
"B":   PN = "2"  !CDS_PN = "2";
BODY = "Q_RES","I13": #LOCATION = "PR3338" !CDS_LOCATION = "PR3338" &SEC = "1" #&CDS_SEC = "1";
"A":   PN = "1"  !CDS_PN = "1";
"B":   PN = "2"  !CDS_PN = "2";
BODY = "RS53317LR","I20": #LOCATION = "PU82" !CDS_LOCATION = "PU82" #SEC = "1" !CDS_SEC = "1";
"AGND":   PN = "7"  !CDS_PN = "7";
"BST":   PN = "10"  !CDS_PN = "10";
"CS":   PN = "4"  !CDS_PN = "4";
"EN":   PN = "5"  !CDS_PN = "5";
"FB":   PN = "6"  !CDS_PN = "6";
"MODE":   PN = "12"  !CDS_PN = "12";
"PGND1":   PN = "1"  !CDS_PN = "1";
"PGND2":   PN = "14"  !CDS_PN = "14";
"PGOOD":   PN = "9"  !CDS_PN = "9";
"REF":   PN = "8"  !CDS_PN = "8";
"SW1":   PN = "2"  !CDS_PN = "2";
"SW2":   PN = "11"  !CDS_PN = "11";
"VCC":   PN = "13"  !CDS_PN = "13";
"VIN":   PN = "3"  !CDS_PN = "3";
BODY = "Q_RES","I34": #LOCATION = "PR502" !CDS_LOCATION = "PR502" &SEC = "1" #&CDS_SEC = "1";
"A":   PN = "1"  !CDS_PN = "1";
"B":   PN = "2"  !CDS_PN = "2";
BODY = "Q_CAP","I36": #LOCATION = "PC1285" !CDS_LOCATION = "PC1285" &SEC = "1" #&CDS_SEC = "1";
"A":   PN = "1"  !CDS_PN = "1";
"B":   PN = "2"  !CDS_PN = "2";
BODY = "Q_RES","I22": #LOCATION = "PR2" !CDS_LOCATION = "PR2" &SEC = "1" #&CDS_SEC = "1";
"A":   PN = "1"  !CDS_PN = "1";
"B":   PN = "2"  !CDS_PN = "2";
BODY = "Q_RES","I25": #LOCATION = "PR4272" !CDS_LOCATION = "PR4272" #SEC = "1" !CDS_SEC = "1";
"A":   PN = "1"  !CDS_PN = "1";
"B":   PN = "2"  !CDS_PN = "2";
BODY = "Q_CAP","I33": #LOCATION = "PC238" !CDS_LOCATION = "PC238" &SEC = "1" #&CDS_SEC = "1";
"A":   PN = "1"  !CDS_PN = "1";
"B":   PN = "2"  !CDS_PN = "2";
BODY = "Q_CAP","I38": #LOCATION = "PC1286" !CDS_LOCATION = "PC1286" &SEC = "1" #&CDS_SEC = "1";
"A":   PN = "1"  !CDS_PN = "1";
"B":   PN = "2"  !CDS_PN = "2";
BODY = "Q_RES","I43": #LOCATION = "PR4699" !CDS_LOCATION = "PR4699" &SEC = "1" #&CDS_SEC = "1";
"A":   PN = "1"  !CDS_PN = "1";
"B":   PN = "2"  !CDS_PN = "2";
BODY = "Q_RES","I5": #LOCATION = "R2384" !CDS_LOCATION = "R2384" &SEC = "1" #&CDS_SEC = "1";
"A":   PN = "1"  !CDS_PN = "1";
"B":   PN = "2"  !CDS_PN = "2";
BODY = "Q_RES","I7": #LOCATION = "R2385" !CDS_LOCATION = "R2385" &SEC = "1" #&CDS_SEC = "1";
"A":   PN = "1"  !CDS_PN = "1";
"B":   PN = "2"  !CDS_PN = "2";
BODY = "Q_CAP","I10": #LOCATION = "PC2222" !CDS_LOCATION = "PC2222" #SEC = "1" !CDS_SEC = "1";
"A":   PN = "1"  !CDS_PN = "1";
"B":   PN = "2"  !CDS_PN = "2";
BODY = "Q_RES","I12": #LOCATION = "PR2220" !CDS_LOCATION = "PR2220" &SEC = "1" #&CDS_SEC = "1";
"A":   PN = "1"  !CDS_PN = "1";
"B":   PN = "2"  !CDS_PN = "2";
BODY = "Q_CAP","I14": #LOCATION = "PC1281" !CDS_LOCATION = "PC1281" &SEC = "1" #&CDS_SEC = "1";
"A":   PN = "1"  !CDS_PN = "1";
"B":   PN = "2"  !CDS_PN = "2";
BODY = "Q_RES","I19": #LOCATION = "PR2222" !CDS_LOCATION = "PR2222" &SEC = "1" #&CDS_SEC = "1";
"A":   PN = "1"  !CDS_PN = "1";
"B":   PN = "2"  !CDS_PN = "2";
BODY = "Q_CAP","I24": #LOCATION = "PC1283" !CDS_LOCATION = "PC1283" &SEC = "1" #&CDS_SEC = "1";
"A":   PN = "1"  !CDS_PN = "1";
"B":   PN = "2"  !CDS_PN = "2";
BODY = "Q_CAP","I28": #LOCATION = "PC1284" !CDS_LOCATION = "PC1284" &SEC = "1" #&CDS_SEC = "1";
"A":   PN = "1"  !CDS_PN = "1";
"B":   PN = "2"  !CDS_PN = "2";
BODY = "Q_CAP","I37": #LOCATION = "C1297" !CDS_LOCATION = "C1297" &SEC = "1" #&CDS_SEC = "1";
"A":   PN = "1"  !CDS_PN = "1";
"B":   PN = "2"  !CDS_PN = "2";
BODY = "Q_CAP","I40": #LOCATION = "PC2277" !CDS_LOCATION = "PC2277" &SEC = "1" #&CDS_SEC = "1";
"A":   PN = "1"  !CDS_PN = "1";
"B":   PN = "2"  !CDS_PN = "2";
BODY = "Q_CAP","I45": #LOCATION = "PC1207" !CDS_LOCATION = "PC1207" &SEC = "1" #&CDS_SEC = "1";
"A":   PN = "1"  !CDS_PN = "1";
"B":   PN = "2"  !CDS_PN = "2";
DRAWING = "@s9s_mb_2u_lib.s9s_mb_2u(sch_1):page143";
BODY = "Q_CAP","I2": LOCATION = "C2264" #&CDS_LOCATION = "C2264" &SEC = "1" #&CDS_SEC = "1";
"A":   PN = "1"  !CDS_PN = "1";
"B":   PN = "2"  !CDS_PN = "2";
BODY = "Q_RES","I5": LOCATION = "R4128" #&CDS_LOCATION = "R4128" &SEC = "1" #&CDS_SEC = "1";
"A":   PN = "1"  !CDS_PN = "1";
"B":   PN = "2"  !CDS_PN = "2";
BODY = "MOSFET_NCH_DUAL","I6": #LOCATION = "Q128" !CDS_LOCATION = "Q128" &SEC = "2" #&CDS_SEC = "2";
"D2":   PN = "3"  !CDS_PN = "3";
"G2":   PN = "5"  !CDS_PN = "5";
"S2":   PN = "4"  !CDS_PN = "4";
BODY = "Q_RES","I9": LOCATION = "R4125" #&CDS_LOCATION = "R4125" &SEC = "1" #&CDS_SEC = "1";
"A":   PN = "1"  !CDS_PN = "1";
"B":   PN = "2"  !CDS_PN = "2";
BODY = "MOSFET_NCH_DUAL","I11": LOCATION = "Q128" #&CDS_LOCATION = "Q128" &SEC = "1" #&CDS_SEC = "1";
"D1":   PN = "6"  !CDS_PN = "6";
"G1":   PN = "2"  !CDS_PN = "2";
"S1":   PN = "1"  !CDS_PN = "1";
BODY = "Q_RES","I13": LOCATION = "R4119" #&CDS_LOCATION = "R4119" &SEC = "1" #&CDS_SEC = "1";
"A":   PN = "1"  !CDS_PN = "1";
"B":   PN = "2"  !CDS_PN = "2";
BODY = "Q_RES","I14": LOCATION = "R4120" #&CDS_LOCATION = "R4120" &SEC = "1" #&CDS_SEC = "1";
"A":   PN = "1"  !CDS_PN = "1";
"B":   PN = "2"  !CDS_PN = "2";
BODY = "MOSFET_NCH_DUAL","I19": LOCATION = "Q131" #&CDS_LOCATION = "Q131" &SEC = "2" #&CDS_SEC = "2";
"D2":   PN = "3"  !CDS_PN = "3";
"G2":   PN = "5"  !CDS_PN = "5";
"S2":   PN = "4"  !CDS_PN = "4";
BODY = "Q_RES","I21": LOCATION = "R4130" #&CDS_LOCATION = "R4130" &SEC = "1" #&CDS_SEC = "1";
"A":   PN = "1"  !CDS_PN = "1";
"B":   PN = "2"  !CDS_PN = "2";
BODY = "Q_CAP","I23": LOCATION = "C2266" #&CDS_LOCATION = "C2266" &SEC = "1" #&CDS_SEC = "1";
"A":   PN = "1"  !CDS_PN = "1";
"B":   PN = "2"  !CDS_PN = "2";
BODY = "Q_RES","I27": LOCATION = "R4127" #&CDS_LOCATION = "R4127" &SEC = "1" #&CDS_SEC = "1";
"A":   PN = "1"  !CDS_PN = "1";
"B":   PN = "2"  !CDS_PN = "2";
BODY = "MOSFET_NCH_DUAL","I29": #LOCATION = "Q131" !CDS_LOCATION = "Q131" &SEC = "1" #&CDS_SEC = "1";
"D1":   PN = "6"  !CDS_PN = "6";
"G1":   PN = "2"  !CDS_PN = "2";
"S1":   PN = "1"  !CDS_PN = "1";
BODY = "Q_RES","I31": LOCATION = "R4123" #&CDS_LOCATION = "R4123" &SEC = "1" #&CDS_SEC = "1";
"A":   PN = "1"  !CDS_PN = "1";
"B":   PN = "2"  !CDS_PN = "2";
BODY = "Q_RES","I32": LOCATION = "R4124" #&CDS_LOCATION = "R4124" &SEC = "1" #&CDS_SEC = "1";
"A":   PN = "1"  !CDS_PN = "1";
"B":   PN = "2"  !CDS_PN = "2";
BODY = "MOSFET_NCH_DUAL","I35": LOCATION = "Q132" #&CDS_LOCATION = "Q132" &SEC = "2" #&CDS_SEC = "2";
"D2":   PN = "3"  !CDS_PN = "3";
"G2":   PN = "5"  !CDS_PN = "5";
"S2":   PN = "4"  !CDS_PN = "4";
BODY = "Q_RES","I36": LOCATION = "R4129" #&CDS_LOCATION = "R4129" &SEC = "1" #&CDS_SEC = "1";
"A":   PN = "1"  !CDS_PN = "1";
"B":   PN = "2"  !CDS_PN = "2";
BODY = "Q_CAP","I40": LOCATION = "C2265" #&CDS_LOCATION = "C2265" &SEC = "1" #&CDS_SEC = "1";
"A":   PN = "1"  !CDS_PN = "1";
"B":   PN = "2"  !CDS_PN = "2";
BODY = "Q_RES","I43": LOCATION = "R4126" #&CDS_LOCATION = "R4126" &SEC = "1" #&CDS_SEC = "1";
"A":   PN = "1"  !CDS_PN = "1";
"B":   PN = "2"  !CDS_PN = "2";
BODY = "MOSFET_NCH_DUAL","I44": #LOCATION = "Q132" !CDS_LOCATION = "Q132" &SEC = "1" #&CDS_SEC = "1";
"D1":   PN = "6"  !CDS_PN = "6";
"G1":   PN = "2"  !CDS_PN = "2";
"S1":   PN = "1"  !CDS_PN = "1";
BODY = "Q_RES","I49": LOCATION = "R4122" #&CDS_LOCATION = "R4122" &SEC = "1" #&CDS_SEC = "1";
"A":   PN = "1"  !CDS_PN = "1";
"B":   PN = "2"  !CDS_PN = "2";
BODY = "Q_RES","I52": LOCATION = "R4140" #&CDS_LOCATION = "R4140" &SEC = "1" #&CDS_SEC = "1";
"A":   PN = "1"  !CDS_PN = "1";
"B":   PN = "2"  !CDS_PN = "2";
BODY = "Q_CAP","I55": LOCATION = "C2267" #&CDS_LOCATION = "C2267" &SEC = "1" #&CDS_SEC = "1";
"A":   PN = "1"  !CDS_PN = "1";
"B":   PN = "2"  !CDS_PN = "2";
BODY = "Q_CAP","I57": LOCATION = "C2269" #&CDS_LOCATION = "C2269" &SEC = "1" #&CDS_SEC = "1";
"A":   PN = "1"  !CDS_PN = "1";
"B":   PN = "2"  !CDS_PN = "2";
BODY = "Q_RES","I60": LOCATION = "R4142" #&CDS_LOCATION = "R4142" &SEC = "1" #&CDS_SEC = "1";
"A":   PN = "1"  !CDS_PN = "1";
"B":   PN = "2"  !CDS_PN = "2";
BODY = "Q_RES","I64": LOCATION = "R4141" #&CDS_LOCATION = "R4141" &SEC = "1" #&CDS_SEC = "1";
"A":   PN = "1"  !CDS_PN = "1";
"B":   PN = "2"  !CDS_PN = "2";
BODY = "Q_CAP","I66": LOCATION = "C2268" #&CDS_LOCATION = "C2268" &SEC = "1" #&CDS_SEC = "1";
"A":   PN = "1"  !CDS_PN = "1";
"B":   PN = "2"  !CDS_PN = "2";
BODY = "MOSFET_NCH_DUAL","I70": LOCATION = "Q130" #&CDS_LOCATION = "Q130" &SEC = "2" #&CDS_SEC = "2";
"D2":   PN = "3"  !CDS_PN = "3";
"G2":   PN = "5"  !CDS_PN = "5";
"S2":   PN = "4"  !CDS_PN = "4";
BODY = "MOSFET_NCH_DUAL","I71": #LOCATION = "Q133" !CDS_LOCATION = "Q133" &SEC = "2" #&CDS_SEC = "2";
"D2":   PN = "3"  !CDS_PN = "3";
"G2":   PN = "5"  !CDS_PN = "5";
"S2":   PN = "4"  !CDS_PN = "4";
BODY = "Q_RES","I72": LOCATION = "R4137" #&CDS_LOCATION = "R4137" &SEC = "1" #&CDS_SEC = "1";
"A":   PN = "1"  !CDS_PN = "1";
"B":   PN = "2"  !CDS_PN = "2";
BODY = "MOSFET_NCH_DUAL","I74": #LOCATION = "Q130" !CDS_LOCATION = "Q130" &SEC = "1" #&CDS_SEC = "1";
"D1":   PN = "6"  !CDS_PN = "6";
"G1":   PN = "2"  !CDS_PN = "2";
"S1":   PN = "1"  !CDS_PN = "1";
BODY = "Q_RES","I76": LOCATION = "R4139" #&CDS_LOCATION = "R4139" &SEC = "1" #&CDS_SEC = "1";
"A":   PN = "1"  !CDS_PN = "1";
"B":   PN = "2"  !CDS_PN = "2";
BODY = "MOSFET_NCH_DUAL","I77": LOCATION = "Q129" #&CDS_LOCATION = "Q129" &SEC = "2" #&CDS_SEC = "2";
"D2":   PN = "3"  !CDS_PN = "3";
"G2":   PN = "5"  !CDS_PN = "5";
"S2":   PN = "4"  !CDS_PN = "4";
BODY = "MOSFET_NCH_DUAL","I78": LOCATION = "Q133" #&CDS_LOCATION = "Q133" &SEC = "1" #&CDS_SEC = "1";
"D1":   PN = "6"  !CDS_PN = "6";
"G1":   PN = "2"  !CDS_PN = "2";
"S1":   PN = "1"  !CDS_PN = "1";
BODY = "Q_RES","I81": LOCATION = "R4138" #&CDS_LOCATION = "R4138" &SEC = "1" #&CDS_SEC = "1";
"A":   PN = "1"  !CDS_PN = "1";
"B":   PN = "2"  !CDS_PN = "2";
BODY = "MOSFET_NCH_DUAL","I83": #LOCATION = "Q129" !CDS_LOCATION = "Q129" &SEC = "1" #&CDS_SEC = "1";
"D1":   PN = "6"  !CDS_PN = "6";
"G1":   PN = "2"  !CDS_PN = "2";
"S1":   PN = "1"  !CDS_PN = "1";
BODY = "Q_RES","I85": LOCATION = "R4131" #&CDS_LOCATION = "R4131" &SEC = "1" #&CDS_SEC = "1";
"A":   PN = "1"  !CDS_PN = "1";
"B":   PN = "2"  !CDS_PN = "2";
BODY = "Q_RES","I86": LOCATION = "R4132" #&CDS_LOCATION = "R4132" &SEC = "1" #&CDS_SEC = "1";
"A":   PN = "1"  !CDS_PN = "1";
"B":   PN = "2"  !CDS_PN = "2";
BODY = "Q_RES","I91": LOCATION = "R4136" #&CDS_LOCATION = "R4136" &SEC = "1" #&CDS_SEC = "1";
"A":   PN = "1"  !CDS_PN = "1";
"B":   PN = "2"  !CDS_PN = "2";
BODY = "Q_RES","I95": LOCATION = "R4133" #&CDS_LOCATION = "R4133" &SEC = "1" #&CDS_SEC = "1";
"A":   PN = "1"  !CDS_PN = "1";
"B":   PN = "2"  !CDS_PN = "2";
BODY = "Q_RES","I96": LOCATION = "R4134" #&CDS_LOCATION = "R4134" &SEC = "1" #&CDS_SEC = "1";
"A":   PN = "1"  !CDS_PN = "1";
"B":   PN = "2"  !CDS_PN = "2";
BODY = "MOSFET_NCH_DUAL","I99": LOCATION = "Q134" #&CDS_LOCATION = "Q134" &SEC = "1" #&CDS_SEC = "1";
"D1":   PN = "6"  !CDS_PN = "6";
"G1":   PN = "2"  !CDS_PN = "2";
"S1":   PN = "1"  !CDS_PN = "1";
BODY = "Q_RES","I100": LOCATION = "R4155" #&CDS_LOCATION = "R4155" &SEC = "1" #&CDS_SEC = "1";
"A":   PN = "1"  !CDS_PN = "1";
"B":   PN = "2"  !CDS_PN = "2";
BODY = "Q_RES","I101": LOCATION = "R4156" #&CDS_LOCATION = "R4156" &SEC = "1" #&CDS_SEC = "1";
"A":   PN = "1"  !CDS_PN = "1";
"B":   PN = "2"  !CDS_PN = "2";
BODY = "Q_CAP","I105": LOCATION = "C2270" #&CDS_LOCATION = "C2270" &SEC = "1" #&CDS_SEC = "1";
"A":   PN = "1"  !CDS_PN = "1";
"B":   PN = "2"  !CDS_PN = "2";
BODY = "MOSFET_NCH_DUAL","I107": LOCATION = "Q134" #&CDS_LOCATION = "Q134" &SEC = "2" #&CDS_SEC = "2";
"D2":   PN = "3"  !CDS_PN = "3";
"G2":   PN = "5"  !CDS_PN = "5";
"S2":   PN = "4"  !CDS_PN = "4";
BODY = "Q_RES","I113": LOCATION = "R4154" #&CDS_LOCATION = "R4154" &SEC = "1" #&CDS_SEC = "1";
"A":   PN = "1"  !CDS_PN = "1";
"B":   PN = "2"  !CDS_PN = "2";
BODY = "Q_RES","I116": LOCATION = "R4561" #&CDS_LOCATION = "R4561" &SEC = "1" #&CDS_SEC = "1";
"A":   PN = "1"  !CDS_PN = "1";
"B":   PN = "2"  !CDS_PN = "2";
BODY = "Q_CAP","I118": LOCATION = "C2343" #&CDS_LOCATION = "C2343" &SEC = "1" #&CDS_SEC = "1";
"A":   PN = "1"  !CDS_PN = "1";
"B":   PN = "2"  !CDS_PN = "2";
BODY = "MOSFET_NCH_DUAL","I121": #LOCATION = "Q146" !CDS_LOCATION = "Q146" &SEC = "2" #&CDS_SEC = "2";
"D2":   PN = "3"  !CDS_PN = "3";
"G2":   PN = "5"  !CDS_PN = "5";
"S2":   PN = "4"  !CDS_PN = "4";
BODY = "Q_RES","I124": LOCATION = "R4560" #&CDS_LOCATION = "R4560" &SEC = "1" #&CDS_SEC = "1";
"A":   PN = "1"  !CDS_PN = "1";
"B":   PN = "2"  !CDS_PN = "2";
BODY = "MOSFET_NCH_DUAL","I126": LOCATION = "Q146" #&CDS_LOCATION = "Q146" &SEC = "1" #&CDS_SEC = "1";
"D1":   PN = "6"  !CDS_PN = "6";
"G1":   PN = "2"  !CDS_PN = "2";
"S1":   PN = "1"  !CDS_PN = "1";
BODY = "Q_RES","I129": LOCATION = "R4559" #&CDS_LOCATION = "R4559" &SEC = "1" #&CDS_SEC = "1";
"A":   PN = "1"  !CDS_PN = "1";
"B":   PN = "2"  !CDS_PN = "2";
BODY = "Q_RES","I132": LOCATION = "R4562" #&CDS_LOCATION = "R4562" &SEC = "1" #&CDS_SEC = "1";
"A":   PN = "1"  !CDS_PN = "1";
"B":   PN = "2"  !CDS_PN = "2";
BODY = "Q_RES","I136": LOCATION = "R4574" #&CDS_LOCATION = "R4574" &SEC = "1" #&CDS_SEC = "1";
"A":   PN = "1"  !CDS_PN = "1";
"B":   PN = "2"  !CDS_PN = "2";
BODY = "Q_RES","I137": LOCATION = "R4577" #&CDS_LOCATION = "R4577" &SEC = "1" #&CDS_SEC = "1";
"A":   PN = "1"  !CDS_PN = "1";
"B":   PN = "2"  !CDS_PN = "2";
BODY = "Q_RES","I138": LOCATION = "R4578" #&CDS_LOCATION = "R4578" &SEC = "1" #&CDS_SEC = "1";
"A":   PN = "1"  !CDS_PN = "1";
"B":   PN = "2"  !CDS_PN = "2";
BODY = "Q_RES","I139": LOCATION = "R4576" #&CDS_LOCATION = "R4576" &SEC = "1" #&CDS_SEC = "1";
"A":   PN = "1"  !CDS_PN = "1";
"B":   PN = "2"  !CDS_PN = "2";
BODY = "Q_RES","I140": LOCATION = "R4573" #&CDS_LOCATION = "R4573" &SEC = "1" #&CDS_SEC = "1";
"A":   PN = "1"  !CDS_PN = "1";
"B":   PN = "2"  !CDS_PN = "2";
BODY = "Q_RES","I141": LOCATION = "R4572" #&CDS_LOCATION = "R4572" &SEC = "1" #&CDS_SEC = "1";
"A":   PN = "1"  !CDS_PN = "1";
"B":   PN = "2"  !CDS_PN = "2";
BODY = "Q_RES","I142": LOCATION = "R4575" #&CDS_LOCATION = "R4575" &SEC = "1" #&CDS_SEC = "1";
"A":   PN = "1"  !CDS_PN = "1";
"B":   PN = "2"  !CDS_PN = "2";
BODY = "Q_RES","I143": #LOCATION = "R4121" !CDS_LOCATION = "R4121" &SEC = "1" #&CDS_SEC = "1";
"A":   PN = "1"  !CDS_PN = "1";
"B":   PN = "2"  !CDS_PN = "2";
BODY = "Q_RES","I144": #LOCATION = "R4135" !CDS_LOCATION = "R4135" &SEC = "1" #&CDS_SEC = "1";
"A":   PN = "1"  !CDS_PN = "1";
"B":   PN = "2"  !CDS_PN = "2";
BODY = "Q_RES","I145": #LOCATION = "R4153" !CDS_LOCATION = "R4153" &SEC = "1" #&CDS_SEC = "1";
"A":   PN = "1"  !CDS_PN = "1";
"B":   PN = "2"  !CDS_PN = "2";
DRAWING = "@s9s_mb_2u_lib.s9s_mb_2u(sch_1):page139";
BODY = "Q_RES","I2": LOCATION = "R4161" #&CDS_LOCATION = "R4161" &SEC = "1" #&CDS_SEC = "1";
"A":   PN = "1"  !CDS_PN = "1";
"B":   PN = "2"  !CDS_PN = "2";
BODY = "Q_RES","I4": LOCATION = "R4160" #&CDS_LOCATION = "R4160" &SEC = "1" #&CDS_SEC = "1";
"A":   PN = "1"  !CDS_PN = "1";
"B":   PN = "2"  !CDS_PN = "2";
BODY = "Q_RES","I8": LOCATION = "R4163" #&CDS_LOCATION = "R4163" &SEC = "1" #&CDS_SEC = "1";
"A":   PN = "1"  !CDS_PN = "1";
"B":   PN = "2"  !CDS_PN = "2";
BODY = "Q_RES","I9": LOCATION = "R4162" #&CDS_LOCATION = "R4162" &SEC = "1" #&CDS_SEC = "1";
"A":   PN = "1"  !CDS_PN = "1";
"B":   PN = "2"  !CDS_PN = "2";
BODY = "Q_RES","I13": LOCATION = "R4159" #&CDS_LOCATION = "R4159" &SEC = "1" #&CDS_SEC = "1";
"A":   PN = "1"  !CDS_PN = "1";
"B":   PN = "2"  !CDS_PN = "2";
BODY = "Q_RES","I14": LOCATION = "R4158" #&CDS_LOCATION = "R4158" &SEC = "1" #&CDS_SEC = "1";
"A":   PN = "1"  !CDS_PN = "1";
"B":   PN = "2"  !CDS_PN = "2";
BODY = "MOSFET_NCH_DUAL","I17": LOCATION = "Q136" #&CDS_LOCATION = "Q136" &SEC = "1" #&CDS_SEC = "1";
"D1":   PN = "6"  !CDS_PN = "6";
"G1":   PN = "2"  !CDS_PN = "2";
"S1":   PN = "1"  !CDS_PN = "1";
BODY = "Q_RES","I18": LOCATION = "R4165" #&CDS_LOCATION = "R4165" &SEC = "1" #&CDS_SEC = "1";
"A":   PN = "1"  !CDS_PN = "1";
"B":   PN = "2"  !CDS_PN = "2";
BODY = "MOSFET_NCH_DUAL","I21": LOCATION = "Q137" #&CDS_LOCATION = "Q137" &SEC = "1" #&CDS_SEC = "1";
"D1":   PN = "6"  !CDS_PN = "6";
"G1":   PN = "2"  !CDS_PN = "2";
"S1":   PN = "1"  !CDS_PN = "1";
BODY = "MOSFET_NCH_DUAL","I22": LOCATION = "Q136" #&CDS_LOCATION = "Q136" &SEC = "2" #&CDS_SEC = "2";
"D2":   PN = "3"  !CDS_PN = "3";
"G2":   PN = "5"  !CDS_PN = "5";
"S2":   PN = "4"  !CDS_PN = "4";
BODY = "Q_RES","I23": LOCATION = "R4166" #&CDS_LOCATION = "R4166" &SEC = "1" #&CDS_SEC = "1";
"A":   PN = "1"  !CDS_PN = "1";
"B":   PN = "2"  !CDS_PN = "2";
BODY = "MOSFET_NCH_DUAL","I25": LOCATION = "Q135" #&CDS_LOCATION = "Q135" &SEC = "1" #&CDS_SEC = "1";
"D1":   PN = "6"  !CDS_PN = "6";
"G1":   PN = "2"  !CDS_PN = "2";
"S1":   PN = "1"  !CDS_PN = "1";
BODY = "Q_RES","I27": LOCATION = "R4164" #&CDS_LOCATION = "R4164" &SEC = "1" #&CDS_SEC = "1";
"A":   PN = "1"  !CDS_PN = "1";
"B":   PN = "2"  !CDS_PN = "2";
BODY = "MOSFET_NCH_DUAL","I28": #LOCATION = "Q137" !CDS_LOCATION = "Q137" &SEC = "2" #&CDS_SEC = "2";
"D2":   PN = "3"  !CDS_PN = "3";
"G2":   PN = "5"  !CDS_PN = "5";
"S2":   PN = "4"  !CDS_PN = "4";
BODY = "MOSFET_NCH_DUAL","I29": #LOCATION = "Q135" !CDS_LOCATION = "Q135" &SEC = "2" #&CDS_SEC = "2";
"D2":   PN = "3"  !CDS_PN = "3";
"G2":   PN = "5"  !CDS_PN = "5";
"S2":   PN = "4"  !CDS_PN = "4";
BODY = "Q_CAP","I33": LOCATION = "C2272" #&CDS_LOCATION = "C2272" &SEC = "1" #&CDS_SEC = "1";
"A":   PN = "1"  !CDS_PN = "1";
"B":   PN = "2"  !CDS_PN = "2";
BODY = "Q_RES","I35": LOCATION = "R4168" #&CDS_LOCATION = "R4168" &SEC = "1" #&CDS_SEC = "1";
"A":   PN = "1"  !CDS_PN = "1";
"B":   PN = "2"  !CDS_PN = "2";
BODY = "Q_RES","I39": LOCATION = "R4169" #&CDS_LOCATION = "R4169" &SEC = "1" #&CDS_SEC = "1";
"A":   PN = "1"  !CDS_PN = "1";
"B":   PN = "2"  !CDS_PN = "2";
BODY = "Q_CAP","I42": LOCATION = "C2273" #&CDS_LOCATION = "C2273" &SEC = "1" #&CDS_SEC = "1";
"A":   PN = "1"  !CDS_PN = "1";
"B":   PN = "2"  !CDS_PN = "2";
BODY = "Q_CAP","I44": LOCATION = "C2271" #&CDS_LOCATION = "C2271" &SEC = "1" #&CDS_SEC = "1";
"A":   PN = "1"  !CDS_PN = "1";
"B":   PN = "2"  !CDS_PN = "2";
BODY = "Q_RES","I47": LOCATION = "R4167" #&CDS_LOCATION = "R4167" &SEC = "1" #&CDS_SEC = "1";
"A":   PN = "1"  !CDS_PN = "1";
"B":   PN = "2"  !CDS_PN = "2";
BODY = "Q_RES","I50": LOCATION = "R4546" #&CDS_LOCATION = "R4546" &SEC = "1" #&CDS_SEC = "1";
"A":   PN = "1"  !CDS_PN = "1";
"B":   PN = "2"  !CDS_PN = "2";
BODY = "Q_CAP","I52": LOCATION = "C2340" #&CDS_LOCATION = "C2340" &SEC = "1" #&CDS_SEC = "1";
"A":   PN = "1"  !CDS_PN = "1";
"B":   PN = "2"  !CDS_PN = "2";
BODY = "MOSFET_NCH_DUAL","I55": #LOCATION = "Q148" !CDS_LOCATION = "Q148" &SEC = "2" #&CDS_SEC = "2";
"D2":   PN = "3"  !CDS_PN = "3";
"G2":   PN = "5"  !CDS_PN = "5";
"S2":   PN = "4"  !CDS_PN = "4";
BODY = "Q_RES","I57": LOCATION = "R4545" #&CDS_LOCATION = "R4545" &SEC = "1" #&CDS_SEC = "1";
"A":   PN = "1"  !CDS_PN = "1";
"B":   PN = "2"  !CDS_PN = "2";
BODY = "MOSFET_NCH_DUAL","I61": LOCATION = "Q148" #&CDS_LOCATION = "Q148" &SEC = "1" #&CDS_SEC = "1";
"D1":   PN = "6"  !CDS_PN = "6";
"G1":   PN = "2"  !CDS_PN = "2";
"S1":   PN = "1"  !CDS_PN = "1";
BODY = "Q_RES","I62": LOCATION = "R4544" #&CDS_LOCATION = "R4544" &SEC = "1" #&CDS_SEC = "1";
"A":   PN = "1"  !CDS_PN = "1";
"B":   PN = "2"  !CDS_PN = "2";
BODY = "Q_RES","I85": #LOCATION = "R4543" !CDS_LOCATION = "R4543" &SEC = "1" #&CDS_SEC = "1";
"A":   PN = "1"  !CDS_PN = "1";
"B":   PN = "2"  !CDS_PN = "2";
BODY = "74LVC2G17GW","I86": #LOCATION = "U316" !CDS_LOCATION = "U316" #SEC = "1" !CDS_SEC = "1";
"A0":   PN = "1"  !CDS_PN = "1";
"A1":   PN = "3"  !CDS_PN = "3";
"B0":   PN = "6"  !CDS_PN = "6";
"B1":   PN = "4"  !CDS_PN = "4";
"GND":   PN = "2"  !CDS_PN = "2";
"VCC":   PN = "5"  !CDS_PN = "5";
BODY = "Q_RES","I87": #LOCATION = "R4548" !CDS_LOCATION = "R4548" &SEC = "1" #&CDS_SEC = "1";
"A":   PN = "1"  !CDS_PN = "1";
"B":   PN = "2"  !CDS_PN = "2";
BODY = "Q_RES","I89": LOCATION = "R4547" #&CDS_LOCATION = "R4547" &SEC = "1" #&CDS_SEC = "1";
"A":   PN = "1"  !CDS_PN = "1";
"B":   PN = "2"  !CDS_PN = "2";
BODY = "Q_CAP","I93": LOCATION = "C2341" #&CDS_LOCATION = "C2341" &SEC = "1" #&CDS_SEC = "1";
"A":   PN = "1"  !CDS_PN = "1";
"B":   PN = "2"  !CDS_PN = "2";
BODY = "Q_RES","I98": LOCATION = "R4549" #&CDS_LOCATION = "R4549" &SEC = "1" #&CDS_SEC = "1";
"A":   PN = "1"  !CDS_PN = "1";
"B":   PN = "2"  !CDS_PN = "2";
BODY = "Q_RES","I99": #LOCATION = "R4555" !CDS_LOCATION = "R4555" &SEC = "1" #&CDS_SEC = "1";
"A":   PN = "1"  !CDS_PN = "1";
"B":   PN = "2"  !CDS_PN = "2";
BODY = "Q_RES","I107": LOCATION = "R4569" #&CDS_LOCATION = "R4569" &SEC = "1" #&CDS_SEC = "1";
"A":   PN = "1"  !CDS_PN = "1";
"B":   PN = "2"  !CDS_PN = "2";
BODY = "Q_RES","I108": LOCATION = "R4571" #&CDS_LOCATION = "R4571" &SEC = "1" #&CDS_SEC = "1";
"A":   PN = "1"  !CDS_PN = "1";
"B":   PN = "2"  !CDS_PN = "2";
BODY = "Q_RES","I109": LOCATION = "R4570" #&CDS_LOCATION = "R4570" &SEC = "1" #&CDS_SEC = "1";
"A":   PN = "1"  !CDS_PN = "1";
"B":   PN = "2"  !CDS_PN = "2";
BODY = "Q_RES","I110": #LOCATION = "R4550" !CDS_LOCATION = "R4550" &SEC = "1" #&CDS_SEC = "1";
"A":   PN = "1"  !CDS_PN = "1";
"B":   PN = "2"  !CDS_PN = "2";
DRAWING = "@s9s_mb_2u_lib.s9s_mb_2u(sch_1):page162";
BODY = "Q_RES","I7": LOCATION = "R4281" #&CDS_LOCATION = "R4281" &SEC = "1" #&CDS_SEC = "1";
"A":   PN = "1"  !CDS_PN = "1";
"B":   PN = "2"  !CDS_PN = "2";
BODY = "Q_RES","I11": LOCATION = "R4274" #&CDS_LOCATION = "R4274" &SEC = "1" #&CDS_SEC = "1";
"A":   PN = "1"  !CDS_PN = "1";
"B":   PN = "2"  !CDS_PN = "2";
BODY = "Q_RES","I17": LOCATION = "R4280" #&CDS_LOCATION = "R4280" &SEC = "1" #&CDS_SEC = "1";
"A":   PN = "1"  !CDS_PN = "1";
"B":   PN = "2"  !CDS_PN = "2";
BODY = "Q_RES","I24": LOCATION = "R4637" #&CDS_LOCATION = "R4637" &SEC = "1" #&CDS_SEC = "1";
"A":   PN = "1"  !CDS_PN = "1";
"B":   PN = "2"  !CDS_PN = "2";
BODY = "Q_RES","I41": LOCATION = "R4284" #&CDS_LOCATION = "R4284" &SEC = "1" #&CDS_SEC = "1";
"A":   PN = "1"  !CDS_PN = "1";
"B":   PN = "2"  !CDS_PN = "2";
BODY = "Q_RES","I63": LOCATION = "R4292" #&CDS_LOCATION = "R4292" &SEC = "1" #&CDS_SEC = "1";
"A":   PN = "1"  !CDS_PN = "1";
"B":   PN = "2"  !CDS_PN = "2";
BODY = "Q_RES","I68": LOCATION = "R4290" #&CDS_LOCATION = "R4290" &SEC = "1" #&CDS_SEC = "1";
"A":   PN = "1"  !CDS_PN = "1";
"B":   PN = "2"  !CDS_PN = "2";
BODY = "Q_RES","I2": #LOCATION = "R4276" !CDS_LOCATION = "R4276" &SEC = "1" #&CDS_SEC = "1";
"A":   PN = "1"  !CDS_PN = "1";
"B":   PN = "2"  !CDS_PN = "2";
BODY = "Q_RES","I3": LOCATION = "R4275" #&CDS_LOCATION = "R4275" &SEC = "1" #&CDS_SEC = "1";
"A":   PN = "1"  !CDS_PN = "1";
"B":   PN = "2"  !CDS_PN = "2";
BODY = "Q_RES","I6": #LOCATION = "R4282" !CDS_LOCATION = "R4282" &SEC = "1" #&CDS_SEC = "1";
"A":   PN = "1"  !CDS_PN = "1";
"B":   PN = "2"  !CDS_PN = "2";
BODY = "Q_RES","I12": LOCATION = "R4273" #&CDS_LOCATION = "R4273" &SEC = "1" #&CDS_SEC = "1";
"A":   PN = "1"  !CDS_PN = "1";
"B":   PN = "2"  !CDS_PN = "2";
BODY = "Q_RES","I18": LOCATION = "R4279" #&CDS_LOCATION = "R4279" &SEC = "1" #&CDS_SEC = "1";
"A":   PN = "1"  !CDS_PN = "1";
"B":   PN = "2"  !CDS_PN = "2";
BODY = "Q_RES","I23": LOCATION = "R4636" #&CDS_LOCATION = "R4636" &SEC = "1" #&CDS_SEC = "1";
"A":   PN = "1"  !CDS_PN = "1";
"B":   PN = "2"  !CDS_PN = "2";
BODY = "Q_CAP_DIFFBUS","I25": #LOCATION = "C2350" !CDS_LOCATION = "C2350" &SEC = "1" #&CDS_SEC = "1";
"1":   PN = "1"  !CDS_PN = "1";
"2":   PN = "2"  !CDS_PN = "2";
BODY = "Q_CAP_DIFFBUS","I26": #LOCATION = "C2349" !CDS_LOCATION = "C2349" &SEC = "1" #&CDS_SEC = "1";
"1":   PN = "1"  !CDS_PN = "1";
"2":   PN = "2"  !CDS_PN = "2";
BODY = "Q_INDUCTOR","I35": LOCATION = "L18" #&CDS_LOCATION = "L18" &SEC = "1" #&CDS_SEC = "1";
"1":   PN = "1"  !CDS_PN = "1";
"2":   PN = "2"  !CDS_PN = "2";
BODY = "Q_CAP","I37": #LOCATION = "C2284" !CDS_LOCATION = "C2284" &SEC = "1" #&CDS_SEC = "1";
"A":   PN = "1"  !CDS_PN = "1";
"B":   PN = "2"  !CDS_PN = "2";
BODY = "Q_RES","I40": LOCATION = "R4285" #&CDS_LOCATION = "R4285" &SEC = "1" #&CDS_SEC = "1";
"A":   PN = "1"  !CDS_PN = "1";
"B":   PN = "2"  !CDS_PN = "2";
BODY = "PI3EQX1002EZREX","I43": #LOCATION = "U309" !CDS_LOCATION = "U309" &SEC = "1" #&CDS_SEC = "1";
"AIN":   PN = "7"  !CDS_PN = "7";
"AIP":   PN = "6"  !CDS_PN = "6";
"AON":   PN = "23"  !CDS_PN = "23";
"AOP":   PN = "24"  !CDS_PN = "24";
"BIN":   PN = "19"  !CDS_PN = "19";
"BIP":   PN = "18"  !CDS_PN = "18";
"BON":   PN = "11"  !CDS_PN = "11";
"BOP":   PN = "12"  !CDS_PN = "12";
"EN":   PN = "4"  !CDS_PN = "4";
"EQA":   PN = "1"  !CDS_PN = "1";
"EQB":   PN = "16"  !CDS_PN = "16";
"FGA":   PN = "2"  !CDS_PN = "2";
"FGB":   PN = "15"  !CDS_PN = "15";
"GND_1":   PN = "8"  !CDS_PN = "8";
"GND_2":   PN = "9"  !CDS_PN = "9";
"GND_3":   PN = "10"  !CDS_PN = "10";
"GND_4":   PN = "20"  !CDS_PN = "20";
"GND_5":   PN = "21"  !CDS_PN = "21";
"GND_6":   PN = "22"  !CDS_PN = "22";
"RXDET_EN":   PN = "13"  !CDS_PN = "13";
"SWA":   PN = "3"  !CDS_PN = "3";
"SWB":   PN = "14"  !CDS_PN = "14";
"TH_GND":   PN = "TH"  !CDS_PN = "TH";
"VDD_1":   PN = "5"  !CDS_PN = "5";
"VDD_2":   PN = "17"  !CDS_PN = "17";
BODY = "Q_CAP","I44": LOCATION = "C2285" #&CDS_LOCATION = "C2285" &SEC = "1" #&CDS_SEC = "1";
"A":   PN = "1"  !CDS_PN = "1";
"B":   PN = "2"  !CDS_PN = "2";
BODY = "Q_CAP","I45": LOCATION = "C2286" #&CDS_LOCATION = "C2286" &SEC = "1" #&CDS_SEC = "1";
"A":   PN = "1"  !CDS_PN = "1";
"B":   PN = "2"  !CDS_PN = "2";
BODY = "Q_RES","I48": LOCATION = "R4288" #&CDS_LOCATION = "R4288" &SEC = "1" #&CDS_SEC = "1";
"A":   PN = "1"  !CDS_PN = "1";
"B":   PN = "2"  !CDS_PN = "2";
BODY = "Q_RES","I49": LOCATION = "R4287" #&CDS_LOCATION = "R4287" &SEC = "1" #&CDS_SEC = "1";
"A":   PN = "1"  !CDS_PN = "1";
"B":   PN = "2"  !CDS_PN = "2";
BODY = "Q_CAP","I54": LOCATION = "C2292" #&CDS_LOCATION = "C2292" &SEC = "1" #&CDS_SEC = "1";
"A":   PN = "1"  !CDS_PN = "1";
"B":   PN = "2"  !CDS_PN = "2";
BODY = "Q_CAP","I55": LOCATION = "C2291" #&CDS_LOCATION = "C2291" &SEC = "1" #&CDS_SEC = "1";
"A":   PN = "1"  !CDS_PN = "1";
"B":   PN = "2"  !CDS_PN = "2";
BODY = "Q_CAP","I56": LOCATION = "C2290" #&CDS_LOCATION = "C2290" &SEC = "1" #&CDS_SEC = "1";
"A":   PN = "1"  !CDS_PN = "1";
"B":   PN = "2"  !CDS_PN = "2";
BODY = "Q_CAP","I57": LOCATION = "C2289" #&CDS_LOCATION = "C2289" &SEC = "1" #&CDS_SEC = "1";
"A":   PN = "1"  !CDS_PN = "1";
"B":   PN = "2"  !CDS_PN = "2";
BODY = "Q_RES","I65": LOCATION = "R4291" #&CDS_LOCATION = "R4291" &SEC = "1" #&CDS_SEC = "1";
"A":   PN = "1"  !CDS_PN = "1";
"B":   PN = "2"  !CDS_PN = "2";
BODY = "Q_RES","I69": LOCATION = "R4289" #&CDS_LOCATION = "R4289" &SEC = "1" #&CDS_SEC = "1";
"A":   PN = "1"  !CDS_PN = "1";
"B":   PN = "2"  !CDS_PN = "2";
DRAWING = "@s9s_mb_2u_lib.s9s_mb_2u(sch_1):page237";
BODY = "Q_RES","I43": #LOCATION = "PR3855" !CDS_LOCATION = "PR3855" &SEC = "1" #&CDS_SEC = "1";
"A":   PN = "1"  !CDS_PN = "1";
"B":   PN = "2"  !CDS_PN = "2";
BODY = "Q_CAP","I48": #LOCATION = "PC2169" !CDS_LOCATION = "PC2169" &SEC = "1" #&CDS_SEC = "1";
"A":   PN = "1"  !CDS_PN = "1";
"B":   PN = "2"  !CDS_PN = "2";
BODY = "Q_CAP","I54": #LOCATION = "PC1322" !CDS_LOCATION = "PC1322" &SEC = "1" #&CDS_SEC = "1";
"A":   PN = "1"  !CDS_PN = "1";
"B":   PN = "2"  !CDS_PN = "2";
BODY = "Q_CAP","I35": #LOCATION = "PC2168" !CDS_LOCATION = "PC2168" &SEC = "1" #&CDS_SEC = "1";
"A":   PN = "1"  !CDS_PN = "1";
"B":   PN = "2"  !CDS_PN = "2";
BODY = "Q_RES","I44": LOCATION = "R3631" #&CDS_LOCATION = "R3631" &SEC = "1" #&CDS_SEC = "1";
"A":   PN = "1"  !CDS_PN = "1";
"B":   PN = "2"  !CDS_PN = "2";
BODY = "Q_RES","I46": #LOCATION = "PR3856" !CDS_LOCATION = "PR3856" &SEC = "1" #&CDS_SEC = "1";
"A":   PN = "1"  !CDS_PN = "1";
"B":   PN = "2"  !CDS_PN = "2";
BODY = "Q_CAP","I50": #LOCATION = "PC1321" !CDS_LOCATION = "PC1321" &SEC = "1" #&CDS_SEC = "1";
"A":   PN = "1"  !CDS_PN = "1";
"B":   PN = "2"  !CDS_PN = "2";
BODY = "MP5016GQHLZ","I51": #LOCATION = "PU207" !CDS_LOCATION = "PU207" &SEC = "1" #&CDS_SEC = "1";
"DV_DT":   PN = "10"  !CDS_PN = "10";
"EN":   PN = "9"  !CDS_PN = "9";
"GATE":   PN = "8"  !CDS_PN = "8";
"GND":   PN = "3"  !CDS_PN = "3";
"ILIMIT":   PN = "4"  !CDS_PN = "4";
"MODE":   PN = "5"  !CDS_PN = "5";
"SOURCE":   PN = "6_7"  !CDS_PN = "6_7";
"VCC":   PN = "1_2"  !CDS_PN = "1_2";
BODY = "Q_CAP","I56": #LOCATION = "PC2173" !CDS_LOCATION = "PC2173" &SEC = "1" #&CDS_SEC = "1";
"A":   PN = "1"  !CDS_PN = "1";
"B":   PN = "2"  !CDS_PN = "2";
BODY = "Q_RES","I61": #LOCATION = "PR3847" !CDS_LOCATION = "PR3847" &SEC = "1" #&CDS_SEC = "1";
"A":   PN = "1"  !CDS_PN = "1";
"B":   PN = "2"  !CDS_PN = "2";
BODY = "Q_CAP","I62": #LOCATION = "PC2164" !CDS_LOCATION = "PC2164" &SEC = "1" #&CDS_SEC = "1";
"A":   PN = "1"  !CDS_PN = "1";
"B":   PN = "2"  !CDS_PN = "2";
BODY = "Q_CAP","I65": #LOCATION = "PC2166" !CDS_LOCATION = "PC2166" &SEC = "1" #&CDS_SEC = "1";
"A":   PN = "1"  !CDS_PN = "1";
"B":   PN = "2"  !CDS_PN = "2";
BODY = "Q_RES","I66": LOCATION = "R3630" #&CDS_LOCATION = "R3630" &SEC = "1" #&CDS_SEC = "1";
"A":   PN = "1"  !CDS_PN = "1";
"B":   PN = "2"  !CDS_PN = "2";
BODY = "Q_CAP","I68": #LOCATION = "PC2165" !CDS_LOCATION = "PC2165" &SEC = "1" #&CDS_SEC = "1";
"A":   PN = "1"  !CDS_PN = "1";
"B":   PN = "2"  !CDS_PN = "2";
BODY = "RS31312R","I70": #LOCATION = "PU206" !CDS_LOCATION = "PU206" &SEC = "1" #&CDS_SEC = "1";
"AVIN":   PN = "12"  !CDS_PN = "12";
"EN":   PN = "1"  !CDS_PN = "1";
"ENTM":   PN = "3"  !CDS_PN = "3";
"FLTB":   PN = "9"  !CDS_PN = "9";
"GND":   PN = "7"  !CDS_PN = "7";
"IMON":   PN = "8"  !CDS_PN = "8";
"ISET":   PN = "5"  !CDS_PN = "5";
"LOADEN":   PN = "2"  !CDS_PN = "2";
"OV":   PN = "11"  !CDS_PN = "11";
"PG":   PN = "10"  !CDS_PN = "10";
"SS":   PN = "6"  !CDS_PN = "6";
"TIMER":   PN = "4"  !CDS_PN = "4";
"VIN_21_22":   PN = "21_22"  !CDS_PN = "21_22";
"VIN_23":   PN = "23"  !CDS_PN = "23";
"VIN_24":   PN = "24"  !CDS_PN = "24";
"VIN_25":   PN = "25"  !CDS_PN = "25";
"VIN_26":   PN = "26"  !CDS_PN = "26";
"VOUT_13":   PN = "13"  !CDS_PN = "13";
"VOUT_14":   PN = "14"  !CDS_PN = "14";
"VOUT_15":   PN = "15"  !CDS_PN = "15";
"VOUT_16":   PN = "16"  !CDS_PN = "16";
"VOUT_17":   PN = "17"  !CDS_PN = "17";
"VOUT_18":   PN = "18"  !CDS_PN = "18";
"VOUT_19":   PN = "19"  !CDS_PN = "19";
"VOUT_20":   PN = "20"  !CDS_PN = "20";
BODY = "Q_RES","I72": #LOCATION = "PR3849" !CDS_LOCATION = "PR3849" &SEC = "1" #&CDS_SEC = "1";
"A":   PN = "1"  !CDS_PN = "1";
"B":   PN = "2"  !CDS_PN = "2";
BODY = "Q_CAP","I73": #LOCATION = "PC2167" !CDS_LOCATION = "PC2167" &SEC = "1" #&CDS_SEC = "1";
"A":   PN = "1"  !CDS_PN = "1";
"B":   PN = "2"  !CDS_PN = "2";
BODY = "Q_RES","I74": #LOCATION = "PR3851" !CDS_LOCATION = "PR3851" &SEC = "1" #&CDS_SEC = "1";
"A":   PN = "1"  !CDS_PN = "1";
"B":   PN = "2"  !CDS_PN = "2";
BODY = "Q_RES","I75": LOCATION = "R3848" #&CDS_LOCATION = "R3848" &SEC = "1" #&CDS_SEC = "1";
"A":   PN = "1"  !CDS_PN = "1";
"B":   PN = "2"  !CDS_PN = "2";
BODY = "Q_RES","I77": #LOCATION = "PR3850" !CDS_LOCATION = "PR3850" &SEC = "1" #&CDS_SEC = "1";
"A":   PN = "1"  !CDS_PN = "1";
"B":   PN = "2"  !CDS_PN = "2";
BODY = "Q_RES","I80": LOCATION = "R3874" #&CDS_LOCATION = "R3874" &SEC = "1" #&CDS_SEC = "1";
"A":   PN = "1"  !CDS_PN = "1";
"B":   PN = "2"  !CDS_PN = "2";
BODY = "Q_RES","I81": LOCATION = "R3873" #&CDS_LOCATION = "R3873" &SEC = "1" #&CDS_SEC = "1";
"A":   PN = "1"  !CDS_PN = "1";
"B":   PN = "2"  !CDS_PN = "2";
BODY = "Q_RES","I83": #LOCATION = "PR3854" !CDS_LOCATION = "PR3854" &SEC = "1" #&CDS_SEC = "1";
"A":   PN = "1"  !CDS_PN = "1";
"B":   PN = "2"  !CDS_PN = "2";
BODY = "Q_RES","I84": #LOCATION = "PR3853" !CDS_LOCATION = "PR3853" &SEC = "1" #&CDS_SEC = "1";
"A":   PN = "1"  !CDS_PN = "1";
"B":   PN = "2"  !CDS_PN = "2";
BODY = "Q_RES","I85": #LOCATION = "PR3852" !CDS_LOCATION = "PR3852" &SEC = "1" #&CDS_SEC = "1";
"A":   PN = "1"  !CDS_PN = "1";
"B":   PN = "2"  !CDS_PN = "2";
BODY = "Q_RES","I87": #LOCATION = "PR3857" !CDS_LOCATION = "PR3857" &SEC = "1" #&CDS_SEC = "1";
"A":   PN = "1"  !CDS_PN = "1";
"B":   PN = "2"  !CDS_PN = "2";
BODY = "Q_CAP","I91": #LOCATION = "PC2174" !CDS_LOCATION = "PC2174" &SEC = "1" #&CDS_SEC = "1";
"A":   PN = "1"  !CDS_PN = "1";
"B":   PN = "2"  !CDS_PN = "2";
BODY = "Q_CAP","I95": #LOCATION = "PC1320" !CDS_LOCATION = "PC1320" &SEC = "1" #&CDS_SEC = "1";
"A":   PN = "1"  !CDS_PN = "1";
"B":   PN = "2"  !CDS_PN = "2";
DRAWING = "@s9s_mb_2u_lib.s9s_mb_2u(sch_1):page194";
BODY = "Q_CAP","I2": LOCATION = "C2321" #&CDS_LOCATION = "C2321" &SEC = "1" #&CDS_SEC = "1";
"A":   PN = "1"  !CDS_PN = "1";
"B":   PN = "2"  !CDS_PN = "2";
BODY = "Q_RES","I4": LOCATION = "R4465" #&CDS_LOCATION = "R4465" &SEC = "1" #&CDS_SEC = "1";
"A":   PN = "1"  !CDS_PN = "1";
"B":   PN = "2"  !CDS_PN = "2";
BODY = "Q_RES","I8": LOCATION = "R4449" #&CDS_LOCATION = "R4449" &SEC = "1" #&CDS_SEC = "1";
"A":   PN = "1"  !CDS_PN = "1";
"B":   PN = "2"  !CDS_PN = "2";
BODY = "Q_RES","I9": LOCATION = "R4448" #&CDS_LOCATION = "R4448" &SEC = "1" #&CDS_SEC = "1";
"A":   PN = "1"  !CDS_PN = "1";
"B":   PN = "2"  !CDS_PN = "2";
BODY = "Q_RES","I13": LOCATION = "R4451" #&CDS_LOCATION = "R4451" &SEC = "1" #&CDS_SEC = "1";
"A":   PN = "1"  !CDS_PN = "1";
"B":   PN = "2"  !CDS_PN = "2";
BODY = "Q_CAP","I15": LOCATION = "C2317" #&CDS_LOCATION = "C2317" &SEC = "1" #&CDS_SEC = "1";
"A":   PN = "1"  !CDS_PN = "1";
"B":   PN = "2"  !CDS_PN = "2";
BODY = "Q_RES","I16": LOCATION = "R4455" #&CDS_LOCATION = "R4455" &SEC = "1" #&CDS_SEC = "1";
"A":   PN = "1"  !CDS_PN = "1";
"B":   PN = "2"  !CDS_PN = "2";
BODY = "Q_RES","I17": LOCATION = "R4454" #&CDS_LOCATION = "R4454" &SEC = "1" #&CDS_SEC = "1";
"A":   PN = "1"  !CDS_PN = "1";
"B":   PN = "2"  !CDS_PN = "2";
BODY = "Q_RES","I18": LOCATION = "R4460" #&CDS_LOCATION = "R4460" &SEC = "1" #&CDS_SEC = "1";
"A":   PN = "1"  !CDS_PN = "1";
"B":   PN = "2"  !CDS_PN = "2";
BODY = "Q_RES","I19": LOCATION = "R4461" #&CDS_LOCATION = "R4461" &SEC = "1" #&CDS_SEC = "1";
"A":   PN = "1"  !CDS_PN = "1";
"B":   PN = "2"  !CDS_PN = "2";
BODY = "TUSB211IRWBR","I20": LOCATION = "U312" #&CDS_LOCATION = "U312" &SEC = "1" #&CDS_SEC = "1";
"CD":   PN = "4"  !CDS_PN = "4";
"D1M":   PN = "1"  !CDS_PN = "1";
"D1P":   PN = "2"  !CDS_PN = "2";
"D2M":   PN = "8"  !CDS_PN = "8";
"D2P":   PN = "7"  !CDS_PN = "7";
"ENA_HS":   PN = "9"  !CDS_PN = "9";
"EQ":   PN = "6"  !CDS_PN = "6";
"GND":   PN = "10"  !CDS_PN = "10";
"RSTN":   PN = "5"  !CDS_PN = "5";
"TEST":   PN = "3"  !CDS_PN = "3";
"VCC":   PN = "12"  !CDS_PN = "12";
"VREG":   PN = "11"  !CDS_PN = "11";
BODY = "Q_RES","I22": LOCATION = "R4459" #&CDS_LOCATION = "R4459" &SEC = "1" #&CDS_SEC = "1";
"A":   PN = "1"  !CDS_PN = "1";
"B":   PN = "2"  !CDS_PN = "2";
BODY = "Q_RES","I23": LOCATION = "R4458" #&CDS_LOCATION = "R4458" &SEC = "1" #&CDS_SEC = "1";
"A":   PN = "1"  !CDS_PN = "1";
"B":   PN = "2"  !CDS_PN = "2";
BODY = "Q_RES","I24": LOCATION = "R4457" #&CDS_LOCATION = "R4457" &SEC = "1" #&CDS_SEC = "1";
"A":   PN = "1"  !CDS_PN = "1";
"B":   PN = "2"  !CDS_PN = "2";
BODY = "Q_RES","I25": LOCATION = "R4456" #&CDS_LOCATION = "R4456" &SEC = "1" #&CDS_SEC = "1";
"A":   PN = "1"  !CDS_PN = "1";
"B":   PN = "2"  !CDS_PN = "2";
BODY = "Q_RES","I26": LOCATION = "R4453" #&CDS_LOCATION = "R4453" &SEC = "1" #&CDS_SEC = "1";
"A":   PN = "1"  !CDS_PN = "1";
"B":   PN = "2"  !CDS_PN = "2";
BODY = "Q_RES","I27": LOCATION = "R4452" #&CDS_LOCATION = "R4452" &SEC = "1" #&CDS_SEC = "1";
"A":   PN = "1"  !CDS_PN = "1";
"B":   PN = "2"  !CDS_PN = "2";
BODY = "Q_RES","I37": LOCATION = "R4463" #&CDS_LOCATION = "R4463" &SEC = "1" #&CDS_SEC = "1";
"A":   PN = "1"  !CDS_PN = "1";
"B":   PN = "2"  !CDS_PN = "2";
BODY = "Q_RES","I38": LOCATION = "R4464" #&CDS_LOCATION = "R4464" &SEC = "1" #&CDS_SEC = "1";
"A":   PN = "1"  !CDS_PN = "1";
"B":   PN = "2"  !CDS_PN = "2";
BODY = "GL852GOHY60","I40": LOCATION = "U313" #&CDS_LOCATION = "U313" &SEC = "1" #&CDS_SEC = "1";
"AVDD<0>":   PN = "5"  !CDS_PN = "5";
"AVDD<1>":   PN = "9"  !CDS_PN = "9";
"AVDD<2>":   PN = "14"  !CDS_PN = "14";
"DM0":   PN = "1"  !CDS_PN = "1";
"DM1":   PN = "3"  !CDS_PN = "3";
"DM2":   PN = "6"  !CDS_PN = "6";
"DM3":   PN = "12"  !CDS_PN = "12";
"DM4":   PN = "15"  !CDS_PN = "15";
"DP0":   PN = "2"  !CDS_PN = "2";
"DP1":   PN = "4"  !CDS_PN = "4";
"DP2":   PN = "7"  !CDS_PN = "7";
"DP3":   PN = "13"  !CDS_PN = "13";
"DP4":   PN = "16"  !CDS_PN = "16";
"DVDD":   PN = "21"  !CDS_PN = "21";
"OVCUR1#||SMC":   PN = "25"  !CDS_PN = "25";
"OVCUR2#||SMD":   PN = "24"  !CDS_PN = "24";
"OVCUR3#":   PN = "20"  !CDS_PN = "20";
"OVCUR4#":   PN = "19"  !CDS_PN = "19";
"PGANG":   PN = "23"  !CDS_PN = "23";
"PSELF":   PN = "22"  !CDS_PN = "22";
"RESET#":   PN = "17"  !CDS_PN = "17";
"RREF":   PN = "8"  !CDS_PN = "8";
"SDA":   PN = "26"  !CDS_PN = "26";
"TEST||SCL":   PN = "18"  !CDS_PN = "18";
"TH":   PN = "TH"  !CDS_PN = "TH";
"V5":   PN = "27"  !CDS_PN = "27";
"V33":   PN = "28"  !CDS_PN = "28";
"X1":   PN = "10"  !CDS_PN = "10";
"X2":   PN = "11"  !CDS_PN = "11";
BODY = "Q_RES","I41": LOCATION = "R4450" #&CDS_LOCATION = "R4450" &SEC = "1" #&CDS_SEC = "1";
"A":   PN = "1"  !CDS_PN = "1";
"B":   PN = "2"  !CDS_PN = "2";
BODY = "Q_CAP","I43": LOCATION = "C2313" #&CDS_LOCATION = "C2313" &SEC = "1" #&CDS_SEC = "1";
"A":   PN = "1"  !CDS_PN = "1";
"B":   PN = "2"  !CDS_PN = "2";
BODY = "Q_CAP","I45": LOCATION = "C2314" #&CDS_LOCATION = "C2314" &SEC = "1" #&CDS_SEC = "1";
"A":   PN = "1"  !CDS_PN = "1";
"B":   PN = "2"  !CDS_PN = "2";
BODY = "Q_CAP","I46": LOCATION = "C2315" #&CDS_LOCATION = "C2315" &SEC = "1" #&CDS_SEC = "1";
"A":   PN = "1"  !CDS_PN = "1";
"B":   PN = "2"  !CDS_PN = "2";
BODY = "Q_CAP","I47": LOCATION = "C2316" #&CDS_LOCATION = "C2316" &SEC = "1" #&CDS_SEC = "1";
"A":   PN = "1"  !CDS_PN = "1";
"B":   PN = "2"  !CDS_PN = "2";
BODY = "Q_CAP","I49": LOCATION = "C2318" #&CDS_LOCATION = "C2318" &SEC = "1" #&CDS_SEC = "1";
"A":   PN = "1"  !CDS_PN = "1";
"B":   PN = "2"  !CDS_PN = "2";
BODY = "Q_RES","I50": LOCATION = "R4462" #&CDS_LOCATION = "R4462" &SEC = "1" #&CDS_SEC = "1";
"A":   PN = "1"  !CDS_PN = "1";
"B":   PN = "2"  !CDS_PN = "2";
BODY = "Q_CAP","I51": LOCATION = "C2319" #&CDS_LOCATION = "C2319" &SEC = "1" #&CDS_SEC = "1";
"A":   PN = "1"  !CDS_PN = "1";
"B":   PN = "2"  !CDS_PN = "2";
BODY = "Q_CAP","I52": LOCATION = "C2320" #&CDS_LOCATION = "C2320" &SEC = "1" #&CDS_SEC = "1";
"A":   PN = "1"  !CDS_PN = "1";
"B":   PN = "2"  !CDS_PN = "2";
BODY = "Q_CAP","I53": LOCATION = "C2322" #&CDS_LOCATION = "C2322" &SEC = "1" #&CDS_SEC = "1";
"A":   PN = "1"  !CDS_PN = "1";
"B":   PN = "2"  !CDS_PN = "2";
BODY = "Q_CAP","I55": LOCATION = "C2325" #&CDS_LOCATION = "C2325" &SEC = "1" #&CDS_SEC = "1";
"A":   PN = "1"  !CDS_PN = "1";
"B":   PN = "2"  !CDS_PN = "2";
BODY = "Q_CAP","I56": LOCATION = "C2323" #&CDS_LOCATION = "C2323" &SEC = "1" #&CDS_SEC = "1";
"A":   PN = "1"  !CDS_PN = "1";
"B":   PN = "2"  !CDS_PN = "2";
BODY = "Q_CAP","I58": LOCATION = "C2324" #&CDS_LOCATION = "C2324" &SEC = "1" #&CDS_SEC = "1";
"A":   PN = "1"  !CDS_PN = "1";
"B":   PN = "2"  !CDS_PN = "2";
BODY = "Q_RES","I60": LOCATION = "R4468" #&CDS_LOCATION = "R4468" &SEC = "1" #&CDS_SEC = "1";
"A":   PN = "1"  !CDS_PN = "1";
"B":   PN = "2"  !CDS_PN = "2";
BODY = "Q_RES","I61": LOCATION = "R4467" #&CDS_LOCATION = "R4467" &SEC = "1" #&CDS_SEC = "1";
"A":   PN = "1"  !CDS_PN = "1";
"B":   PN = "2"  !CDS_PN = "2";
BODY = "Q_RES","I72": LOCATION = "R4474" #&CDS_LOCATION = "R4474" &SEC = "1" #&CDS_SEC = "1";
"A":   PN = "1"  !CDS_PN = "1";
"B":   PN = "2"  !CDS_PN = "2";
BODY = "Q_RES","I73": LOCATION = "R4473" #&CDS_LOCATION = "R4473" &SEC = "1" #&CDS_SEC = "1";
"A":   PN = "1"  !CDS_PN = "1";
"B":   PN = "2"  !CDS_PN = "2";
BODY = "Q_RES","I75": LOCATION = "R4466" #&CDS_LOCATION = "R4466" &SEC = "1" #&CDS_SEC = "1";
"A":   PN = "1"  !CDS_PN = "1";
"B":   PN = "2"  !CDS_PN = "2";
BODY = "Q_RES","I77": LOCATION = "R4471" #&CDS_LOCATION = "R4471" &SEC = "1" #&CDS_SEC = "1";
"A":   PN = "1"  !CDS_PN = "1";
"B":   PN = "2"  !CDS_PN = "2";
BODY = "Q_RES","I78": LOCATION = "R4472" #&CDS_LOCATION = "R4472" &SEC = "1" #&CDS_SEC = "1";
"A":   PN = "1"  !CDS_PN = "1";
"B":   PN = "2"  !CDS_PN = "2";
BODY = "Q_CAP","I81": LOCATION = "C2326" #&CDS_LOCATION = "C2326" &SEC = "1" #&CDS_SEC = "1";
"A":   PN = "1"  !CDS_PN = "1";
"B":   PN = "2"  !CDS_PN = "2";
BODY = "Q_XTAL_4P_13BI_24GND","I83": LOCATION = "Y9" #&CDS_LOCATION = "Y9" &SEC = "1" #&CDS_SEC = "1";
"G1":   PN = "2"  !CDS_PN = "2";
"G2":   PN = "4"  !CDS_PN = "4";
"X1":   PN = "1"  !CDS_PN = "1";
"X2":   PN = "3"  !CDS_PN = "3";
BODY = "Q_CAP","I85": LOCATION = "C2327" #&CDS_LOCATION = "C2327" &SEC = "1" #&CDS_SEC = "1";
"A":   PN = "1"  !CDS_PN = "1";
"B":   PN = "2"  !CDS_PN = "2";
BODY = "Q_RES","I90": LOCATION = "R4486" #&CDS_LOCATION = "R4486" &SEC = "1" #&CDS_SEC = "1";
"A":   PN = "1"  !CDS_PN = "1";
"B":   PN = "2"  !CDS_PN = "2";
BODY = "Q_RES","I88": LOCATION = "R4487" #&CDS_LOCATION = "R4487" &SEC = "1" #&CDS_SEC = "1";
"A":   PN = "1"  !CDS_PN = "1";
"B":   PN = "2"  !CDS_PN = "2";
DRAWING = "@s9s_mb_2u_lib.s9s_mb_2u(sch_1):page303";
BODY = "Q_RES","I4": #LOCATION = "R3907" !CDS_LOCATION = "R3907" &SEC = "1" #&CDS_SEC = "1";
"A":   PN = "1"  !CDS_PN = "1";
"B":   PN = "2"  !CDS_PN = "2";
BODY = "MOSFET_NCH_GDS_ESD_PROTECTED","I5": LOCATION = "U290" #&CDS_LOCATION = "U290" &SEC = "1" #&CDS_SEC = "1";
"D":   PN = "D"  !CDS_PN = "D";
"G":   PN = "G"  !CDS_PN = "G";
"S":   PN = "S"  !CDS_PN = "S";
BODY = "Q_RES","I10": #LOCATION = "R3923" !CDS_LOCATION = "R3923" &SEC = "1" #&CDS_SEC = "1";
"A":   PN = "1"  !CDS_PN = "1";
"B":   PN = "2"  !CDS_PN = "2";
BODY = "Q_RES","I52": #LOCATION = "PR3926" !CDS_LOCATION = "PR3926" &SEC = "1" #&CDS_SEC = "1";
"A":   PN = "1"  !CDS_PN = "1";
"B":   PN = "2"  !CDS_PN = "2";
BODY = "MP5990GMA1111Z","I56": #LOCATION = "PU289" !CDS_LOCATION = "PU289" &SEC = "1" #&CDS_SEC = "1";
"ADDR":   PN = "23"  !CDS_PN = "23";
"ALT#":   PN = "10"  !CDS_PN = "10";
"CS":   PN = "20"  !CDS_PN = "20";
"D_OC":   PN = "37"  !CDS_PN = "37";
"EN":   PN = "26"  !CDS_PN = "26";
"FLT_TYPE":   PN = "40"  !CDS_PN = "40";
"GND1":   PN = "18"  !CDS_PN = "18";
"GND2":   PN = "44"  !CDS_PN = "44";
"GOK":   PN = "39"  !CDS_PN = "39";
"IMON":   PN = "21"  !CDS_PN = "21";
"MODE":   PN = "41"  !CDS_PN = "41";
"OCREF":   PN = "22"  !CDS_PN = "22";
"ON":   PN = "38"  !CDS_PN = "38";
"PG||OCW#":   PN = "13"  !CDS_PN = "13";
"SCL":   PN = "11"  !CDS_PN = "11";
"SCREF_OCWREF":   PN = "25"  !CDS_PN = "25";
"SDA":   PN = "12"  !CDS_PN = "12";
"SS":   PN = "16"  !CDS_PN = "16";
"VDD18":   PN = "19"  !CDS_PN = "19";
"VDD33_1":   PN = "17"  !CDS_PN = "17";
"VDD33_2":   PN = "45"  !CDS_PN = "45";
"VIN1":   PN = "1"  !CDS_PN = "1";
"VIN2":   PN = "2"  !CDS_PN = "2";
"VIN3":   PN = "3"  !CDS_PN = "3";
"VIN4":   PN = "4"  !CDS_PN = "4";
"VIN5":   PN = "5"  !CDS_PN = "5";
"VIN6":   PN = "6"  !CDS_PN = "6";
"VIN7":   PN = "7"  !CDS_PN = "7";
"VIN8":   PN = "8"  !CDS_PN = "8";
"VIN9":   PN = "42"  !CDS_PN = "42";
"VIN10":   PN = "43"  !CDS_PN = "43";
"VIN_UVW#":   PN = "14"  !CDS_PN = "14";
"VINSEN":   PN = "9"  !CDS_PN = "9";
"VOSEN":   PN = "24"  !CDS_PN = "24";
"VOUT1":   PN = "27"  !CDS_PN = "27";
"VOUT2":   PN = "28"  !CDS_PN = "28";
"VOUT3":   PN = "29"  !CDS_PN = "29";
"VOUT4":   PN = "30"  !CDS_PN = "30";
"VOUT5":   PN = "31"  !CDS_PN = "31";
"VOUT6":   PN = "32"  !CDS_PN = "32";
"VOUT7":   PN = "33"  !CDS_PN = "33";
"VOUT8":   PN = "34"  !CDS_PN = "34";
"VOUT9":   PN = "35"  !CDS_PN = "35";
"VOUT10":   PN = "36"  !CDS_PN = "36";
"VTEMP":   PN = "15"  !CDS_PN = "15";
BODY = "Q_RES","I59": #LOCATION = "PR3932" !CDS_LOCATION = "PR3932" &SEC = "1" #&CDS_SEC = "1";
"A":   PN = "1"  !CDS_PN = "1";
"B":   PN = "2"  !CDS_PN = "2";
BODY = "Q_RES","I85": #LOCATION = "R3936" !CDS_LOCATION = "R3936" &SEC = "1" #&CDS_SEC = "1";
"A":   PN = "1"  !CDS_PN = "1";
"B":   PN = "2"  !CDS_PN = "2";
BODY = "Q_RES","I86": #LOCATION = "PR3931" !CDS_LOCATION = "PR3931" &SEC = "1" #&CDS_SEC = "1";
"A":   PN = "1"  !CDS_PN = "1";
"B":   PN = "2"  !CDS_PN = "2";
BODY = "Q_RES","I24": #LOCATION = "PR2149" !CDS_LOCATION = "PR2149" &SEC = "1" #&CDS_SEC = "1";
"A":   PN = "1"  !CDS_PN = "1";
"B":   PN = "2"  !CDS_PN = "2";
BODY = "Q_RES","I43": LOCATION = "PR2106" #&CDS_LOCATION = "PR2106" &SEC = "1" #&CDS_SEC = "1";
"A":   PN = "1"  !CDS_PN = "1";
"B":   PN = "2"  !CDS_PN = "2";
BODY = "Q_CAP","I51": #LOCATION = "PC2188" !CDS_LOCATION = "PC2188" &SEC = "1" #&CDS_SEC = "1";
"A":   PN = "1"  !CDS_PN = "1";
"B":   PN = "2"  !CDS_PN = "2";
BODY = "Q_CAP","I75": #LOCATION = "PC2190" !CDS_LOCATION = "PC2190" &SEC = "1" #&CDS_SEC = "1";
"A":   PN = "1"  !CDS_PN = "1";
"B":   PN = "2"  !CDS_PN = "2";
BODY = "Q_RES","I81": #LOCATION = "R2588" !CDS_LOCATION = "R2588" &SEC = "1" #&CDS_SEC = "1";
"A":   PN = "1"  !CDS_PN = "1";
"B":   PN = "2"  !CDS_PN = "2";
BODY = "Q_RES","I7": #LOCATION = "R2585" !CDS_LOCATION = "R2585" &SEC = "1" #&CDS_SEC = "1";
"A":   PN = "1"  !CDS_PN = "1";
"B":   PN = "2"  !CDS_PN = "2";
BODY = "Q_RES","I17": LOCATION = "R3924" #&CDS_LOCATION = "R3924" &SEC = "1" #&CDS_SEC = "1";
"A":   PN = "1"  !CDS_PN = "1";
"B":   PN = "2"  !CDS_PN = "2";
BODY = "Q_RES","I33": LOCATION = "R3925" #&CDS_LOCATION = "R3925" &SEC = "1" #&CDS_SEC = "1";
"A":   PN = "1"  !CDS_PN = "1";
"B":   PN = "2"  !CDS_PN = "2";
BODY = "Q_RES","I38": #LOCATION = "R3909" !CDS_LOCATION = "R3909" &SEC = "1" #&CDS_SEC = "1";
"A":   PN = "1"  !CDS_PN = "1";
"B":   PN = "2"  !CDS_PN = "2";
BODY = "Q_RES","I40": #LOCATION = "PR3927" !CDS_LOCATION = "PR3927" &SEC = "1" #&CDS_SEC = "1";
"A":   PN = "1"  !CDS_PN = "1";
"B":   PN = "2"  !CDS_PN = "2";
BODY = "Q_RES","I41": #LOCATION = "PR3928" !CDS_LOCATION = "PR3928" &SEC = "1" #&CDS_SEC = "1";
"A":   PN = "1"  !CDS_PN = "1";
"B":   PN = "2"  !CDS_PN = "2";
BODY = "Q_CAP","I45": #LOCATION = "PC2189" !CDS_LOCATION = "PC2189" &SEC = "1" #&CDS_SEC = "1";
"A":   PN = "1"  !CDS_PN = "1";
"B":   PN = "2"  !CDS_PN = "2";
BODY = "Q_RES","I61": #LOCATION = "R1117" !CDS_LOCATION = "R1117" &SEC = "1" #&CDS_SEC = "1";
"A":   PN = "1"  !CDS_PN = "1";
"B":   PN = "2"  !CDS_PN = "2";
BODY = "Q_CAP","I69": #LOCATION = "PC2191" !CDS_LOCATION = "PC2191" &SEC = "1" #&CDS_SEC = "1";
"A":   PN = "1"  !CDS_PN = "1";
"B":   PN = "2"  !CDS_PN = "2";
BODY = "Q_CAP","I77": #LOCATION = "PC2192" !CDS_LOCATION = "PC2192" &SEC = "1" #&CDS_SEC = "1";
"A":   PN = "1"  !CDS_PN = "1";
"B":   PN = "2"  !CDS_PN = "2";
BODY = "Q_CAP","I3": #LOCATION = "C1797" !CDS_LOCATION = "C1797" &SEC = "1" #&CDS_SEC = "1";
"A":   PN = "1"  !CDS_PN = "1";
"B":   PN = "2"  !CDS_PN = "2";
BODY = "CONN3_210HP1030BR1","I12": #LOCATION = "JP4003" !CDS_LOCATION = "JP4003" &SEC = "1" #&CDS_SEC = "1";
"1":   PN = "1"  !CDS_PN = "1";
"2":   PN = "2"  !CDS_PN = "2";
"3":   PN = "3"  !CDS_PN = "3";
BODY = "Q_CAP","I14": #LOCATION = "PC2186" !CDS_LOCATION = "PC2186" &SEC = "1" #&CDS_SEC = "1";
"A":   PN = "1"  !CDS_PN = "1";
"B":   PN = "2"  !CDS_PN = "2";
BODY = "Q_CAP","I23": #LOCATION = "PC2187" !CDS_LOCATION = "PC2187" &SEC = "1" #&CDS_SEC = "1";
"A":   PN = "1"  !CDS_PN = "1";
"B":   PN = "2"  !CDS_PN = "2";
BODY = "Q_RES","I26": #LOCATION = "R4901" !CDS_LOCATION = "R4901" &SEC = "1" #&CDS_SEC = "1";
"A":   PN = "1"  !CDS_PN = "1";
"B":   PN = "2"  !CDS_PN = "2";
BODY = "Q_CAP","I29": #LOCATION = "C2179" !CDS_LOCATION = "C2179" &SEC = "1" #&CDS_SEC = "1";
"A":   PN = "1"  !CDS_PN = "1";
"B":   PN = "2"  !CDS_PN = "2";
BODY = "Q_RES","I32": #LOCATION = "PR3930" !CDS_LOCATION = "PR3930" &SEC = "1" #&CDS_SEC = "1";
"A":   PN = "1"  !CDS_PN = "1";
"B":   PN = "2"  !CDS_PN = "2";
BODY = "Q_CAP","I35": LOCATION = "PC2103" #&CDS_LOCATION = "PC2103" &SEC = "1" #&CDS_SEC = "1";
"A":   PN = "1"  !CDS_PN = "1";
"B":   PN = "2"  !CDS_PN = "2";
BODY = "Q_RES","I37": #LOCATION = "R1714" !CDS_LOCATION = "R1714" &SEC = "1" #&CDS_SEC = "1";
"A":   PN = "1"  !CDS_PN = "1";
"B":   PN = "2"  !CDS_PN = "2";
BODY = "Q_RES","I42": #LOCATION = "PR3929" !CDS_LOCATION = "PR3929" &SEC = "1" #&CDS_SEC = "1";
"A":   PN = "1"  !CDS_PN = "1";
"B":   PN = "2"  !CDS_PN = "2";
BODY = "Q_RES","I44": #LOCATION = "R2586" !CDS_LOCATION = "R2586" &SEC = "1" #&CDS_SEC = "1";
"A":   PN = "1"  !CDS_PN = "1";
"B":   PN = "2"  !CDS_PN = "2";
BODY = "Q_RES","I54": #LOCATION = "PR3002" !CDS_LOCATION = "PR3002" &SEC = "1" #&CDS_SEC = "1";
"A":   PN = "1"  !CDS_PN = "1";
"B":   PN = "2"  !CDS_PN = "2";
BODY = "Q_RES","I58": LOCATION = "PR1131" #&CDS_LOCATION = "PR1131" &SEC = "1" #&CDS_SEC = "1";
"A":   PN = "1"  !CDS_PN = "1";
"B":   PN = "2"  !CDS_PN = "2";
BODY = "Q_RES","I62": #LOCATION = "R3933" !CDS_LOCATION = "R3933" &SEC = "1" #&CDS_SEC = "1";
"A":   PN = "1"  !CDS_PN = "1";
"B":   PN = "2"  !CDS_PN = "2";
BODY = "Q_RES","I79": #LOCATION = "PR3935" !CDS_LOCATION = "PR3935" &SEC = "1" #&CDS_SEC = "1";
"A":   PN = "1"  !CDS_PN = "1";
"B":   PN = "2"  !CDS_PN = "2";
BODY = "Q_RES","I82": #LOCATION = "R3934" !CDS_LOCATION = "R3934" &SEC = "1" #&CDS_SEC = "1";
"A":   PN = "1"  !CDS_PN = "1";
"B":   PN = "2"  !CDS_PN = "2";
BODY = "Q_RES","I84": #LOCATION = "PR3937" !CDS_LOCATION = "PR3937" &SEC = "1" #&CDS_SEC = "1";
"A":   PN = "1"  !CDS_PN = "1";
"B":   PN = "2"  !CDS_PN = "2";
BODY = "Q_CAP","I89": #LOCATION = "PC2193" !CDS_LOCATION = "PC2193" &SEC = "1" #&CDS_SEC = "1";
"A":   PN = "1"  !CDS_PN = "1";
"B":   PN = "2"  !CDS_PN = "2";
BODY = "Q_RES","I91": LOCATION = "PR1133" #&CDS_LOCATION = "PR1133" &SEC = "1" #&CDS_SEC = "1";
"A":   PN = "1"  !CDS_PN = "1";
"B":   PN = "2"  !CDS_PN = "2";
BODY = "Q_RES","I93": #LOCATION = "R2587" !CDS_LOCATION = "R2587" &SEC = "1" #&CDS_SEC = "1";
"A":   PN = "1"  !CDS_PN = "1";
"B":   PN = "2"  !CDS_PN = "2";
DRAWING = "@s9s_mb_2u_lib.s9s_mb_2u(sch_1):page225";
BODY = "Q_CAP","I5": LOCATION = "C2337" #&CDS_LOCATION = "C2337" &SEC = "1" #&CDS_SEC = "1";
"A":   PN = "1"  !CDS_PN = "1";
"B":   PN = "2"  !CDS_PN = "2";
BODY = "Q_CAP","I8": LOCATION = "C2338" #&CDS_LOCATION = "C2338" &SEC = "1" #&CDS_SEC = "1";
"A":   PN = "1"  !CDS_PN = "1";
"B":   PN = "2"  !CDS_PN = "2";
BODY = "Q_RES","I11": LOCATION = "R4498" #&CDS_LOCATION = "R4498" &SEC = "1" #&CDS_SEC = "1";
"A":   PN = "1"  !CDS_PN = "1";
"B":   PN = "2"  !CDS_PN = "2";
BODY = "Q_RES","I12": LOCATION = "R4499" #&CDS_LOCATION = "R4499" &SEC = "1" #&CDS_SEC = "1";
"A":   PN = "1"  !CDS_PN = "1";
"B":   PN = "2"  !CDS_PN = "2";
BODY = "PCA9617ADP","I17": LOCATION = "U315" #&CDS_LOCATION = "U315" &SEC = "1" #&CDS_SEC = "1";
"EN":   PN = "5"  !CDS_PN = "5";
"GND":   PN = "4"  !CDS_PN = "4";
"SCLA":   PN = "2"  !CDS_PN = "2";
"SCLB":   PN = "7"  !CDS_PN = "7";
"SDAA":   PN = "3"  !CDS_PN = "3";
"SDAB":   PN = "6"  !CDS_PN = "6";
"VCCA":   PN = "1"  !CDS_PN = "1";
"VCCB":   PN = "8"  !CDS_PN = "8";
BODY = "Q_RES","I24": LOCATION = "R4480" #&CDS_LOCATION = "R4480" &SEC = "1" #&CDS_SEC = "1";
"A":   PN = "1"  !CDS_PN = "1";
"B":   PN = "2"  !CDS_PN = "2";
BODY = "Q_RES","I25": LOCATION = "R4481" #&CDS_LOCATION = "R4481" &SEC = "1" #&CDS_SEC = "1";
"A":   PN = "1"  !CDS_PN = "1";
"B":   PN = "2"  !CDS_PN = "2";
BODY = "Q_RES","I26": LOCATION = "R4497" #&CDS_LOCATION = "R4497" &SEC = "1" #&CDS_SEC = "1";
"A":   PN = "1"  !CDS_PN = "1";
"B":   PN = "2"  !CDS_PN = "2";
BODY = "Q_RES","I27": LOCATION = "R4496" #&CDS_LOCATION = "R4496" &SEC = "1" #&CDS_SEC = "1";
"A":   PN = "1"  !CDS_PN = "1";
"B":   PN = "2"  !CDS_PN = "2";
BODY = "Q_RES","I32": LOCATION = "R4500" #&CDS_LOCATION = "R4500" &SEC = "1" #&CDS_SEC = "1";
"A":   PN = "1"  !CDS_PN = "1";
"B":   PN = "2"  !CDS_PN = "2";
BODY = "Q_RES","I33": LOCATION = "R4540" #&CDS_LOCATION = "R4540" &SEC = "1" #&CDS_SEC = "1";
"A":   PN = "1"  !CDS_PN = "1";
"B":   PN = "2"  !CDS_PN = "2";
BODY = "Q_RES","I34": LOCATION = "R4541" #&CDS_LOCATION = "R4541" &SEC = "1" #&CDS_SEC = "1";
"A":   PN = "1"  !CDS_PN = "1";
"B":   PN = "2"  !CDS_PN = "2";
DRAWING = "@s9s_mb_2u_lib.s9s_mb_2u(sch_1):page184";
BODY = "Q_RES","I1": LOCATION = "R4581" #&CDS_LOCATION = "R4581" &SEC = "1" #&CDS_SEC = "1";
"A":   PN = "1"  !CDS_PN = "1";
"B":   PN = "2"  !CDS_PN = "2";
BODY = "Q_RES","I18": LOCATION = "R4583" #&CDS_LOCATION = "R4583" &SEC = "1" #&CDS_SEC = "1";
"A":   PN = "1"  !CDS_PN = "1";
"B":   PN = "2"  !CDS_PN = "2";
BODY = "Q_RES","I20": LOCATION = "R4585" #&CDS_LOCATION = "R4585" &SEC = "1" #&CDS_SEC = "1";
"A":   PN = "1"  !CDS_PN = "1";
"B":   PN = "2"  !CDS_PN = "2";
BODY = "Q_RES","I22": LOCATION = "R4597" #&CDS_LOCATION = "R4597" &SEC = "1" #&CDS_SEC = "1";
"A":   PN = "1"  !CDS_PN = "1";
"B":   PN = "2"  !CDS_PN = "2";
BODY = "Q_RES","I30": LOCATION = "R2243" #&CDS_LOCATION = "R2243" &SEC = "1" #&CDS_SEC = "1";
"A":   PN = "1"  !CDS_PN = "1";
"B":   PN = "2"  !CDS_PN = "2";
BODY = "Q_RES","I50": LOCATION = "R2242" #&CDS_LOCATION = "R2242" &SEC = "1" #&CDS_SEC = "1";
"A":   PN = "1"  !CDS_PN = "1";
"B":   PN = "2"  !CDS_PN = "2";
BODY = "Q_RES","I58": LOCATION = "R4588" #&CDS_LOCATION = "R4588" &SEC = "1" #&CDS_SEC = "1";
"A":   PN = "1"  !CDS_PN = "1";
"B":   PN = "2"  !CDS_PN = "2";
BODY = "Q_RES","I59": LOCATION = "R4590" #&CDS_LOCATION = "R4590" &SEC = "1" #&CDS_SEC = "1";
"A":   PN = "1"  !CDS_PN = "1";
"B":   PN = "2"  !CDS_PN = "2";
BODY = "Q_RES","I62": LOCATION = "R4586" #&CDS_LOCATION = "R4586" &SEC = "1" #&CDS_SEC = "1";
"A":   PN = "1"  !CDS_PN = "1";
"B":   PN = "2"  !CDS_PN = "2";
BODY = "Q_RES","I4": LOCATION = "R4592" #&CDS_LOCATION = "R4592" &SEC = "1" #&CDS_SEC = "1";
"A":   PN = "1"  !CDS_PN = "1";
"B":   PN = "2"  !CDS_PN = "2";
BODY = "Q_RES","I5": LOCATION = "R4580" #&CDS_LOCATION = "R4580" &SEC = "1" #&CDS_SEC = "1";
"A":   PN = "1"  !CDS_PN = "1";
"B":   PN = "2"  !CDS_PN = "2";
BODY = "Q_RES","I6": LOCATION = "R4591" #&CDS_LOCATION = "R4591" &SEC = "1" #&CDS_SEC = "1";
"A":   PN = "1"  !CDS_PN = "1";
"B":   PN = "2"  !CDS_PN = "2";
BODY = "Q_RES","I9": LOCATION = "R2235" #&CDS_LOCATION = "R2235" &SEC = "1" #&CDS_SEC = "1";
"A":   PN = "1"  !CDS_PN = "1";
"B":   PN = "2"  !CDS_PN = "2";
BODY = "Q_RES","I11": LOCATION = "R2977" #&CDS_LOCATION = "R2977" &SEC = "1" #&CDS_SEC = "1";
"A":   PN = "1"  !CDS_PN = "1";
"B":   PN = "2"  !CDS_PN = "2";
BODY = "Q_RES","I12": LOCATION = "R2234" #&CDS_LOCATION = "R2234" &SEC = "1" #&CDS_SEC = "1";
"A":   PN = "1"  !CDS_PN = "1";
"B":   PN = "2"  !CDS_PN = "2";
BODY = "Q_RES","I13": LOCATION = "R2976" #&CDS_LOCATION = "R2976" &SEC = "1" #&CDS_SEC = "1";
"A":   PN = "1"  !CDS_PN = "1";
"B":   PN = "2"  !CDS_PN = "2";
BODY = "Q_RES","I16": LOCATION = "R4598" #&CDS_LOCATION = "R4598" &SEC = "1" #&CDS_SEC = "1";
"A":   PN = "1"  !CDS_PN = "1";
"B":   PN = "2"  !CDS_PN = "2";
BODY = "Q_RES","I23": LOCATION = "R4582" #&CDS_LOCATION = "R4582" &SEC = "1" #&CDS_SEC = "1";
"A":   PN = "1"  !CDS_PN = "1";
"B":   PN = "2"  !CDS_PN = "2";
BODY = "Q_RES","I24": LOCATION = "R4584" #&CDS_LOCATION = "R4584" &SEC = "1" #&CDS_SEC = "1";
"A":   PN = "1"  !CDS_PN = "1";
"B":   PN = "2"  !CDS_PN = "2";
BODY = "Q_RES","I26": LOCATION = "R2980" #&CDS_LOCATION = "R2980" &SEC = "1" #&CDS_SEC = "1";
"A":   PN = "1"  !CDS_PN = "1";
"B":   PN = "2"  !CDS_PN = "2";
BODY = "Q_RES","I28": LOCATION = "R2241" #&CDS_LOCATION = "R2241" &SEC = "1" #&CDS_SEC = "1";
"A":   PN = "1"  !CDS_PN = "1";
"B":   PN = "2"  !CDS_PN = "2";
BODY = "Q_RES","I48": LOCATION = "R2979" #&CDS_LOCATION = "R2979" &SEC = "1" #&CDS_SEC = "1";
"A":   PN = "1"  !CDS_PN = "1";
"B":   PN = "2"  !CDS_PN = "2";
BODY = "Q_RES","I49": LOCATION = "R2240" #&CDS_LOCATION = "R2240" &SEC = "1" #&CDS_SEC = "1";
"A":   PN = "1"  !CDS_PN = "1";
"B":   PN = "2"  !CDS_PN = "2";
BODY = "Q_RES","I61": LOCATION = "R4596" #&CDS_LOCATION = "R4596" &SEC = "1" #&CDS_SEC = "1";
"A":   PN = "1"  !CDS_PN = "1";
"B":   PN = "2"  !CDS_PN = "2";
BODY = "Q_RES","I63": LOCATION = "R4589" #&CDS_LOCATION = "R4589" &SEC = "1" #&CDS_SEC = "1";
"A":   PN = "1"  !CDS_PN = "1";
"B":   PN = "2"  !CDS_PN = "2";
BODY = "Q_RES","I67": LOCATION = "R4579" #&CDS_LOCATION = "R4579" &SEC = "1" #&CDS_SEC = "1";
"A":   PN = "1"  !CDS_PN = "1";
"B":   PN = "2"  !CDS_PN = "2";
BODY = "Q_RES","I69": LOCATION = "R2973" #&CDS_LOCATION = "R2973" &SEC = "1" #&CDS_SEC = "1";
"A":   PN = "1"  !CDS_PN = "1";
"B":   PN = "2"  !CDS_PN = "2";
BODY = "Q_RES","I70": LOCATION = "R2975" #&CDS_LOCATION = "R2975" &SEC = "1" #&CDS_SEC = "1";
"A":   PN = "1"  !CDS_PN = "1";
"B":   PN = "2"  !CDS_PN = "2";
BODY = "Q_RES","I71": LOCATION = "R2972" #&CDS_LOCATION = "R2972" &SEC = "1" #&CDS_SEC = "1";
"A":   PN = "1"  !CDS_PN = "1";
"B":   PN = "2"  !CDS_PN = "2";
BODY = "Q_RES","I72": LOCATION = "R2974" #&CDS_LOCATION = "R2974" &SEC = "1" #&CDS_SEC = "1";
"A":   PN = "1"  !CDS_PN = "1";
"B":   PN = "2"  !CDS_PN = "2";
BODY = "Q_RES","I74": LOCATION = "R2978" #&CDS_LOCATION = "R2978" &SEC = "1" #&CDS_SEC = "1";
"A":   PN = "1"  !CDS_PN = "1";
"B":   PN = "2"  !CDS_PN = "2";
BODY = "Q_RES","I75": LOCATION = "R2232" #&CDS_LOCATION = "R2232" &SEC = "1" #&CDS_SEC = "1";
"A":   PN = "1"  !CDS_PN = "1";
"B":   PN = "2"  !CDS_PN = "2";
DRAWING = "@s9s_mb_2u_lib.s9s_mb_2u(sch_1):page235";
BODY = "Q_RES","I16": LOCATION = "R4628" #&CDS_LOCATION = "R4628" &SEC = "1" #&CDS_SEC = "1";
"A":   PN = "1"  !CDS_PN = "1";
"B":   PN = "2"  !CDS_PN = "2";
BODY = "Q_RES","I25": LOCATION = "R4631" #&CDS_LOCATION = "R4631" &SEC = "1" #&CDS_SEC = "1";
"A":   PN = "1"  !CDS_PN = "1";
"B":   PN = "2"  !CDS_PN = "2";
BODY = "Q_RES","I27": LOCATION = "R4630" #&CDS_LOCATION = "R4630" &SEC = "1" #&CDS_SEC = "1";
"A":   PN = "1"  !CDS_PN = "1";
"B":   PN = "2"  !CDS_PN = "2";
BODY = "Q_RES","I3": LOCATION = "R4635" #&CDS_LOCATION = "R4635" &SEC = "1" #&CDS_SEC = "1";
"A":   PN = "1"  !CDS_PN = "1";
"B":   PN = "2"  !CDS_PN = "2";
BODY = "Q_RES","I4": LOCATION = "R4634" #&CDS_LOCATION = "R4634" &SEC = "1" #&CDS_SEC = "1";
"A":   PN = "1"  !CDS_PN = "1";
"B":   PN = "2"  !CDS_PN = "2";
BODY = "Q_RES","I11": LOCATION = "R4623" #&CDS_LOCATION = "R4623" &SEC = "1" #&CDS_SEC = "1";
"A":   PN = "1"  !CDS_PN = "1";
"B":   PN = "2"  !CDS_PN = "2";
BODY = "CONN3_210HP1030BR1","I13": LOCATION = "JP16" #&CDS_LOCATION = "JP16" &SEC = "1" #&CDS_SEC = "1";
"1":   PN = "1"  !CDS_PN = "1";
"2":   PN = "2"  !CDS_PN = "2";
"3":   PN = "3"  !CDS_PN = "3";
BODY = "Q_RES","I14": LOCATION = "R4624" #&CDS_LOCATION = "R4624" &SEC = "1" #&CDS_SEC = "1";
"A":   PN = "1"  !CDS_PN = "1";
"B":   PN = "2"  !CDS_PN = "2";
BODY = "Q_RES","I15": LOCATION = "R4629" #&CDS_LOCATION = "R4629" &SEC = "1" #&CDS_SEC = "1";
"A":   PN = "1"  !CDS_PN = "1";
"B":   PN = "2"  !CDS_PN = "2";
BODY = "Q_RES","I17": LOCATION = "R4627" #&CDS_LOCATION = "R4627" &SEC = "1" #&CDS_SEC = "1";
"A":   PN = "1"  !CDS_PN = "1";
"B":   PN = "2"  !CDS_PN = "2";
BODY = "Q_RES","I18": LOCATION = "R4626" #&CDS_LOCATION = "R4626" &SEC = "1" #&CDS_SEC = "1";
"A":   PN = "1"  !CDS_PN = "1";
"B":   PN = "2"  !CDS_PN = "2";
BODY = "74CBTLV3126PW","I19": LOCATION = "U327" #&CDS_LOCATION = "U327" &SEC = "1" #&CDS_SEC = "1";
"1A":   PN = "2"  !CDS_PN = "2";
"1B":   PN = "3"  !CDS_PN = "3";
"1OE":   PN = "1"  !CDS_PN = "1";
"2A":   PN = "5"  !CDS_PN = "5";
"2B":   PN = "6"  !CDS_PN = "6";
"2OE":   PN = "4"  !CDS_PN = "4";
"3A":   PN = "9"  !CDS_PN = "9";
"3B":   PN = "8"  !CDS_PN = "8";
"3OE":   PN = "10"  !CDS_PN = "10";
"4A":   PN = "12"  !CDS_PN = "12";
"4B":   PN = "11"  !CDS_PN = "11";
"4OE":   PN = "13"  !CDS_PN = "13";
"GND":   PN = "7"  !CDS_PN = "7";
"VCC":   PN = "14"  !CDS_PN = "14";
BODY = "Q_CAP","I23": LOCATION = "C2348" #&CDS_LOCATION = "C2348" &SEC = "1" #&CDS_SEC = "1";
"A":   PN = "1"  !CDS_PN = "1";
"B":   PN = "2"  !CDS_PN = "2";
BODY = "Q_RES","I24": LOCATION = "R4633" #&CDS_LOCATION = "R4633" &SEC = "1" #&CDS_SEC = "1";
"A":   PN = "1"  !CDS_PN = "1";
"B":   PN = "2"  !CDS_PN = "2";
BODY = "Q_RES","I26": LOCATION = "R4632" #&CDS_LOCATION = "R4632" &SEC = "1" #&CDS_SEC = "1";
"A":   PN = "1"  !CDS_PN = "1";
"B":   PN = "2"  !CDS_PN = "2";
DRAWING = "@s9s_mb_2u_lib.s9s_mb_2u(sch_1):page328";
BODY = "Q_RES","I16": #LOCATION = "PR2528" !CDS_LOCATION = "PR2528" &SEC = "1" #&CDS_SEC = "1";
"A":   PN = "1"  !CDS_PN = "1";
"B":   PN = "2"  !CDS_PN = "2";
BODY = "MOSFET_NCH_1D3S","I35": #LOCATION = "PPQ5" !CDS_LOCATION = "PPQ5" &SEC = "1" #&CDS_SEC = "1";
"1":   PN = "1"  !CDS_PN = "1";
"2":   PN = "2"  !CDS_PN = "2";
"3":   PN = "3"  !CDS_PN = "3";
"4":   PN = "4"  !CDS_PN = "4";
"5":   PN = "5"  !CDS_PN = "5";
BODY = "Q_RES","I38": #LOCATION = "PR2529" !CDS_LOCATION = "PR2529" &SEC = "1" #&CDS_SEC = "1";
"A":   PN = "1"  !CDS_PN = "1";
"B":   PN = "2"  !CDS_PN = "2";
BODY = "Q_RES","I39": #LOCATION = "PR2530" !CDS_LOCATION = "PR2530" &SEC = "1" #&CDS_SEC = "1";
"A":   PN = "1"  !CDS_PN = "1";
"B":   PN = "2"  !CDS_PN = "2";
BODY = "MOSFET_NCH_1D3S","I40": #LOCATION = "PPQ6" !CDS_LOCATION = "PPQ6" &SEC = "1" #&CDS_SEC = "1";
"1":   PN = "1"  !CDS_PN = "1";
"2":   PN = "2"  !CDS_PN = "2";
"3":   PN = "3"  !CDS_PN = "3";
"4":   PN = "4"  !CDS_PN = "4";
"5":   PN = "5"  !CDS_PN = "5";
BODY = "MOSFET_NCH_1D3S","I41": #LOCATION = "PPQ7" !CDS_LOCATION = "PPQ7" &SEC = "1" #&CDS_SEC = "1";
"1":   PN = "1"  !CDS_PN = "1";
"2":   PN = "2"  !CDS_PN = "2";
"3":   PN = "3"  !CDS_PN = "3";
"4":   PN = "4"  !CDS_PN = "4";
"5":   PN = "5"  !CDS_PN = "5";
BODY = "ZENER_AC","I51": #LOCATION = "PD15" !CDS_LOCATION = "PD15" &SEC = "1" #&CDS_SEC = "1";
"A":   PN = "A"  !CDS_PN = "A";
"C":   PN = "C"  !CDS_PN = "C";
BODY = "ZENER_AC","I53": #LOCATION = "PD16" !CDS_LOCATION = "PD16" &SEC = "1" #&CDS_SEC = "1";
"A":   PN = "A"  !CDS_PN = "A";
"C":   PN = "C"  !CDS_PN = "C";
BODY = "Q_FUSE","I54": #LOCATION = "FS1" !CDS_LOCATION = "FS1" &SEC = "1" #&CDS_SEC = "1";
"1":   PN = "1"  !CDS_PN = "1";
"2":   PN = "2"  !CDS_PN = "2";
BODY = "Q_RES","I59": #LOCATION = "PR2531" !CDS_LOCATION = "PR2531" &SEC = "1" #&CDS_SEC = "1";
"A":   PN = "1"  !CDS_PN = "1";
"B":   PN = "2"  !CDS_PN = "2";
BODY = "Q_RES","I60": #LOCATION = "PR2535" !CDS_LOCATION = "PR2535" &SEC = "1" #&CDS_SEC = "1";
"A":   PN = "1"  !CDS_PN = "1";
"B":   PN = "2"  !CDS_PN = "2";
BODY = "Q_RES","I61": #LOCATION = "PR2536" !CDS_LOCATION = "PR2536" &SEC = "1" #&CDS_SEC = "1";
"A":   PN = "1"  !CDS_PN = "1";
"B":   PN = "2"  !CDS_PN = "2";
BODY = "MOSFET_NCH_1D3S","I62": #LOCATION = "PPQ8" !CDS_LOCATION = "PPQ8" &SEC = "1" #&CDS_SEC = "1";
"1":   PN = "1"  !CDS_PN = "1";
"2":   PN = "2"  !CDS_PN = "2";
"3":   PN = "3"  !CDS_PN = "3";
"4":   PN = "4"  !CDS_PN = "4";
"5":   PN = "5"  !CDS_PN = "5";
BODY = "Q_SP_RES4P","I63": #LOCATION = "PR2534" !CDS_LOCATION = "PR2534" &SEC = "1" #&CDS_SEC = "1";
"1A":   PN = "1A"  !CDS_PN = "1A";
"1B":   PN = "1B"  !CDS_PN = "1B";
"2A":   PN = "2A"  !CDS_PN = "2A";
"2B":   PN = "2B"  !CDS_PN = "2B";
BODY = "Q_SP_RES4P","I64": #LOCATION = "PR2533" !CDS_LOCATION = "PR2533" &SEC = "1" #&CDS_SEC = "1";
"1A":   PN = "1A"  !CDS_PN = "1A";
"1B":   PN = "1B"  !CDS_PN = "1B";
"2A":   PN = "2A"  !CDS_PN = "2A";
"2B":   PN = "2B"  !CDS_PN = "2B";
BODY = "MOSFET_NCH_1D3S","I65": #LOCATION = "PPQ1" !CDS_LOCATION = "PPQ1" #SEC = "1" !CDS_SEC = "1";
"1":   PN = "1"  !CDS_PN = "1";
"2":   PN = "2"  !CDS_PN = "2";
"3":   PN = "3"  !CDS_PN = "3";
"4":   PN = "4"  !CDS_PN = "4";
"5":   PN = "5"  !CDS_PN = "5";
BODY = "Q_CAP","I68": #LOCATION = "PC1750" !CDS_LOCATION = "PC1750" &SEC = "1" #&CDS_SEC = "1";
"A":   PN = "1"  !CDS_PN = "1";
"B":   PN = "2"  !CDS_PN = "2";
BODY = "Q_CAP","I69": #LOCATION = "PC1751" !CDS_LOCATION = "PC1751" &SEC = "1" #&CDS_SEC = "1";
"A":   PN = "1"  !CDS_PN = "1";
"B":   PN = "2"  !CDS_PN = "2";
BODY = "Q_RES","I70": #LOCATION = "PR2537" !CDS_LOCATION = "PR2537" &SEC = "1" #&CDS_SEC = "1";
"A":   PN = "1"  !CDS_PN = "1";
"B":   PN = "2"  !CDS_PN = "2";
BODY = "SS15P3SM386A","I72": #LOCATION = "PD17" !CDS_LOCATION = "PD17" &SEC = "1" #&CDS_SEC = "1";
"ANODE_1":   PN = "1"  !CDS_PN = "1";
"ANODE_2":   PN = "2"  !CDS_PN = "2";
"CATHODE":   PN = "K"  !CDS_PN = "K";
BODY = "MOSFET_NCH_1D3S","I73": #LOCATION = "PPQ2" !CDS_LOCATION = "PPQ2" #SEC = "1" !CDS_SEC = "1";
"1":   PN = "1"  !CDS_PN = "1";
"2":   PN = "2"  !CDS_PN = "2";
"3":   PN = "3"  !CDS_PN = "3";
"4":   PN = "4"  !CDS_PN = "4";
"5":   PN = "5"  !CDS_PN = "5";
BODY = "Q_RES","I76": #LOCATION = "PR2538" !CDS_LOCATION = "PR2538" &SEC = "1" #&CDS_SEC = "1";
"A":   PN = "1"  !CDS_PN = "1";
"B":   PN = "2"  !CDS_PN = "2";
BODY = "MOSFET_NCH_1D3S","I77": #LOCATION = "PPQ9" !CDS_LOCATION = "PPQ9" &SEC = "1" #&CDS_SEC = "1";
"1":   PN = "1"  !CDS_PN = "1";
"2":   PN = "2"  !CDS_PN = "2";
"3":   PN = "3"  !CDS_PN = "3";
"4":   PN = "4"  !CDS_PN = "4";
"5":   PN = "5"  !CDS_PN = "5";
BODY = "Q_SP_RES4P","I78": #LOCATION = "PR2532" !CDS_LOCATION = "PR2532" &SEC = "1" #&CDS_SEC = "1";
"1A":   PN = "1A"  !CDS_PN = "1A";
"1B":   PN = "1B"  !CDS_PN = "1B";
"2A":   PN = "2A"  !CDS_PN = "2A";
"2B":   PN = "2B"  !CDS_PN = "2B";
BODY = "Q_SP_RES4P","I79": #LOCATION = "PR4" !CDS_LOCATION = "PR4" #SEC = "1" !CDS_SEC = "1";
"1A":   PN = "1A"  !CDS_PN = "1A";
"1B":   PN = "1B"  !CDS_PN = "1B";
"2A":   PN = "2A"  !CDS_PN = "2A";
"2B":   PN = "2B"  !CDS_PN = "2B";
BODY = "Q_RES","I86": #LOCATION = "PR2522" !CDS_LOCATION = "PR2522" &SEC = "1" #&CDS_SEC = "1";
"A":   PN = "1"  !CDS_PN = "1";
"B":   PN = "2"  !CDS_PN = "2";
BODY = "Q_RES","I87": #LOCATION = "PR2523" !CDS_LOCATION = "PR2523" &SEC = "1" #&CDS_SEC = "1";
"A":   PN = "1"  !CDS_PN = "1";
"B":   PN = "2"  !CDS_PN = "2";
BODY = "Q_RES","I88": #LOCATION = "PR2521" !CDS_LOCATION = "PR2521" &SEC = "1" #&CDS_SEC = "1";
"A":   PN = "1"  !CDS_PN = "1";
"B":   PN = "2"  !CDS_PN = "2";
BODY = "Q_RES","I89": #LOCATION = "PR2520" !CDS_LOCATION = "PR2520" &SEC = "1" #&CDS_SEC = "1";
"A":   PN = "1"  !CDS_PN = "1";
"B":   PN = "2"  !CDS_PN = "2";
BODY = "Q_RES","I90": #LOCATION = "PR2517" !CDS_LOCATION = "PR2517" &SEC = "1" #&CDS_SEC = "1";
"A":   PN = "1"  !CDS_PN = "1";
"B":   PN = "2"  !CDS_PN = "2";
BODY = "Q_RES","I91": #LOCATION = "PR2518" !CDS_LOCATION = "PR2518" &SEC = "1" #&CDS_SEC = "1";
"A":   PN = "1"  !CDS_PN = "1";
"B":   PN = "2"  !CDS_PN = "2";
BODY = "Q_RES","I92": #LOCATION = "PR2519" !CDS_LOCATION = "PR2519" &SEC = "1" #&CDS_SEC = "1";
"A":   PN = "1"  !CDS_PN = "1";
"B":   PN = "2"  !CDS_PN = "2";
BODY = "Q_RES","I93": #LOCATION = "PR2515" !CDS_LOCATION = "PR2515" &SEC = "1" #&CDS_SEC = "1";
"A":   PN = "1"  !CDS_PN = "1";
"B":   PN = "2"  !CDS_PN = "2";
BODY = "Q_RES","I94": #LOCATION = "PR2516" !CDS_LOCATION = "PR2516" &SEC = "1" #&CDS_SEC = "1";
"A":   PN = "1"  !CDS_PN = "1";
"B":   PN = "2"  !CDS_PN = "2";
BODY = "Q_RES","I95": #LOCATION = "PR2513" !CDS_LOCATION = "PR2513" &SEC = "1" #&CDS_SEC = "1";
"A":   PN = "1"  !CDS_PN = "1";
"B":   PN = "2"  !CDS_PN = "2";
BODY = "Q_RES","I96": #LOCATION = "PR2512" !CDS_LOCATION = "PR2512" &SEC = "1" #&CDS_SEC = "1";
"A":   PN = "1"  !CDS_PN = "1";
"B":   PN = "2"  !CDS_PN = "2";
BODY = "Q_RES","I97": #LOCATION = "PR2514" !CDS_LOCATION = "PR2514" &SEC = "1" #&CDS_SEC = "1";
"A":   PN = "1"  !CDS_PN = "1";
"B":   PN = "2"  !CDS_PN = "2";
BODY = "Q_RES","I98": #LOCATION = "PR2510" !CDS_LOCATION = "PR2510" &SEC = "1" #&CDS_SEC = "1";
"A":   PN = "1"  !CDS_PN = "1";
"B":   PN = "2"  !CDS_PN = "2";
BODY = "Q_RES","I99": #LOCATION = "PR2511" !CDS_LOCATION = "PR2511" &SEC = "1" #&CDS_SEC = "1";
"A":   PN = "1"  !CDS_PN = "1";
"B":   PN = "2"  !CDS_PN = "2";
BODY = "Q_RES","I117": #LOCATION = "PR2527" !CDS_LOCATION = "PR2527" &SEC = "1" #&CDS_SEC = "1";
"A":   PN = "1"  !CDS_PN = "1";
"B":   PN = "2"  !CDS_PN = "2";
BODY = "Q_RES","I118": #LOCATION = "PR2526" !CDS_LOCATION = "PR2526" &SEC = "1" #&CDS_SEC = "1";
"A":   PN = "1"  !CDS_PN = "1";
"B":   PN = "2"  !CDS_PN = "2";
BODY = "Q_RES","I119": #LOCATION = "PR2524" !CDS_LOCATION = "PR2524" &SEC = "1" #&CDS_SEC = "1";
"A":   PN = "1"  !CDS_PN = "1";
"B":   PN = "2"  !CDS_PN = "2";
BODY = "Q_RES","I120": #LOCATION = "PR2525" !CDS_LOCATION = "PR2525" &SEC = "1" #&CDS_SEC = "1";
"A":   PN = "1"  !CDS_PN = "1";
"B":   PN = "2"  !CDS_PN = "2";
BODY = "Q_RES_4P_12","I126": #LOCATION = "PR3" !CDS_LOCATION = "PR3" &SEC = "1" #&CDS_SEC = "1";
"1":   PN = "1"  !CDS_PN = "1";
"2":   PN = "2"  !CDS_PN = "2";
"3":   PN = "3"  !CDS_PN = "3";
"4":   PN = "4"  !CDS_PN = "4";
DRAWING = "@s9s_mb_2u_lib.s9s_mb_2u(sch_1):page327";
BODY = "Q_RES","I4": #LOCATION = "R4893" !CDS_LOCATION = "R4893" &SEC = "1" #&CDS_SEC = "1";
"A":   PN = "1"  !CDS_PN = "1";
"B":   PN = "2"  !CDS_PN = "2";
BODY = "Q_RES","I5": #LOCATION = "R4892" !CDS_LOCATION = "R4892" &SEC = "1" #&CDS_SEC = "1";
"A":   PN = "1"  !CDS_PN = "1";
"B":   PN = "2"  !CDS_PN = "2";
BODY = "Q_CAP","I6": #LOCATION = "C2459" !CDS_LOCATION = "C2459" &SEC = "1" #&CDS_SEC = "1";
"A":   PN = "1"  !CDS_PN = "1";
"B":   PN = "2"  !CDS_PN = "2";
BODY = "Q_CAP","I8": #LOCATION = "C2458" !CDS_LOCATION = "C2458" &SEC = "1" #&CDS_SEC = "1";
"A":   PN = "1"  !CDS_PN = "1";
"B":   PN = "2"  !CDS_PN = "2";
BODY = "NCT7718W","I10": #LOCATION = "U345" !CDS_LOCATION = "U345" &SEC = "1" #&CDS_SEC = "1";
"ALERT#":   PN = "6"  !CDS_PN = "6";
"D+":   PN = "2"  !CDS_PN = "2";
"D-":   PN = "3"  !CDS_PN = "3";
"GND":   PN = "5"  !CDS_PN = "5";
"SCL":   PN = "8"  !CDS_PN = "8";
"SDA":   PN = "7"  !CDS_PN = "7";
"T_CRIT#":   PN = "4"  !CDS_PN = "4";
"VDD":   PN = "1"  !CDS_PN = "1";
BODY = "Q_RES","I11": #LOCATION = "R4896" !CDS_LOCATION = "R4896" &SEC = "1" #&CDS_SEC = "1";
"A":   PN = "1"  !CDS_PN = "1";
"B":   PN = "2"  !CDS_PN = "2";
BODY = "Q_RES","I14": LOCATION = "R4684" #&CDS_LOCATION = "R4684" &SEC = "1" #&CDS_SEC = "1";
"A":   PN = "1"  !CDS_PN = "1";
"B":   PN = "2"  !CDS_PN = "2";
BODY = "Q_RES","I15": #LOCATION = "R4894" !CDS_LOCATION = "R4894" &SEC = "1" #&CDS_SEC = "1";
"A":   PN = "1"  !CDS_PN = "1";
"B":   PN = "2"  !CDS_PN = "2";
BODY = "Q_RES","I16": #LOCATION = "R4895" !CDS_LOCATION = "R4895" &SEC = "1" #&CDS_SEC = "1";
"A":   PN = "1"  !CDS_PN = "1";
"B":   PN = "2"  !CDS_PN = "2";
BODY = "Q_RES","I17": LOCATION = "R4686" #&CDS_LOCATION = "R4686" &SEC = "1" #&CDS_SEC = "1";
"A":   PN = "1"  !CDS_PN = "1";
"B":   PN = "2"  !CDS_PN = "2";
BODY = "Q_RES","I23": LOCATION = "R4685" #&CDS_LOCATION = "R4685" &SEC = "1" #&CDS_SEC = "1";
"A":   PN = "1"  !CDS_PN = "1";
"B":   PN = "2"  !CDS_PN = "2";
BODY = "Q_RES","I25": LOCATION = "R4696" #&CDS_LOCATION = "R4696" &SEC = "1" #&CDS_SEC = "1";
"A":   PN = "1"  !CDS_PN = "1";
"B":   PN = "2"  !CDS_PN = "2";
BODY = "Q_RES","I26": LOCATION = "R4695" #&CDS_LOCATION = "R4695" &SEC = "1" #&CDS_SEC = "1";
"A":   PN = "1"  !CDS_PN = "1";
"B":   PN = "2"  !CDS_PN = "2";
BODY = "SCONN21_9193031121LF","I34": #LOCATION = "PJ42" !CDS_LOCATION = "PJ42" &SEC = "1" #&CDS_SEC = "1";
"1":   PN = "1"  !CDS_PN = "1";
"2":   PN = "2"  !CDS_PN = "2";
"3":   PN = "3"  !CDS_PN = "3";
"4":   PN = "4"  !CDS_PN = "4";
"5":   PN = "5"  !CDS_PN = "5";
"6":   PN = "6"  !CDS_PN = "6";
"7":   PN = "7"  !CDS_PN = "7";
"8":   PN = "8"  !CDS_PN = "8";
"9":   PN = "9"  !CDS_PN = "9";
"10":   PN = "10"  !CDS_PN = "10";
"11":   PN = "11"  !CDS_PN = "11";
"12":   PN = "12"  !CDS_PN = "12";
"13":   PN = "13"  !CDS_PN = "13";
"14":   PN = "14"  !CDS_PN = "14";
"15":   PN = "15"  !CDS_PN = "15";
"16":   PN = "16"  !CDS_PN = "16";
"17":   PN = "17"  !CDS_PN = "17";
"18":   PN = "18"  !CDS_PN = "18";
"19":   PN = "19"  !CDS_PN = "19";
"20":   PN = "20"  !CDS_PN = "20";
"21":   PN = "21"  !CDS_PN = "21";
"G1":   PN = "G1"  !CDS_PN = "G1";
"G2":   PN = "G2"  !CDS_PN = "G2";
BODY = "Q_CAP","I38": LOCATION = "PC1789" #&CDS_LOCATION = "PC1789" &SEC = "1" #&CDS_SEC = "1";
"A":   PN = "1"  !CDS_PN = "1";
"B":   PN = "2"  !CDS_PN = "2";
BODY = "MMBT3904","I49": #LOCATION = "U365" !CDS_LOCATION = "U365" &SEC = "1" #&CDS_SEC = "1";
"1":   PN = "B"  !CDS_PN = "B";
"2":   PN = "E"  !CDS_PN = "E";
"3":   PN = "C"  !CDS_PN = "C";
BODY = "CONN3_210HP1030BR1","I51": LOCATION = "JP10" #&CDS_LOCATION = "JP10" &SEC = "1" #&CDS_SEC = "1";
"1":   PN = "1"  !CDS_PN = "1";
"2":   PN = "2"  !CDS_PN = "2";
"3":   PN = "3"  !CDS_PN = "3";
DRAWING = "@s9s_mb_2u_lib.s9s_mb_2u(sch_1):page326";
BODY = "Q_RES","I2": LOCATION = "R2238" #&CDS_LOCATION = "R2238" &SEC = "1" #&CDS_SEC = "1";
"A":   PN = "1"  !CDS_PN = "1";
"B":   PN = "2"  !CDS_PN = "2";
BODY = "TPS3700DDCR","I5": LOCATION = "U205" #&CDS_LOCATION = "U205" &SEC = "1" #&CDS_SEC = "1";
"GND":   PN = "2"  !CDS_PN = "2";
"INA+":   PN = "3"  !CDS_PN = "3";
"INB-":   PN = "4"  !CDS_PN = "4";
"OUTA":   PN = "1"  !CDS_PN = "1";
"OUTB":   PN = "6"  !CDS_PN = "6";
"VDD":   PN = "5"  !CDS_PN = "5";
BODY = "Q_RES","I7": #LOCATION = "R2236" !CDS_LOCATION = "R2236" &SEC = "1" #&CDS_SEC = "1";
"A":   PN = "1"  !CDS_PN = "1";
"B":   PN = "2"  !CDS_PN = "2";
BODY = "Q_RES","I13": LOCATION = "R4668" #&CDS_LOCATION = "R4668" &SEC = "1" #&CDS_SEC = "1";
"A":   PN = "1"  !CDS_PN = "1";
"B":   PN = "2"  !CDS_PN = "2";
BODY = "Q_RES","I14": LOCATION = "R4667" #&CDS_LOCATION = "R4667" &SEC = "1" #&CDS_SEC = "1";
"A":   PN = "1"  !CDS_PN = "1";
"B":   PN = "2"  !CDS_PN = "2";
BODY = "Q_RES","I17": #LOCATION = "R2222" !CDS_LOCATION = "R2222" &SEC = "1" #&CDS_SEC = "1";
"A":   PN = "1"  !CDS_PN = "1";
"B":   PN = "2"  !CDS_PN = "2";
BODY = "Q_RES","I20": #LOCATION = "R2221" !CDS_LOCATION = "R2221" &SEC = "1" #&CDS_SEC = "1";
"A":   PN = "1"  !CDS_PN = "1";
"B":   PN = "2"  !CDS_PN = "2";
BODY = "Q_RES","I24": LOCATION = "R4670" #&CDS_LOCATION = "R4670" &SEC = "1" #&CDS_SEC = "1";
"A":   PN = "1"  !CDS_PN = "1";
"B":   PN = "2"  !CDS_PN = "2";
BODY = "Q_RES","I25": LOCATION = "R4669" #&CDS_LOCATION = "R4669" &SEC = "1" #&CDS_SEC = "1";
"A":   PN = "1"  !CDS_PN = "1";
"B":   PN = "2"  !CDS_PN = "2";
BODY = "Q_RES","I29": LOCATION = "R4693" #&CDS_LOCATION = "R4693" &SEC = "1" #&CDS_SEC = "1";
"A":   PN = "1"  !CDS_PN = "1";
"B":   PN = "2"  !CDS_PN = "2";
BODY = "TPS3700DDCR","I30": #LOCATION = "U369" !CDS_LOCATION = "U369" &SEC = "1" #&CDS_SEC = "1";
"GND":   PN = "2"  !CDS_PN = "2";
"INA+":   PN = "3"  !CDS_PN = "3";
"INB-":   PN = "4"  !CDS_PN = "4";
"OUTA":   PN = "1"  !CDS_PN = "1";
"OUTB":   PN = "6"  !CDS_PN = "6";
"VDD":   PN = "5"  !CDS_PN = "5";
BODY = "Q_RES","I33": #LOCATION = "R2330" !CDS_LOCATION = "R2330" &SEC = "1" #&CDS_SEC = "1";
"A":   PN = "1"  !CDS_PN = "1";
"B":   PN = "2"  !CDS_PN = "2";
BODY = "MOSFET_N","I38": LOCATION = "U325" #&CDS_LOCATION = "U325" &SEC = "1" #&CDS_SEC = "1";
"DRAIN":   PN = "D"  !CDS_PN = "D";
"GATE":   PN = "G"  !CDS_PN = "G";
"SOURCE":   PN = "S"  !CDS_PN = "S";
BODY = "Q_RES","I39": #LOCATION = "R2230" !CDS_LOCATION = "R2230" &SEC = "1" #&CDS_SEC = "1";
"A":   PN = "1"  !CDS_PN = "1";
"B":   PN = "2"  !CDS_PN = "2";
BODY = "Q_RES","I41": #LOCATION = "R2233" !CDS_LOCATION = "R2233" &SEC = "1" #&CDS_SEC = "1";
"A":   PN = "1"  !CDS_PN = "1";
"B":   PN = "2"  !CDS_PN = "2";
BODY = "Q_RES","I44": LOCATION = "R4673" #&CDS_LOCATION = "R4673" &SEC = "1" #&CDS_SEC = "1";
"A":   PN = "1"  !CDS_PN = "1";
"B":   PN = "2"  !CDS_PN = "2";
BODY = "Q_RES","I45": LOCATION = "R4620" #&CDS_LOCATION = "R4620" &SEC = "1" #&CDS_SEC = "1";
"A":   PN = "1"  !CDS_PN = "1";
"B":   PN = "2"  !CDS_PN = "2";
BODY = "MOSFET_NCH_GDS_ESD_PROTECTED","I46": LOCATION = "U329" #&CDS_LOCATION = "U329" &SEC = "1" #&CDS_SEC = "1";
"D":   PN = "D"  !CDS_PN = "D";
"G":   PN = "G"  !CDS_PN = "G";
"S":   PN = "S"  !CDS_PN = "S";
BODY = "Q_RES","I48": #LOCATION = "R4652" !CDS_LOCATION = "R4652" &SEC = "1" #&CDS_SEC = "1";
"A":   PN = "1"  !CDS_PN = "1";
"B":   PN = "2"  !CDS_PN = "2";
BODY = "Q_RES","I51": LOCATION = "R4671" #&CDS_LOCATION = "R4671" &SEC = "1" #&CDS_SEC = "1";
"A":   PN = "1"  !CDS_PN = "1";
"B":   PN = "2"  !CDS_PN = "2";
BODY = "Q_RES","I53": LOCATION = "R4672" #&CDS_LOCATION = "R4672" &SEC = "1" #&CDS_SEC = "1";
"A":   PN = "1"  !CDS_PN = "1";
"B":   PN = "2"  !CDS_PN = "2";
BODY = "LM4040AIM3X25NOPB","I56": LOCATION = "U343" #&CDS_LOCATION = "U343" &SEC = "1" #&CDS_SEC = "1";
"1+":   PN = "1"  !CDS_PN = "1";
"2-":   PN = "2"  !CDS_PN = "2";
"3":   PN = "3"  !CDS_PN = "3";
BODY = "Q_RES","I57": LOCATION = "R4792" #&CDS_LOCATION = "R4792" &SEC = "1" #&CDS_SEC = "1";
"A":   PN = "1"  !CDS_PN = "1";
"B":   PN = "2"  !CDS_PN = "2";
BODY = "Q_CAP","I64": LOCATION = "C2388" #&CDS_LOCATION = "C2388" &SEC = "1" #&CDS_SEC = "1";
"A":   PN = "1"  !CDS_PN = "1";
"B":   PN = "2"  !CDS_PN = "2";
BODY = "AP331AWG7","I66": LOCATION = "U344" #&CDS_LOCATION = "U344" &SEC = "1" #&CDS_SEC = "1";
"GND":   PN = "2"  !CDS_PN = "2";
"IN+":   PN = "3"  !CDS_PN = "3";
"IN-":   PN = "1"  !CDS_PN = "1";
"OUTPUT":   PN = "4"  !CDS_PN = "4";
"VCC":   PN = "5"  !CDS_PN = "5";
BODY = "Q_RES","I68": LOCATION = "R4793" #&CDS_LOCATION = "R4793" &SEC = "1" #&CDS_SEC = "1";
"A":   PN = "1"  !CDS_PN = "1";
"B":   PN = "2"  !CDS_PN = "2";
BODY = "Q_CAP","I71": LOCATION = "C2390" #&CDS_LOCATION = "C2390" &SEC = "1" #&CDS_SEC = "1";
"A":   PN = "1"  !CDS_PN = "1";
"B":   PN = "2"  !CDS_PN = "2";
BODY = "Q_RES","I72": LOCATION = "R4794" #&CDS_LOCATION = "R4794" &SEC = "1" #&CDS_SEC = "1";
"A":   PN = "1"  !CDS_PN = "1";
"B":   PN = "2"  !CDS_PN = "2";
BODY = "Q_CAP","I76": LOCATION = "C2389" #&CDS_LOCATION = "C2389" &SEC = "1" #&CDS_SEC = "1";
"A":   PN = "1"  !CDS_PN = "1";
"B":   PN = "2"  !CDS_PN = "2";
BODY = "Q_RES","I77": LOCATION = "R4796" #&CDS_LOCATION = "R4796" &SEC = "1" #&CDS_SEC = "1";
"A":   PN = "1"  !CDS_PN = "1";
"B":   PN = "2"  !CDS_PN = "2";
BODY = "Q_RES","I78": LOCATION = "R4795" #&CDS_LOCATION = "R4795" &SEC = "1" #&CDS_SEC = "1";
"A":   PN = "1"  !CDS_PN = "1";
"B":   PN = "2"  !CDS_PN = "2";
BODY = "Q_RES","I80": LOCATION = "R4797" #&CDS_LOCATION = "R4797" &SEC = "1" #&CDS_SEC = "1";
"A":   PN = "1"  !CDS_PN = "1";
"B":   PN = "2"  !CDS_PN = "2";
BODY = "Q_CAP","I89": #LOCATION = "C1562" !CDS_LOCATION = "C1562" &SEC = "1" #&CDS_SEC = "1";
"A":   PN = "1"  !CDS_PN = "1";
"B":   PN = "2"  !CDS_PN = "2";
BODY = "Q_CAP","I90": #LOCATION = "C1561" !CDS_LOCATION = "C1561" &SEC = "1" #&CDS_SEC = "1";
"A":   PN = "1"  !CDS_PN = "1";
"B":   PN = "2"  !CDS_PN = "2";
BODY = "Q_CAP","I91": #LOCATION = "C4562" !CDS_LOCATION = "C4562" &SEC = "1" #&CDS_SEC = "1";
"A":   PN = "1"  !CDS_PN = "1";
"B":   PN = "2"  !CDS_PN = "2";
BODY = "Q_CAP","I92": LOCATION = "C2393" #&CDS_LOCATION = "C2393" &SEC = "1" #&CDS_SEC = "1";
"A":   PN = "1"  !CDS_PN = "1";
"B":   PN = "2"  !CDS_PN = "2";
BODY = "Q_CAP","I93": LOCATION = "C2394" #&CDS_LOCATION = "C2394" &SEC = "1" #&CDS_SEC = "1";
"A":   PN = "1"  !CDS_PN = "1";
"B":   PN = "2"  !CDS_PN = "2";
BODY = "Q_CAP","I95": LOCATION = "C2392" #&CDS_LOCATION = "C2392" &SEC = "1" #&CDS_SEC = "1";
"A":   PN = "1"  !CDS_PN = "1";
"B":   PN = "2"  !CDS_PN = "2";
BODY = "Q_RES","I97": #LOCATION = "R4804" !CDS_LOCATION = "R4804" &SEC = "1" #&CDS_SEC = "1";
"A":   PN = "1"  !CDS_PN = "1";
"B":   PN = "2"  !CDS_PN = "2";
BODY = "Q_RES","I98": #LOCATION = "R4806" !CDS_LOCATION = "R4806" &SEC = "1" #&CDS_SEC = "1";
"A":   PN = "1"  !CDS_PN = "1";
"B":   PN = "2"  !CDS_PN = "2";
BODY = "Q_RES","I99": #LOCATION = "R4805" !CDS_LOCATION = "R4805" &SEC = "1" #&CDS_SEC = "1";
"A":   PN = "1"  !CDS_PN = "1";
"B":   PN = "2"  !CDS_PN = "2";
BODY = "Q_RES","I100": #LOCATION = "R2219" !CDS_LOCATION = "R2219" &SEC = "1" #&CDS_SEC = "1";
"A":   PN = "1"  !CDS_PN = "1";
"B":   PN = "2"  !CDS_PN = "2";
BODY = "Q_RES","I101": #LOCATION = "R2227" !CDS_LOCATION = "R2227" &SEC = "1" #&CDS_SEC = "1";
"A":   PN = "1"  !CDS_PN = "1";
"B":   PN = "2"  !CDS_PN = "2";
BODY = "LT6700CS61TRPBF","I102": #LOCATION = "U206" !CDS_LOCATION = "U206" &SEC = "1" #&CDS_SEC = "1";
"GND":   PN = "2"  !CDS_PN = "2";
"INA+":   PN = "3"  !CDS_PN = "3";
"INB-":   PN = "4"  !CDS_PN = "4";
"OUTA":   PN = "1"  !CDS_PN = "1";
"OUTB":   PN = "6"  !CDS_PN = "6";
"VS":   PN = "5"  !CDS_PN = "5";
DRAWING = "@s9s_mb_2u_lib.s9s_mb_2u(sch_1):page209";
BODY = "Q_CAP","I3": #LOCATION = "C1209" !CDS_LOCATION = "C1209" &SEC = "1" #&CDS_SEC = "1";
"A":   PN = "1"  !CDS_PN = "1";
"B":   PN = "2"  !CDS_PN = "2";
BODY = "Q_CAP","I4": #LOCATION = "C1211" !CDS_LOCATION = "C1211" &SEC = "1" #&CDS_SEC = "1";
"A":   PN = "1"  !CDS_PN = "1";
"B":   PN = "2"  !CDS_PN = "2";
BODY = "Q_RES","I11": LOCATION = "R736" #&CDS_LOCATION = "R736" &SEC = "1" #&CDS_SEC = "1";
"A":   PN = "1"  !CDS_PN = "1";
"B":   PN = "2"  !CDS_PN = "2";
BODY = "Q_RES","I13": LOCATION = "R735" #&CDS_LOCATION = "R735" &SEC = "1" #&CDS_SEC = "1";
"A":   PN = "1"  !CDS_PN = "1";
"B":   PN = "2"  !CDS_PN = "2";
BODY = "Q_RES","I14": LOCATION = "R1660" #&CDS_LOCATION = "R1660" &SEC = "1" #&CDS_SEC = "1";
"A":   PN = "1"  !CDS_PN = "1";
"B":   PN = "2"  !CDS_PN = "2";
BODY = "Q_RES","I15": LOCATION = "R1558" #&CDS_LOCATION = "R1558" &SEC = "1" #&CDS_SEC = "1";
"A":   PN = "1"  !CDS_PN = "1";
"B":   PN = "2"  !CDS_PN = "2";
BODY = "Q_RES","I16": LOCATION = "R1401" #&CDS_LOCATION = "R1401" &SEC = "1" #&CDS_SEC = "1";
"A":   PN = "1"  !CDS_PN = "1";
"B":   PN = "2"  !CDS_PN = "2";
BODY = "Q_RES","I17": LOCATION = "R1399" #&CDS_LOCATION = "R1399" &SEC = "1" #&CDS_SEC = "1";
"A":   PN = "1"  !CDS_PN = "1";
"B":   PN = "2"  !CDS_PN = "2";
BODY = "Q_RES","I21": LOCATION = "R1494" #&CDS_LOCATION = "R1494" &SEC = "1" #&CDS_SEC = "1";
"A":   PN = "1"  !CDS_PN = "1";
"B":   PN = "2"  !CDS_PN = "2";
BODY = "Q_RES","I22": LOCATION = "R1312" #&CDS_LOCATION = "R1312" &SEC = "1" #&CDS_SEC = "1";
"A":   PN = "1"  !CDS_PN = "1";
"B":   PN = "2"  !CDS_PN = "2";
BODY = "Q_RES","I23": LOCATION = "R1308" #&CDS_LOCATION = "R1308" &SEC = "1" #&CDS_SEC = "1";
"A":   PN = "1"  !CDS_PN = "1";
"B":   PN = "2"  !CDS_PN = "2";
BODY = "Q_RES","I24": LOCATION = "R1742" #&CDS_LOCATION = "R1742" &SEC = "1" #&CDS_SEC = "1";
"A":   PN = "1"  !CDS_PN = "1";
"B":   PN = "2"  !CDS_PN = "2";
BODY = "Q_RES","I35": LOCATION = "R1492" #&CDS_LOCATION = "R1492" &SEC = "1" #&CDS_SEC = "1";
"A":   PN = "1"  !CDS_PN = "1";
"B":   PN = "2"  !CDS_PN = "2";
BODY = "Q_RES","I36": LOCATION = "R1474" #&CDS_LOCATION = "R1474" &SEC = "1" #&CDS_SEC = "1";
"A":   PN = "1"  !CDS_PN = "1";
"B":   PN = "2"  !CDS_PN = "2";
BODY = "Q_RES","I37": LOCATION = "R1473" #&CDS_LOCATION = "R1473" &SEC = "1" #&CDS_SEC = "1";
"A":   PN = "1"  !CDS_PN = "1";
"B":   PN = "2"  !CDS_PN = "2";
BODY = "Q_RES","I38": LOCATION = "R1741" #&CDS_LOCATION = "R1741" &SEC = "1" #&CDS_SEC = "1";
"A":   PN = "1"  !CDS_PN = "1";
"B":   PN = "2"  !CDS_PN = "2";
BODY = "Q_RES","I39": LOCATION = "R2244" #&CDS_LOCATION = "R2244" &SEC = "1" #&CDS_SEC = "1";
"A":   PN = "1"  !CDS_PN = "1";
"B":   PN = "2"  !CDS_PN = "2";
BODY = "Q_RES","I40": LOCATION = "R139" #&CDS_LOCATION = "R139" &SEC = "1" #&CDS_SEC = "1";
"A":   PN = "1"  !CDS_PN = "1";
"B":   PN = "2"  !CDS_PN = "2";
BODY = "Q_RES","I41": LOCATION = "R1440" #&CDS_LOCATION = "R1440" &SEC = "1" #&CDS_SEC = "1";
"A":   PN = "1"  !CDS_PN = "1";
"B":   PN = "2"  !CDS_PN = "2";
BODY = "Q_RES","I42": LOCATION = "R1437" #&CDS_LOCATION = "R1437" &SEC = "1" #&CDS_SEC = "1";
"A":   PN = "1"  !CDS_PN = "1";
"B":   PN = "2"  !CDS_PN = "2";
BODY = "Q_RES","I43": LOCATION = "R1435" #&CDS_LOCATION = "R1435" &SEC = "1" #&CDS_SEC = "1";
"A":   PN = "1"  !CDS_PN = "1";
"B":   PN = "2"  !CDS_PN = "2";
BODY = "Q_RES","I44": LOCATION = "R1434" #&CDS_LOCATION = "R1434" &SEC = "1" #&CDS_SEC = "1";
"A":   PN = "1"  !CDS_PN = "1";
"B":   PN = "2"  !CDS_PN = "2";
BODY = "Q_RES","I46": LOCATION = "R4674" #&CDS_LOCATION = "R4674" &SEC = "1" #&CDS_SEC = "1";
"A":   PN = "1"  !CDS_PN = "1";
"B":   PN = "2"  !CDS_PN = "2";
DRAWING = "@s9s_mb_2u_lib.s9s_mb_2u(sch_1):page173";
BODY = "Q_RES","I1": LOCATION = "R495" #&CDS_LOCATION = "R495" &SEC = "1" #&CDS_SEC = "1";
"A":   PN = "1"  !CDS_PN = "1";
"B":   PN = "2"  !CDS_PN = "2";
BODY = "Q_CAP_DIFFBUS","I60": LOCATION = "C1105" #&CDS_LOCATION = "C1105" &SEC = "1" #&CDS_SEC = "1";
"1":   PN = "1"  !CDS_PN = "1";
"2":   PN = "2"  !CDS_PN = "2";
BODY = "Q_CAP_DIFFBUS","I61": LOCATION = "C1104" #&CDS_LOCATION = "C1104" &SEC = "1" #&CDS_SEC = "1";
"1":   PN = "1"  !CDS_PN = "1";
"2":   PN = "2"  !CDS_PN = "2";
BODY = "Q_CAP_DIFFBUS","I62": LOCATION = "C1103" #&CDS_LOCATION = "C1103" &SEC = "1" #&CDS_SEC = "1";
"1":   PN = "1"  !CDS_PN = "1";
"2":   PN = "2"  !CDS_PN = "2";
BODY = "Q_CAP_DIFFBUS","I63": LOCATION = "C1102" #&CDS_LOCATION = "C1102" &SEC = "1" #&CDS_SEC = "1";
"1":   PN = "1"  !CDS_PN = "1";
"2":   PN = "2"  !CDS_PN = "2";
BODY = "Q_CAP_DIFFBUS","I64": LOCATION = "C1100" #&CDS_LOCATION = "C1100" &SEC = "1" #&CDS_SEC = "1";
"1":   PN = "1"  !CDS_PN = "1";
"2":   PN = "2"  !CDS_PN = "2";
BODY = "Q_CAP_DIFFBUS","I65": LOCATION = "C1101" #&CDS_LOCATION = "C1101" &SEC = "1" #&CDS_SEC = "1";
"1":   PN = "1"  !CDS_PN = "1";
"2":   PN = "2"  !CDS_PN = "2";
BODY = "Q_CAP_DIFFBUS","I66": LOCATION = "C1099" #&CDS_LOCATION = "C1099" &SEC = "1" #&CDS_SEC = "1";
"1":   PN = "1"  !CDS_PN = "1";
"2":   PN = "2"  !CDS_PN = "2";
BODY = "Q_CAP_DIFFBUS","I67": LOCATION = "C1098" #&CDS_LOCATION = "C1098" &SEC = "1" #&CDS_SEC = "1";
"1":   PN = "1"  !CDS_PN = "1";
"2":   PN = "2"  !CDS_PN = "2";
BODY = "Q_CAP_DIFFBUS","I68": LOCATION = "C1996" #&CDS_LOCATION = "C1996" &SEC = "1" #&CDS_SEC = "1";
"1":   PN = "1"  !CDS_PN = "1";
"2":   PN = "2"  !CDS_PN = "2";
BODY = "Q_CAP_DIFFBUS","I69": LOCATION = "C1995" #&CDS_LOCATION = "C1995" &SEC = "1" #&CDS_SEC = "1";
"1":   PN = "1"  !CDS_PN = "1";
"2":   PN = "2"  !CDS_PN = "2";
BODY = "Q_CAP_DIFFBUS","I70": LOCATION = "C1994" #&CDS_LOCATION = "C1994" &SEC = "1" #&CDS_SEC = "1";
"1":   PN = "1"  !CDS_PN = "1";
"2":   PN = "2"  !CDS_PN = "2";
BODY = "Q_CAP_DIFFBUS","I71": LOCATION = "C1993" #&CDS_LOCATION = "C1993" &SEC = "1" #&CDS_SEC = "1";
"1":   PN = "1"  !CDS_PN = "1";
"2":   PN = "2"  !CDS_PN = "2";
BODY = "Q_CAP_DIFFBUS","I72": LOCATION = "C1992" #&CDS_LOCATION = "C1992" &SEC = "1" #&CDS_SEC = "1";
"1":   PN = "1"  !CDS_PN = "1";
"2":   PN = "2"  !CDS_PN = "2";
BODY = "Q_CAP_DIFFBUS","I73": LOCATION = "C1991" #&CDS_LOCATION = "C1991" &SEC = "1" #&CDS_SEC = "1";
"1":   PN = "1"  !CDS_PN = "1";
"2":   PN = "2"  !CDS_PN = "2";
BODY = "Q_CAP_DIFFBUS","I74": LOCATION = "C1990" #&CDS_LOCATION = "C1990" &SEC = "1" #&CDS_SEC = "1";
"1":   PN = "1"  !CDS_PN = "1";
"2":   PN = "2"  !CDS_PN = "2";
BODY = "Q_CAP_DIFFBUS","I75": LOCATION = "C1989" #&CDS_LOCATION = "C1989" &SEC = "1" #&CDS_SEC = "1";
"1":   PN = "1"  !CDS_PN = "1";
"2":   PN = "2"  !CDS_PN = "2";
BODY = "Q_CAP_DIFFBUS","I76": LOCATION = "C2078" #&CDS_LOCATION = "C2078" &SEC = "1" #&CDS_SEC = "1";
"1":   PN = "1"  !CDS_PN = "1";
"2":   PN = "2"  !CDS_PN = "2";
BODY = "Q_CAP_DIFFBUS","I77": LOCATION = "C2077" #&CDS_LOCATION = "C2077" &SEC = "1" #&CDS_SEC = "1";
"1":   PN = "1"  !CDS_PN = "1";
"2":   PN = "2"  !CDS_PN = "2";
BODY = "Q_CAP","I78": #LOCATION = "C1097" !CDS_LOCATION = "C1097" &SEC = "1" #&CDS_SEC = "1";
"A":   PN = "1"  !CDS_PN = "1";
"B":   PN = "2"  !CDS_PN = "2";
BODY = "Q_CAP_DIFFBUS","I79": LOCATION = "C2076" #&CDS_LOCATION = "C2076" &SEC = "1" #&CDS_SEC = "1";
"1":   PN = "1"  !CDS_PN = "1";
"2":   PN = "2"  !CDS_PN = "2";
BODY = "Q_CAP","I80": LOCATION = "C1096" #&CDS_LOCATION = "C1096" &SEC = "1" #&CDS_SEC = "1";
"A":   PN = "1"  !CDS_PN = "1";
"B":   PN = "2"  !CDS_PN = "2";
BODY = "Q_CAP_DIFFBUS","I81": LOCATION = "C2075" #&CDS_LOCATION = "C2075" &SEC = "1" #&CDS_SEC = "1";
"1":   PN = "1"  !CDS_PN = "1";
"2":   PN = "2"  !CDS_PN = "2";
BODY = "Q_CAP_DIFFBUS","I82": LOCATION = "C2074" #&CDS_LOCATION = "C2074" &SEC = "1" #&CDS_SEC = "1";
"1":   PN = "1"  !CDS_PN = "1";
"2":   PN = "2"  !CDS_PN = "2";
BODY = "Q_CAP_DIFFBUS","I83": LOCATION = "C2073" #&CDS_LOCATION = "C2073" &SEC = "1" #&CDS_SEC = "1";
"1":   PN = "1"  !CDS_PN = "1";
"2":   PN = "2"  !CDS_PN = "2";
BODY = "EMMITSBURG_REV0P9","I110": LOCATION = "U4" #&CDS_LOCATION = "U4" &SEC = "3" #&CDS_SEC = "3";
"DMI_0_RXN":   PN = "A30"  !CDS_PN = "A30";
"DMI_0_RXP":   PN = "C30"  !CDS_PN = "C30";
"DMI_0_TXN":   PN = "K28"  !CDS_PN = "K28";
"DMI_0_TXP":   PN = "H28"  !CDS_PN = "H28";
"DMI_1_RXN":   PN = "B31"  !CDS_PN = "B31";
"DMI_1_RXP":   PN = "D31"  !CDS_PN = "D31";
"DMI_1_TXN":   PN = "G29"  !CDS_PN = "G29";
"DMI_1_TXP":   PN = "F28"  !CDS_PN = "F28";
"DMI_2_RXN":   PN = "A32"  !CDS_PN = "A32";
"DMI_2_RXP":   PN = "C32"  !CDS_PN = "C32";
"DMI_2_TXN":   PN = "J29"  !CDS_PN = "J29";
"DMI_2_TXP":   PN = "H31"  !CDS_PN = "H31";
"DMI_3_RXN":   PN = "B33"  !CDS_PN = "B33";
"DMI_3_RXP":   PN = "D33"  !CDS_PN = "D33";
"DMI_3_TXN":   PN = "L32"  !CDS_PN = "L32";
"DMI_3_TXP":   PN = "K31"  !CDS_PN = "K31";
"DMI_4_SATA_19_PCIE3_19_RXN":   PN = "A34"  !CDS_PN = "A34";
"DMI_4_SATA_19_PCIE3_19_RXP":   PN = "C34"  !CDS_PN = "C34";
"DMI_4_SATA_19_PCIE3_19_TXN":   PN = "J32"  !CDS_PN = "J32";
"DMI_4_SATA_19_PCIE3_19_TXP":   PN = "G32"  !CDS_PN = "G32";
"DMI_5_SATA_18_PCIE3_18_RXN":   PN = "B35"  !CDS_PN = "B35";
"DMI_5_SATA_18_PCIE3_18_RXP":   PN = "D35"  !CDS_PN = "D35";
"DMI_5_SATA_18_PCIE3_18_TXN":   PN = "G36"  !CDS_PN = "G36";
"DMI_5_SATA_18_PCIE3_18_TXP":   PN = "H34"  !CDS_PN = "H34";
"DMI_6_SATA_17_PCIE3_17_RXN":   PN = "A36"  !CDS_PN = "A36";
"DMI_6_SATA_17_PCIE3_17_RXP":   PN = "C36"  !CDS_PN = "C36";
"DMI_6_SATA_17_PCIE3_17_TXN":   PN = "K37"  !CDS_PN = "K37";
"DMI_6_SATA_17_PCIE3_17_TXP":   PN = "J36"  !CDS_PN = "J36";
"DMI_7_SATA_16_PCIE3_16_RXN":   PN = "B37"  !CDS_PN = "B37";
"DMI_7_SATA_16_PCIE3_16_RXP":   PN = "D37"  !CDS_PN = "D37";
"DMI_7_SATA_16_PCIE3_16_TXN":   PN = "F37"  !CDS_PN = "F37";
"DMI_7_SATA_16_PCIE3_16_TXP":   PN = "H37"  !CDS_PN = "H37";
"PHY_PCIE3_RCOMPN":   PN = "AP31"  !CDS_PN = "AP31";
"PHY_PCIE3_RCOMPP":   PN = "AR29"  !CDS_PN = "AR29";
"RSVD_C40":   PN = "C40"  !CDS_PN = "C40";
"RSVD_D39":   PN = "D39"  !CDS_PN = "D39";
"RSVD_N40":   PN = "N40"  !CDS_PN = "N40";
"RSVD_N42":   PN = "N42"  !CDS_PN = "N42";
"SATA_0_PCIE3_0_USB3_0_RXN":   PN = "AE41"  !CDS_PN = "AE41";
"SATA_0_PCIE3_0_USB3_0_RXP":   PN = "AE43"  !CDS_PN = "AE43";
"SATA_0_PCIE3_0_USB3_0_TXN":   PN = "AL32"  !CDS_PN = "AL32";
"SATA_0_PCIE3_0_USB3_0_TXP":   PN = "AK31"  !CDS_PN = "AK31";
"SATA_1_PCIE3_1_USB3_1_RXN":   PN = "AD40"  !CDS_PN = "AD40";
"SATA_1_PCIE3_1_USB3_1_RXP":   PN = "AD42"  !CDS_PN = "AD42";
"SATA_1_PCIE3_1_USB3_1_TXN":   PN = "AN36"  !CDS_PN = "AN36";
"SATA_1_PCIE3_1_USB3_1_TXP":   PN = "AP34"  !CDS_PN = "AP34";
"SATA_2_PCIE3_2_USB3_2_RXN":   PN = "AC41"  !CDS_PN = "AC41";
"SATA_2_PCIE3_2_USB3_2_RXP":   PN = "AC43"  !CDS_PN = "AC43";
"SATA_2_PCIE3_2_USB3_2_TXN":   PN = "AR36"  !CDS_PN = "AR36";
"SATA_2_PCIE3_2_USB3_2_TXP":   PN = "AT37"  !CDS_PN = "AT37";
"SATA_3_PCIE3_3_USB3_3_RXN":   PN = "AB40"  !CDS_PN = "AB40";
"SATA_3_PCIE3_3_USB3_3_RXP":   PN = "AB42"  !CDS_PN = "AB42";
"SATA_3_PCIE3_3_USB3_3_TXN":   PN = "AK34"  !CDS_PN = "AK34";
"SATA_3_PCIE3_3_USB3_3_TXP":   PN = "AM34"  !CDS_PN = "AM34";
"SATA_4_PCIE3_4_USB3_4_RXN":   PN = "AA41"  !CDS_PN = "AA41";
"SATA_4_PCIE3_4_USB3_4_RXP":   PN = "AA43"  !CDS_PN = "AA43";
"SATA_4_PCIE3_4_USB3_4_TXN":   PN = "AL36"  !CDS_PN = "AL36";
"SATA_4_PCIE3_4_USB3_4_TXP":   PN = "AM37"  !CDS_PN = "AM37";
"SATA_5_PCIE3_5_USB3_5_RXN":   PN = "Y40"  !CDS_PN = "Y40";
"SATA_5_PCIE3_5_USB3_5_RXP":   PN = "Y42"  !CDS_PN = "Y42";
"SATA_5_PCIE3_5_USB3_5_TXN":   PN = "AH34"  !CDS_PN = "AH34";
"SATA_5_PCIE3_5_USB3_5_TXP":   PN = "AJ32"  !CDS_PN = "AJ32";
"SATA_6_PCIE3_6_USB3_6_RXN":   PN = "W41"  !CDS_PN = "W41";
"SATA_6_PCIE3_6_USB3_6_RXP":   PN = "W43"  !CDS_PN = "W43";
"SATA_6_PCIE3_6_USB3_6_TXN":   PN = "AF37"  !CDS_PN = "AF37";
"SATA_6_PCIE3_6_USB3_6_TXP":   PN = "AH37"  !CDS_PN = "AH37";
"SATA_7_PCIE3_7_USB3_7_RXN":   PN = "V40"  !CDS_PN = "V40";
"SATA_7_PCIE3_7_USB3_7_RXP":   PN = "V42"  !CDS_PN = "V42";
"SATA_7_PCIE3_7_USB3_7_TXN":   PN = "AF34"  !CDS_PN = "AF34";
"SATA_7_PCIE3_7_USB3_7_TXP":   PN = "AG36"  !CDS_PN = "AG36";
"SATA_8_PCIE3_8_USB3_8_RXN":   PN = "U41"  !CDS_PN = "U41";
"SATA_8_PCIE3_8_USB3_8_RXP":   PN = "U43"  !CDS_PN = "U43";
"SATA_8_PCIE3_8_USB3_8_TXN":   PN = "AE36"  !CDS_PN = "AE36";
"SATA_8_PCIE3_8_USB3_8_TXP":   PN = "AD37"  !CDS_PN = "AD37";
"SATA_9_PCIE3_9_USB3_9_RXN":   PN = "R40"  !CDS_PN = "R40";
"SATA_9_PCIE3_9_USB3_9_RXP":   PN = "R42"  !CDS_PN = "R42";
"SATA_9_PCIE3_9_USB3_9_TXN":   PN = "AE32"  !CDS_PN = "AE32";
"SATA_9_PCIE3_9_USB3_9_TXP":   PN = "AG32"  !CDS_PN = "AG32";
"SATA_10_PCIE3_10_GBE_0_RXN":   PN = "M41"  !CDS_PN = "M41";
"SATA_10_PCIE3_10_GBE_0_RXP":   PN = "M43"  !CDS_PN = "M43";
"SATA_10_PCIE3_10_GBE_0_TXN":   PN = "W36"  !CDS_PN = "W36";
"SATA_10_PCIE3_10_GBE_0_TXP":   PN = "Y37"  !CDS_PN = "Y37";
"SATA_11_PCIE3_11_RXN":   PN = "L40"  !CDS_PN = "L40";
"SATA_11_PCIE3_11_RXP":   PN = "L42"  !CDS_PN = "L42";
"SATA_11_PCIE3_11_TXN":   PN = "T37"  !CDS_PN = "T37";
"SATA_11_PCIE3_11_TXP":   PN = "V37"  !CDS_PN = "V37";
"SATA_12_PCIE3_12_GBE_1_RXN":   PN = "K41"  !CDS_PN = "K41";
"SATA_12_PCIE3_12_GBE_1_RXP":   PN = "K43"  !CDS_PN = "K43";
"SATA_12_PCIE3_12_GBE_1_TXN":   PN = "V34"  !CDS_PN = "V34";
"SATA_12_PCIE3_12_GBE_1_TXP":   PN = "U36"  !CDS_PN = "U36";
"SATA_13_PCIE3_13_RXN":   PN = "J40"  !CDS_PN = "J40";
"SATA_13_PCIE3_13_RXP":   PN = "J42"  !CDS_PN = "J42";
"SATA_13_PCIE3_13_TXN":   PN = "U32"  !CDS_PN = "U32";
"SATA_13_PCIE3_13_TXP":   PN = "W32"  !CDS_PN = "W32";
"SATA_14_PCIE3_14_GBE_2_RXN":   PN = "H41"  !CDS_PN = "H41";
"SATA_14_PCIE3_14_GBE_2_RXP":   PN = "H43"  !CDS_PN = "H43";
"SATA_14_PCIE3_14_GBE_2_TXN":   PN = "R32"  !CDS_PN = "R32";
"SATA_14_PCIE3_14_GBE_2_TXP":   PN = "T34"  !CDS_PN = "T34";
"SATA_15_PCIE3_15_RXN":   PN = "G40"  !CDS_PN = "G40";
"SATA_15_PCIE3_15_RXP":   PN = "G42"  !CDS_PN = "G42";
"SATA_15_PCIE3_15_TXN":   PN = "P34"  !CDS_PN = "P34";
"SATA_15_PCIE3_15_TXP":   PN = "N36"  !CDS_PN = "N36";
DRAWING = "@s9s_mb_2u_lib.s9s_mb_2u(sch_1):page329";
BODY = "Q_CAP","I1": LOCATION = "C2379" #&CDS_LOCATION = "C2379" &SEC = "1" #&CDS_SEC = "1";
"A":   PN = "1"  !CDS_PN = "1";
"B":   PN = "2"  !CDS_PN = "2";
BODY = "Q_RES","I2": LOCATION = "R4775" #&CDS_LOCATION = "R4775" &SEC = "1" #&CDS_SEC = "1";
"A":   PN = "1"  !CDS_PN = "1";
"B":   PN = "2"  !CDS_PN = "2";
BODY = "LM4040AIM3X25NOPB","I3": LOCATION = "U337" #&CDS_LOCATION = "U337" &SEC = "1" #&CDS_SEC = "1";
"1+":   PN = "1"  !CDS_PN = "1";
"2-":   PN = "2"  !CDS_PN = "2";
"3":   PN = "3"  !CDS_PN = "3";
BODY = "Q_RES","I6": LOCATION = "R4784" #&CDS_LOCATION = "R4784" &SEC = "1" #&CDS_SEC = "1";
"A":   PN = "1"  !CDS_PN = "1";
"B":   PN = "2"  !CDS_PN = "2";
BODY = "Q_RES","I7": LOCATION = "R4782" #&CDS_LOCATION = "R4782" &SEC = "1" #&CDS_SEC = "1";
"A":   PN = "1"  !CDS_PN = "1";
"B":   PN = "2"  !CDS_PN = "2";
BODY = "Q_RES","I9": LOCATION = "R4778" #&CDS_LOCATION = "R4778" &SEC = "1" #&CDS_SEC = "1";
"A":   PN = "1"  !CDS_PN = "1";
"B":   PN = "2"  !CDS_PN = "2";
BODY = "Q_CAP","I11": LOCATION = "C2383" #&CDS_LOCATION = "C2383" &SEC = "1" #&CDS_SEC = "1";
"A":   PN = "1"  !CDS_PN = "1";
"B":   PN = "2"  !CDS_PN = "2";
BODY = "AP331AWG7","I12": LOCATION = "U339" #&CDS_LOCATION = "U339" &SEC = "1" #&CDS_SEC = "1";
"GND":   PN = "2"  !CDS_PN = "2";
"IN+":   PN = "3"  !CDS_PN = "3";
"IN-":   PN = "1"  !CDS_PN = "1";
"OUTPUT":   PN = "4"  !CDS_PN = "4";
"VCC":   PN = "5"  !CDS_PN = "5";
BODY = "Q_CAP","I14": LOCATION = "C2381" #&CDS_LOCATION = "C2381" &SEC = "1" #&CDS_SEC = "1";
"A":   PN = "1"  !CDS_PN = "1";
"B":   PN = "2"  !CDS_PN = "2";
BODY = "Q_RES","I17": LOCATION = "R4774" #&CDS_LOCATION = "R4774" &SEC = "1" #&CDS_SEC = "1";
"A":   PN = "1"  !CDS_PN = "1";
"B":   PN = "2"  !CDS_PN = "2";
BODY = "Q_RES","I21": LOCATION = "R4772" #&CDS_LOCATION = "R4772" &SEC = "1" #&CDS_SEC = "1";
"A":   PN = "1"  !CDS_PN = "1";
"B":   PN = "2"  !CDS_PN = "2";
BODY = "AP331AWG7","I23": LOCATION = "U340" #&CDS_LOCATION = "U340" &SEC = "1" #&CDS_SEC = "1";
"GND":   PN = "2"  !CDS_PN = "2";
"IN+":   PN = "3"  !CDS_PN = "3";
"IN-":   PN = "1"  !CDS_PN = "1";
"OUTPUT":   PN = "4"  !CDS_PN = "4";
"VCC":   PN = "5"  !CDS_PN = "5";
BODY = "Q_RES","I25": LOCATION = "R4785" #&CDS_LOCATION = "R4785" &SEC = "1" #&CDS_SEC = "1";
"A":   PN = "1"  !CDS_PN = "1";
"B":   PN = "2"  !CDS_PN = "2";
BODY = "Q_RES","I27": LOCATION = "R4783" #&CDS_LOCATION = "R4783" &SEC = "1" #&CDS_SEC = "1";
"A":   PN = "1"  !CDS_PN = "1";
"B":   PN = "2"  !CDS_PN = "2";
BODY = "Q_CAP","I29": LOCATION = "C2384" #&CDS_LOCATION = "C2384" &SEC = "1" #&CDS_SEC = "1";
"A":   PN = "1"  !CDS_PN = "1";
"B":   PN = "2"  !CDS_PN = "2";
BODY = "Q_RES","I31": LOCATION = "R4779" #&CDS_LOCATION = "R4779" &SEC = "1" #&CDS_SEC = "1";
"A":   PN = "1"  !CDS_PN = "1";
"B":   PN = "2"  !CDS_PN = "2";
BODY = "Q_CAP","I33": LOCATION = "C2382" #&CDS_LOCATION = "C2382" &SEC = "1" #&CDS_SEC = "1";
"A":   PN = "1"  !CDS_PN = "1";
"B":   PN = "2"  !CDS_PN = "2";
BODY = "Q_CAP","I35": LOCATION = "C2380" #&CDS_LOCATION = "C2380" &SEC = "1" #&CDS_SEC = "1";
"A":   PN = "1"  !CDS_PN = "1";
"B":   PN = "2"  !CDS_PN = "2";
BODY = "Q_RES","I38": LOCATION = "R4776" #&CDS_LOCATION = "R4776" &SEC = "1" #&CDS_SEC = "1";
"A":   PN = "1"  !CDS_PN = "1";
"B":   PN = "2"  !CDS_PN = "2";
BODY = "Q_RES","I39": LOCATION = "R4777" #&CDS_LOCATION = "R4777" &SEC = "1" #&CDS_SEC = "1";
"A":   PN = "1"  !CDS_PN = "1";
"B":   PN = "2"  !CDS_PN = "2";
BODY = "Q_RES","I42": LOCATION = "R4773" #&CDS_LOCATION = "R4773" &SEC = "1" #&CDS_SEC = "1";
"A":   PN = "1"  !CDS_PN = "1";
"B":   PN = "2"  !CDS_PN = "2";
BODY = "LM4040AIM3X25NOPB","I43": LOCATION = "U338" #&CDS_LOCATION = "U338" &SEC = "1" #&CDS_SEC = "1";
"1+":   PN = "1"  !CDS_PN = "1";
"2-":   PN = "2"  !CDS_PN = "2";
"3":   PN = "3"  !CDS_PN = "3";
BODY = "AP331AWG7","I45": LOCATION = "U342" #&CDS_LOCATION = "U342" &SEC = "1" #&CDS_SEC = "1";
"GND":   PN = "2"  !CDS_PN = "2";
"IN+":   PN = "3"  !CDS_PN = "3";
"IN-":   PN = "1"  !CDS_PN = "1";
"OUTPUT":   PN = "4"  !CDS_PN = "4";
"VCC":   PN = "5"  !CDS_PN = "5";
BODY = "Q_RES","I46": LOCATION = "R4787" #&CDS_LOCATION = "R4787" &SEC = "1" #&CDS_SEC = "1";
"A":   PN = "1"  !CDS_PN = "1";
"B":   PN = "2"  !CDS_PN = "2";
BODY = "Q_RES","I49": LOCATION = "R4789" #&CDS_LOCATION = "R4789" &SEC = "1" #&CDS_SEC = "1";
"A":   PN = "1"  !CDS_PN = "1";
"B":   PN = "2"  !CDS_PN = "2";
BODY = "Q_RES","I50": LOCATION = "R4788" #&CDS_LOCATION = "R4788" &SEC = "1" #&CDS_SEC = "1";
"A":   PN = "1"  !CDS_PN = "1";
"B":   PN = "2"  !CDS_PN = "2";
BODY = "Q_CAP","I51": LOCATION = "C2387" #&CDS_LOCATION = "C2387" &SEC = "1" #&CDS_SEC = "1";
"A":   PN = "1"  !CDS_PN = "1";
"B":   PN = "2"  !CDS_PN = "2";
BODY = "Q_CAP","I55": LOCATION = "C2386" #&CDS_LOCATION = "C2386" &SEC = "1" #&CDS_SEC = "1";
"A":   PN = "1"  !CDS_PN = "1";
"B":   PN = "2"  !CDS_PN = "2";
BODY = "Q_CAP","I57": LOCATION = "C2385" #&CDS_LOCATION = "C2385" &SEC = "1" #&CDS_SEC = "1";
"A":   PN = "1"  !CDS_PN = "1";
"B":   PN = "2"  !CDS_PN = "2";
BODY = "LM4040AIM3X25NOPB","I63": LOCATION = "U341" #&CDS_LOCATION = "U341" &SEC = "1" #&CDS_SEC = "1";
"1+":   PN = "1"  !CDS_PN = "1";
"2-":   PN = "2"  !CDS_PN = "2";
"3":   PN = "3"  !CDS_PN = "3";
BODY = "Q_RES","I65": LOCATION = "R4786" #&CDS_LOCATION = "R4786" &SEC = "1" #&CDS_SEC = "1";
"A":   PN = "1"  !CDS_PN = "1";
"B":   PN = "2"  !CDS_PN = "2";
BODY = "Q_RES","I67": LOCATION = "R4790" #&CDS_LOCATION = "R4790" &SEC = "1" #&CDS_SEC = "1";
"A":   PN = "1"  !CDS_PN = "1";
"B":   PN = "2"  !CDS_PN = "2";
BODY = "Q_RES","I68": LOCATION = "R4791" #&CDS_LOCATION = "R4791" &SEC = "1" #&CDS_SEC = "1";
"A":   PN = "1"  !CDS_PN = "1";
"B":   PN = "2"  !CDS_PN = "2";
DRAWING = "@s9s_mb_2u_lib.s9s_mb_2u(sch_1):page245";
BODY = "Q_DIODE","I71": LOCATION = "D145" #&CDS_LOCATION = "D145" &SEC = "1" #&CDS_SEC = "1";
"1":   PN = "1"  !CDS_PN = "1";
"2":   PN = "2"  !CDS_PN = "2";
BODY = "Q_RES","I72": #LOCATION = "R1571" !CDS_LOCATION = "R1571" &SEC = "1" #&CDS_SEC = "1";
"A":   PN = "1"  !CDS_PN = "1";
"B":   PN = "2"  !CDS_PN = "2";
BODY = "Q_CAP","I73": #LOCATION = "C2541" !CDS_LOCATION = "C2541" &SEC = "1" #&CDS_SEC = "1";
"A":   PN = "1"  !CDS_PN = "1";
"B":   PN = "2"  !CDS_PN = "2";
BODY = "Q_RES","I76": LOCATION = "R3118" #&CDS_LOCATION = "R3118" &SEC = "1" #&CDS_SEC = "1";
"A":   PN = "1"  !CDS_PN = "1";
"B":   PN = "2"  !CDS_PN = "2";
BODY = "Q_RES","I78": LOCATION = "R3117" #&CDS_LOCATION = "R3117" &SEC = "1" #&CDS_SEC = "1";
"A":   PN = "1"  !CDS_PN = "1";
"B":   PN = "2"  !CDS_PN = "2";
BODY = "Q_RES","I84": #LOCATION = "PR832" !CDS_LOCATION = "PR832" &SEC = "1" #&CDS_SEC = "1";
"A":   PN = "1"  !CDS_PN = "1";
"B":   PN = "2"  !CDS_PN = "2";
BODY = "Q_CAP","I86": #LOCATION = "PC581" !CDS_LOCATION = "PC581" &SEC = "1" #&CDS_SEC = "1";
"A":   PN = "1"  !CDS_PN = "1";
"B":   PN = "2"  !CDS_PN = "2";
BODY = "Q_RES","I89": #LOCATION = "PR833" !CDS_LOCATION = "PR833" &SEC = "1" #&CDS_SEC = "1";
"A":   PN = "1"  !CDS_PN = "1";
"B":   PN = "2"  !CDS_PN = "2";
BODY = "Q_RES","I91": #LOCATION = "PR834" !CDS_LOCATION = "PR834" &SEC = "1" #&CDS_SEC = "1";
"A":   PN = "1"  !CDS_PN = "1";
"B":   PN = "2"  !CDS_PN = "2";
BODY = "Q_CAP","I93": #LOCATION = "PC591" !CDS_LOCATION = "PC591" &SEC = "1" #&CDS_SEC = "1";
"A":   PN = "1"  !CDS_PN = "1";
"B":   PN = "2"  !CDS_PN = "2";
BODY = "Q_RES","I94": #LOCATION = "PR389" !CDS_LOCATION = "PR389" &SEC = "1" #&CDS_SEC = "1";
"A":   PN = "1"  !CDS_PN = "1";
"B":   PN = "2"  !CDS_PN = "2";
BODY = "IR3889MTRPBF","I95": #LOCATION = "PU9" !CDS_LOCATION = "PU9" #SEC = "1" !CDS_SEC = "1";
"AGND":   PN = "32"  !CDS_PN = "32";
"BOOT":   PN = "26"  !CDS_PN = "26";
"EN":   PN = "27"  !CDS_PN = "27";
"FB":   PN = "30"  !CDS_PN = "30";
"GATEL1":   PN = "6"  !CDS_PN = "6";
"GATEL2":   PN = "37"  !CDS_PN = "37";
"ILIM":   PN = "1"  !CDS_PN = "1";
"NC1":   PN = "28"  !CDS_PN = "28";
"NC2":   PN = "33"  !CDS_PN = "33";
"NC3":   PN = "34"  !CDS_PN = "34";
"NC4":   PN = "35"  !CDS_PN = "35";
"PGND":   PN = "7_10-19"  !CDS_PN = "7_10-19";
"PGOOD":   PN = "2"  !CDS_PN = "2";
"PHASE":   PN = "25"  !CDS_PN = "25";
"PVIN":   PN = "20_24"  !CDS_PN = "20_24";
"SS||LATCH":   PN = "29"  !CDS_PN = "29";
"SW":   PN = "11_18"  !CDS_PN = "11_18";
"TON||MODE":   PN = "36"  !CDS_PN = "36";
"VCC||LDO":   PN = "4"  !CDS_PN = "4";
"VDRV":   PN = "5"  !CDS_PN = "5";
"VIN":   PN = "3"  !CDS_PN = "3";
"VSENM":   PN = "31"  !CDS_PN = "31";
BODY = "Q_CAP","I97": #LOCATION = "PC1649" !CDS_LOCATION = "PC1649" &SEC = "1" #&CDS_SEC = "1";
"A":   PN = "1"  !CDS_PN = "1";
"B":   PN = "2"  !CDS_PN = "2";
BODY = "Q_INDUCTOR","I98": #LOCATION = "PL45" !CDS_LOCATION = "PL45" &SEC = "1" #&CDS_SEC = "1";
"1":   PN = "1"  !CDS_PN = "1";
"2":   PN = "2"  !CDS_PN = "2";
BODY = "Q_CAP","I100": #LOCATION = "PC2260" !CDS_LOCATION = "PC2260" &SEC = "1" #&CDS_SEC = "1";
"A":   PN = "1"  !CDS_PN = "1";
"B":   PN = "2"  !CDS_PN = "2";
BODY = "Q_CAP","I101": #LOCATION = "PC2261" !CDS_LOCATION = "PC2261" &SEC = "1" #&CDS_SEC = "1";
"A":   PN = "1"  !CDS_PN = "1";
"B":   PN = "2"  !CDS_PN = "2";
BODY = "Q_CAPP","I103": #LOCATION = "PC3" !CDS_LOCATION = "PC3" &SEC = "1" #&CDS_SEC = "1";
"A":   PN = "1"  !CDS_PN = "1";
"B":   PN = "2"  !CDS_PN = "2";
BODY = "Q_CAPP","I104": #LOCATION = "PC566" !CDS_LOCATION = "PC566" &SEC = "1" #&CDS_SEC = "1";
"A":   PN = "1"  !CDS_PN = "1";
"B":   PN = "2"  !CDS_PN = "2";
BODY = "Q_CAP","I105": #LOCATION = "PC2262" !CDS_LOCATION = "PC2262" &SEC = "1" #&CDS_SEC = "1";
"A":   PN = "1"  !CDS_PN = "1";
"B":   PN = "2"  !CDS_PN = "2";
BODY = "Q_CAP","I106": #LOCATION = "PC567" !CDS_LOCATION = "PC567" &SEC = "1" #&CDS_SEC = "1";
"A":   PN = "1"  !CDS_PN = "1";
"B":   PN = "2"  !CDS_PN = "2";
BODY = "Q_CAP","I107": #LOCATION = "PC2263" !CDS_LOCATION = "PC2263" &SEC = "1" #&CDS_SEC = "1";
"A":   PN = "1"  !CDS_PN = "1";
"B":   PN = "2"  !CDS_PN = "2";
BODY = "Q_CAP","I108": #LOCATION = "PC2342" !CDS_LOCATION = "PC2342" &SEC = "1" #&CDS_SEC = "1";
"A":   PN = "1"  !CDS_PN = "1";
"B":   PN = "2"  !CDS_PN = "2";
BODY = "Q_CAP","I109": #LOCATION = "PC570" !CDS_LOCATION = "PC570" &SEC = "1" #&CDS_SEC = "1";
"A":   PN = "1"  !CDS_PN = "1";
"B":   PN = "2"  !CDS_PN = "2";
BODY = "Q_CAP","I110": #LOCATION = "PC571" !CDS_LOCATION = "PC571" &SEC = "1" #&CDS_SEC = "1";
"A":   PN = "1"  !CDS_PN = "1";
"B":   PN = "2"  !CDS_PN = "2";
BODY = "Q_CAP","I111": #LOCATION = "PC2343" !CDS_LOCATION = "PC2343" &SEC = "1" #&CDS_SEC = "1";
"A":   PN = "1"  !CDS_PN = "1";
"B":   PN = "2"  !CDS_PN = "2";
BODY = "Q_CAP","I112": #LOCATION = "PC2344" !CDS_LOCATION = "PC2344" &SEC = "1" #&CDS_SEC = "1";
"A":   PN = "1"  !CDS_PN = "1";
"B":   PN = "2"  !CDS_PN = "2";
BODY = "Q_CAP","I113": #LOCATION = "PC576" !CDS_LOCATION = "PC576" &SEC = "1" #&CDS_SEC = "1";
"A":   PN = "1"  !CDS_PN = "1";
"B":   PN = "2"  !CDS_PN = "2";
BODY = "Q_CAP","I114": #LOCATION = "PC71" !CDS_LOCATION = "PC71" &SEC = "1" #&CDS_SEC = "1";
"A":   PN = "1"  !CDS_PN = "1";
"B":   PN = "2"  !CDS_PN = "2";
BODY = "Q_CAP","I115": #LOCATION = "PC577" !CDS_LOCATION = "PC577" &SEC = "1" #&CDS_SEC = "1";
"A":   PN = "1"  !CDS_PN = "1";
"B":   PN = "2"  !CDS_PN = "2";
BODY = "Q_CAP","I118": #LOCATION = "PC8" !CDS_LOCATION = "PC8" &SEC = "1" #&CDS_SEC = "1";
"A":   PN = "1"  !CDS_PN = "1";
"B":   PN = "2"  !CDS_PN = "2";
BODY = "Q_RES","I121": #LOCATION = "PR836" !CDS_LOCATION = "PR836" &SEC = "1" #&CDS_SEC = "1";
"A":   PN = "1"  !CDS_PN = "1";
"B":   PN = "2"  !CDS_PN = "2";
BODY = "Q_CAP","I122": #LOCATION = "PC568" !CDS_LOCATION = "PC568" &SEC = "1" #&CDS_SEC = "1";
"A":   PN = "1"  !CDS_PN = "1";
"B":   PN = "2"  !CDS_PN = "2";
BODY = "Q_RES","I123": #LOCATION = "PR835" !CDS_LOCATION = "PR835" &SEC = "1" #&CDS_SEC = "1";
"A":   PN = "1"  !CDS_PN = "1";
"B":   PN = "2"  !CDS_PN = "2";
BODY = "Q_RES","I125": #LOCATION = "PR830" !CDS_LOCATION = "PR830" &SEC = "1" #&CDS_SEC = "1";
"A":   PN = "1"  !CDS_PN = "1";
"B":   PN = "2"  !CDS_PN = "2";
BODY = "Q_CAP","I127": #LOCATION = "PC569" !CDS_LOCATION = "PC569" &SEC = "1" #&CDS_SEC = "1";
"A":   PN = "1"  !CDS_PN = "1";
"B":   PN = "2"  !CDS_PN = "2";
BODY = "Q_RES","I128": #LOCATION = "PR831" !CDS_LOCATION = "PR831" &SEC = "1" #&CDS_SEC = "1";
"A":   PN = "1"  !CDS_PN = "1";
"B":   PN = "2"  !CDS_PN = "2";
BODY = "Q_INDUCTOR","I129": #LOCATION = "PL66" !CDS_LOCATION = "PL66" &SEC = "1" #&CDS_SEC = "1";
"1":   PN = "1"  !CDS_PN = "1";
"2":   PN = "2"  !CDS_PN = "2";
BODY = "Q_CAPP","I131": #LOCATION = "PC1866" !CDS_LOCATION = "PC1866" &SEC = "1" #&CDS_SEC = "1";
"A":   PN = "1"  !CDS_PN = "1";
"B":   PN = "2"  !CDS_PN = "2";
BODY = "Q_CAPP","I132": #LOCATION = "PC1867" !CDS_LOCATION = "PC1867" &SEC = "1" #&CDS_SEC = "1";
"A":   PN = "1"  !CDS_PN = "1";
"B":   PN = "2"  !CDS_PN = "2";
BODY = "Q_CAP","I133": #LOCATION = "PC1868" !CDS_LOCATION = "PC1868" &SEC = "1" #&CDS_SEC = "1";
"A":   PN = "1"  !CDS_PN = "1";
"B":   PN = "2"  !CDS_PN = "2";
BODY = "Q_CAP","I134": #LOCATION = "PC1599" !CDS_LOCATION = "PC1599" &SEC = "1" #&CDS_SEC = "1";
"A":   PN = "1"  !CDS_PN = "1";
"B":   PN = "2"  !CDS_PN = "2";
BODY = "Q_CAP","I136": #LOCATION = "PC1600" !CDS_LOCATION = "PC1600" &SEC = "1" #&CDS_SEC = "1";
"A":   PN = "1"  !CDS_PN = "1";
"B":   PN = "2"  !CDS_PN = "2";
BODY = "Q_CAP","I137": #LOCATION = "PC1869" !CDS_LOCATION = "PC1869" &SEC = "1" #&CDS_SEC = "1";
"A":   PN = "1"  !CDS_PN = "1";
"B":   PN = "2"  !CDS_PN = "2";
BODY = "Q_RES","I139": #LOCATION = "PR73" !CDS_LOCATION = "PR73" &SEC = "1" #&CDS_SEC = "1";
"A":   PN = "1"  !CDS_PN = "1";
"B":   PN = "2"  !CDS_PN = "2";
DRAWING = "@s9s_mb_2u_lib.s9s_mb_2u(sch_1):page121";
BODY = "Q_RES","I4": LOCATION = "R4396" #&CDS_LOCATION = "R4396" &SEC = "1" #&CDS_SEC = "1";
"A":   PN = "1"  !CDS_PN = "1";
"B":   PN = "2"  !CDS_PN = "2";
BODY = "Q_RES","I5": LOCATION = "R240" #&CDS_LOCATION = "R240" &SEC = "1" #&CDS_SEC = "1";
"A":   PN = "1"  !CDS_PN = "1";
"B":   PN = "2"  !CDS_PN = "2";
BODY = "Q_RES","I6": #LOCATION = "R238" !CDS_LOCATION = "R238" &SEC = "1" #&CDS_SEC = "1";
"A":   PN = "1"  !CDS_PN = "1";
"B":   PN = "2"  !CDS_PN = "2";
BODY = "Q_RES","I7": LOCATION = "R239" #&CDS_LOCATION = "R239" &SEC = "1" #&CDS_SEC = "1";
"A":   PN = "1"  !CDS_PN = "1";
"B":   PN = "2"  !CDS_PN = "2";
BODY = "BC847BPN","I8": #LOCATION = "Q139" !CDS_LOCATION = "Q139" &SEC = "2" #&CDS_SEC = "2";
"B2":   PN = "5"  !CDS_PN = "5";
"C2":   PN = "3"  !CDS_PN = "3";
"E2":   PN = "4"  !CDS_PN = "4";
BODY = "Q_RES","I10": LOCATION = "R4398" #&CDS_LOCATION = "R4398" &SEC = "1" #&CDS_SEC = "1";
"A":   PN = "1"  !CDS_PN = "1";
"B":   PN = "2"  !CDS_PN = "2";
BODY = "Q_RES","I13": LOCATION = "R4395" #&CDS_LOCATION = "R4395" &SEC = "1" #&CDS_SEC = "1";
"A":   PN = "1"  !CDS_PN = "1";
"B":   PN = "2"  !CDS_PN = "2";
BODY = "Q_RES","I15": #LOCATION = "R237" !CDS_LOCATION = "R237" &SEC = "1" #&CDS_SEC = "1";
"A":   PN = "1"  !CDS_PN = "1";
"B":   PN = "2"  !CDS_PN = "2";
BODY = "Q_RES","I16": LOCATION = "R4397" #&CDS_LOCATION = "R4397" &SEC = "1" #&CDS_SEC = "1";
"A":   PN = "1"  !CDS_PN = "1";
"B":   PN = "2"  !CDS_PN = "2";
BODY = "BC847BPN","I17": #LOCATION = "Q138" !CDS_LOCATION = "Q138" &SEC = "2" #&CDS_SEC = "2";
"B2":   PN = "5"  !CDS_PN = "5";
"C2":   PN = "3"  !CDS_PN = "3";
"E2":   PN = "4"  !CDS_PN = "4";
BODY = "Q_RES","I19": LOCATION = "R244" #&CDS_LOCATION = "R244" &SEC = "1" #&CDS_SEC = "1";
"A":   PN = "1"  !CDS_PN = "1";
"B":   PN = "2"  !CDS_PN = "2";
BODY = "BC847BPN","I21": #LOCATION = "Q139" !CDS_LOCATION = "Q139" &SEC = "1" #&CDS_SEC = "1";
"B1":   PN = "2"  !CDS_PN = "2";
"C1":   PN = "6"  !CDS_PN = "6";
"E1":   PN = "1"  !CDS_PN = "1";
BODY = "Q_RES","I23": LOCATION = "R243" #&CDS_LOCATION = "R243" &SEC = "1" #&CDS_SEC = "1";
"A":   PN = "1"  !CDS_PN = "1";
"B":   PN = "2"  !CDS_PN = "2";
BODY = "Q_RES","I26": #LOCATION = "R242" !CDS_LOCATION = "R242" &SEC = "1" #&CDS_SEC = "1";
"A":   PN = "1"  !CDS_PN = "1";
"B":   PN = "2"  !CDS_PN = "2";
BODY = "Q_RES","I29": LOCATION = "R4400" #&CDS_LOCATION = "R4400" &SEC = "1" #&CDS_SEC = "1";
"A":   PN = "1"  !CDS_PN = "1";
"B":   PN = "2"  !CDS_PN = "2";
BODY = "BC847BPN","I31": #LOCATION = "Q138" !CDS_LOCATION = "Q138" &SEC = "1" #&CDS_SEC = "1";
"B1":   PN = "2"  !CDS_PN = "2";
"C1":   PN = "6"  !CDS_PN = "6";
"E1":   PN = "1"  !CDS_PN = "1";
BODY = "Q_RES","I33": LOCATION = "R241" #&CDS_LOCATION = "R241" &SEC = "1" #&CDS_SEC = "1";
"A":   PN = "1"  !CDS_PN = "1";
"B":   PN = "2"  !CDS_PN = "2";
BODY = "Q_RES","I35": LOCATION = "R4399" #&CDS_LOCATION = "R4399" &SEC = "1" #&CDS_SEC = "1";
"A":   PN = "1"  !CDS_PN = "1";
"B":   PN = "2"  !CDS_PN = "2";
DRAWING = "@s9s_mb_2u_lib.s9s_mb_2u(sch_1):page122";
BODY = "Q_RES","I5": LOCATION = "R4402" #&CDS_LOCATION = "R4402" &SEC = "1" #&CDS_SEC = "1";
"A":   PN = "1"  !CDS_PN = "1";
"B":   PN = "2"  !CDS_PN = "2";
BODY = "Q_RES","I6": #LOCATION = "R204" !CDS_LOCATION = "R204" &SEC = "1" #&CDS_SEC = "1";
"A":   PN = "1"  !CDS_PN = "1";
"B":   PN = "2"  !CDS_PN = "2";
BODY = "Q_RES","I8": LOCATION = "R4401" #&CDS_LOCATION = "R4401" &SEC = "1" #&CDS_SEC = "1";
"A":   PN = "1"  !CDS_PN = "1";
"B":   PN = "2"  !CDS_PN = "2";
BODY = "Q_RES","I9": #LOCATION = "R203" !CDS_LOCATION = "R203" &SEC = "1" #&CDS_SEC = "1";
"A":   PN = "1"  !CDS_PN = "1";
"B":   PN = "2"  !CDS_PN = "2";
BODY = "BC847BPN","I10": #LOCATION = "Q142" !CDS_LOCATION = "Q142" &SEC = "2" #&CDS_SEC = "2";
"B2":   PN = "5"  !CDS_PN = "5";
"C2":   PN = "3"  !CDS_PN = "3";
"E2":   PN = "4"  !CDS_PN = "4";
BODY = "BC847BPN","I12": #LOCATION = "Q143" !CDS_LOCATION = "Q143" &SEC = "2" #&CDS_SEC = "2";
"B2":   PN = "5"  !CDS_PN = "5";
"C2":   PN = "3"  !CDS_PN = "3";
"E2":   PN = "4"  !CDS_PN = "4";
BODY = "Q_RES","I15": LOCATION = "R210" #&CDS_LOCATION = "R210" &SEC = "1" #&CDS_SEC = "1";
"A":   PN = "1"  !CDS_PN = "1";
"B":   PN = "2"  !CDS_PN = "2";
BODY = "Q_RES","I16": LOCATION = "R208" #&CDS_LOCATION = "R208" &SEC = "1" #&CDS_SEC = "1";
"A":   PN = "1"  !CDS_PN = "1";
"B":   PN = "2"  !CDS_PN = "2";
BODY = "BC847BPN","I17": #LOCATION = "Q142" !CDS_LOCATION = "Q142" &SEC = "1" #&CDS_SEC = "1";
"B1":   PN = "2"  !CDS_PN = "2";
"C1":   PN = "6"  !CDS_PN = "6";
"E1":   PN = "1"  !CDS_PN = "1";
BODY = "Q_RES","I18": LOCATION = "R4408" #&CDS_LOCATION = "R4408" &SEC = "1" #&CDS_SEC = "1";
"A":   PN = "1"  !CDS_PN = "1";
"B":   PN = "2"  !CDS_PN = "2";
BODY = "Q_RES","I20": LOCATION = "R4404" #&CDS_LOCATION = "R4404" &SEC = "1" #&CDS_SEC = "1";
"A":   PN = "1"  !CDS_PN = "1";
"B":   PN = "2"  !CDS_PN = "2";
BODY = "Q_RES","I21": LOCATION = "R4403" #&CDS_LOCATION = "R4403" &SEC = "1" #&CDS_SEC = "1";
"A":   PN = "1"  !CDS_PN = "1";
"B":   PN = "2"  !CDS_PN = "2";
BODY = "BC847BPN","I22": #LOCATION = "Q143" !CDS_LOCATION = "Q143" &SEC = "1" #&CDS_SEC = "1";
"B1":   PN = "2"  !CDS_PN = "2";
"C1":   PN = "6"  !CDS_PN = "6";
"E1":   PN = "1"  !CDS_PN = "1";
BODY = "Q_RES","I24": LOCATION = "R4406" #&CDS_LOCATION = "R4406" &SEC = "1" #&CDS_SEC = "1";
"A":   PN = "1"  !CDS_PN = "1";
"B":   PN = "2"  !CDS_PN = "2";
BODY = "Q_RES","I27": LOCATION = "R4405" #&CDS_LOCATION = "R4405" &SEC = "1" #&CDS_SEC = "1";
"A":   PN = "1"  !CDS_PN = "1";
"B":   PN = "2"  !CDS_PN = "2";
BODY = "Q_RES","I29": LOCATION = "R220" #&CDS_LOCATION = "R220" &SEC = "1" #&CDS_SEC = "1";
"A":   PN = "1"  !CDS_PN = "1";
"B":   PN = "2"  !CDS_PN = "2";
BODY = "Q_RES","I31": LOCATION = "R4407" #&CDS_LOCATION = "R4407" &SEC = "1" #&CDS_SEC = "1";
"A":   PN = "1"  !CDS_PN = "1";
"B":   PN = "2"  !CDS_PN = "2";
BODY = "Q_RES","I33": LOCATION = "R4294" #&CDS_LOCATION = "R4294" &SEC = "1" #&CDS_SEC = "1";
"A":   PN = "1"  !CDS_PN = "1";
"B":   PN = "2"  !CDS_PN = "2";
BODY = "Q_RES","I34": LOCATION = "R4293" #&CDS_LOCATION = "R4293" &SEC = "1" #&CDS_SEC = "1";
"A":   PN = "1"  !CDS_PN = "1";
"B":   PN = "2"  !CDS_PN = "2";
BODY = "Q_RES","I37": LOCATION = "R219" #&CDS_LOCATION = "R219" &SEC = "1" #&CDS_SEC = "1";
"A":   PN = "1"  !CDS_PN = "1";
"B":   PN = "2"  !CDS_PN = "2";
DRAWING = "@s9s_mb_2u_lib.s9s_mb_2u(sch_1):page233";
BODY = "Q_RES","I3": LOCATION = "R4769" #&CDS_LOCATION = "R4769" &SEC = "1" #&CDS_SEC = "1";
"A":   PN = "1"  !CDS_PN = "1";
"B":   PN = "2"  !CDS_PN = "2";
BODY = "Q_RES","I4": LOCATION = "R2950" #&CDS_LOCATION = "R2950" &SEC = "1" #&CDS_SEC = "1";
"A":   PN = "1"  !CDS_PN = "1";
"B":   PN = "2"  !CDS_PN = "2";
BODY = "Q_RES","I8": #LOCATION = "R3114" !CDS_LOCATION = "R3114" &SEC = "1" #&CDS_SEC = "1";
"A":   PN = "1"  !CDS_PN = "1";
"B":   PN = "2"  !CDS_PN = "2";
BODY = "Q_RES","I9": #LOCATION = "R3113" !CDS_LOCATION = "R3113" &SEC = "1" #&CDS_SEC = "1";
"A":   PN = "1"  !CDS_PN = "1";
"B":   PN = "2"  !CDS_PN = "2";
BODY = "Q_RES","I10": #LOCATION = "R2796" !CDS_LOCATION = "R2796" &SEC = "1" #&CDS_SEC = "1";
"A":   PN = "1"  !CDS_PN = "1";
"B":   PN = "2"  !CDS_PN = "2";
BODY = "CONN60_101062636003K02LF","I12": #LOCATION = "J45" !CDS_LOCATION = "J45" &SEC = "1" #&CDS_SEC = "1";
"A1":   PN = "A1"  !CDS_PN = "A1";
"A2":   PN = "A2"  !CDS_PN = "A2";
"A3":   PN = "A3"  !CDS_PN = "A3";
"B1":   PN = "B1"  !CDS_PN = "B1";
"B2":   PN = "B2"  !CDS_PN = "B2";
"B3":   PN = "B3"  !CDS_PN = "B3";
"C1":   PN = "C1"  !CDS_PN = "C1";
"C2":   PN = "C2"  !CDS_PN = "C2";
"C3":   PN = "C3"  !CDS_PN = "C3";
"D1":   PN = "D1"  !CDS_PN = "D1";
"D2":   PN = "D2"  !CDS_PN = "D2";
"D3":   PN = "D3"  !CDS_PN = "D3";
"P1_1":   PN = "P1_1"  !CDS_PN = "P1_1";
"P1_2":   PN = "P1_2"  !CDS_PN = "P1_2";
"P1_3":   PN = "P1_3"  !CDS_PN = "P1_3";
"P1_4":   PN = "P1_4"  !CDS_PN = "P1_4";
"P1_5":   PN = "P1_5"  !CDS_PN = "P1_5";
"P1_6":   PN = "P1_6"  !CDS_PN = "P1_6";
"P1_7":   PN = "P1_7"  !CDS_PN = "P1_7";
"P1_8":   PN = "P1_8"  !CDS_PN = "P1_8";
"P2_1":   PN = "P2_1"  !CDS_PN = "P2_1";
"P2_2":   PN = "P2_2"  !CDS_PN = "P2_2";
"P2_3":   PN = "P2_3"  !CDS_PN = "P2_3";
"P2_4":   PN = "P2_4"  !CDS_PN = "P2_4";
"P2_5":   PN = "P2_5"  !CDS_PN = "P2_5";
"P2_6":   PN = "P2_6"  !CDS_PN = "P2_6";
"P2_7":   PN = "P2_7"  !CDS_PN = "P2_7";
"P2_8":   PN = "P2_8"  !CDS_PN = "P2_8";
"P3_1":   PN = "P3_1"  !CDS_PN = "P3_1";
"P3_2":   PN = "P3_2"  !CDS_PN = "P3_2";
"P3_3":   PN = "P3_3"  !CDS_PN = "P3_3";
"P3_4":   PN = "P3_4"  !CDS_PN = "P3_4";
"P3_5":   PN = "P3_5"  !CDS_PN = "P3_5";
"P3_6":   PN = "P3_6"  !CDS_PN = "P3_6";
"P3_7":   PN = "P3_7"  !CDS_PN = "P3_7";
"P3_8":   PN = "P3_8"  !CDS_PN = "P3_8";
"P4_1":   PN = "P4_1"  !CDS_PN = "P4_1";
"P4_2":   PN = "P4_2"  !CDS_PN = "P4_2";
"P4_3":   PN = "P4_3"  !CDS_PN = "P4_3";
"P4_4":   PN = "P4_4"  !CDS_PN = "P4_4";
"P4_5":   PN = "P4_5"  !CDS_PN = "P4_5";
"P4_6":   PN = "P4_6"  !CDS_PN = "P4_6";
"P4_7":   PN = "P4_7"  !CDS_PN = "P4_7";
"P4_8":   PN = "P4_8"  !CDS_PN = "P4_8";
"P5_1":   PN = "P5_1"  !CDS_PN = "P5_1";
"P5_2":   PN = "P5_2"  !CDS_PN = "P5_2";
"P5_3":   PN = "P5_3"  !CDS_PN = "P5_3";
"P5_4":   PN = "P5_4"  !CDS_PN = "P5_4";
"P5_5":   PN = "P5_5"  !CDS_PN = "P5_5";
"P5_6":   PN = "P5_6"  !CDS_PN = "P5_6";
"P5_7":   PN = "P5_7"  !CDS_PN = "P5_7";
"P5_8":   PN = "P5_8"  !CDS_PN = "P5_8";
"P6_1":   PN = "P6_1"  !CDS_PN = "P6_1";
"P6_2":   PN = "P6_2"  !CDS_PN = "P6_2";
"P6_3":   PN = "P6_3"  !CDS_PN = "P6_3";
"P6_4":   PN = "P6_4"  !CDS_PN = "P6_4";
"P6_5":   PN = "P6_5"  !CDS_PN = "P6_5";
"P6_6":   PN = "P6_6"  !CDS_PN = "P6_6";
"P6_7":   PN = "P6_7"  !CDS_PN = "P6_7";
"P6_8":   PN = "P6_8"  !CDS_PN = "P6_8";
BODY = "Q_RES","I14": LOCATION = "R2801" #&CDS_LOCATION = "R2801" &SEC = "1" #&CDS_SEC = "1";
"A":   PN = "1"  !CDS_PN = "1";
"B":   PN = "2"  !CDS_PN = "2";
BODY = "Q_RES","I15": LOCATION = "R2800" #&CDS_LOCATION = "R2800" &SEC = "1" #&CDS_SEC = "1";
"A":   PN = "1"  !CDS_PN = "1";
"B":   PN = "2"  !CDS_PN = "2";
BODY = "LTC4307CMS8","I16": LOCATION = "U192" #&CDS_LOCATION = "U192" &SEC = "1" #&CDS_SEC = "1";
"ENABLE":   PN = "1"  !CDS_PN = "1";
"GND":   PN = "4"  !CDS_PN = "4";
"READY":   PN = "5"  !CDS_PN = "5";
"SCL_IN":   PN = "3"  !CDS_PN = "3";
"SCL_OUT":   PN = "2"  !CDS_PN = "2";
"SDA_IN":   PN = "6"  !CDS_PN = "6";
"SDA_OUT":   PN = "7"  !CDS_PN = "7";
"VCC":   PN = "8"  !CDS_PN = "8";
BODY = "Q_CAP","I19": LOCATION = "C1751" #&CDS_LOCATION = "C1751" &SEC = "1" #&CDS_SEC = "1";
"A":   PN = "1"  !CDS_PN = "1";
"B":   PN = "2"  !CDS_PN = "2";
BODY = "Q_RES","I20": LOCATION = "R2812" #&CDS_LOCATION = "R2812" &SEC = "1" #&CDS_SEC = "1";
"A":   PN = "1"  !CDS_PN = "1";
"B":   PN = "2"  !CDS_PN = "2";
BODY = "Q_RES","I21": LOCATION = "R2811" #&CDS_LOCATION = "R2811" &SEC = "1" #&CDS_SEC = "1";
"A":   PN = "1"  !CDS_PN = "1";
"B":   PN = "2"  !CDS_PN = "2";
BODY = "Q_RES","I22": LOCATION = "R2805" #&CDS_LOCATION = "R2805" &SEC = "1" #&CDS_SEC = "1";
"A":   PN = "1"  !CDS_PN = "1";
"B":   PN = "2"  !CDS_PN = "2";
BODY = "Q_RES","I24": LOCATION = "R2807" #&CDS_LOCATION = "R2807" &SEC = "1" #&CDS_SEC = "1";
"A":   PN = "1"  !CDS_PN = "1";
"B":   PN = "2"  !CDS_PN = "2";
BODY = "Q_RES","I34": LOCATION = "R2905" #&CDS_LOCATION = "R2905" &SEC = "1" #&CDS_SEC = "1";
"A":   PN = "1"  !CDS_PN = "1";
"B":   PN = "2"  !CDS_PN = "2";
BODY = "Q_RES","I35": LOCATION = "R4721" #&CDS_LOCATION = "R4721" &SEC = "1" #&CDS_SEC = "1";
"A":   PN = "1"  !CDS_PN = "1";
"B":   PN = "2"  !CDS_PN = "2";
BODY = "Q_RES","I37": LOCATION = "R2906" #&CDS_LOCATION = "R2906" &SEC = "1" #&CDS_SEC = "1";
"A":   PN = "1"  !CDS_PN = "1";
"B":   PN = "2"  !CDS_PN = "2";
BODY = "Q_RES","I38": LOCATION = "R2803" #&CDS_LOCATION = "R2803" &SEC = "1" #&CDS_SEC = "1";
"A":   PN = "1"  !CDS_PN = "1";
"B":   PN = "2"  !CDS_PN = "2";
BODY = "Q_RES","I39": LOCATION = "R2802" #&CDS_LOCATION = "R2802" &SEC = "1" #&CDS_SEC = "1";
"A":   PN = "1"  !CDS_PN = "1";
"B":   PN = "2"  !CDS_PN = "2";
BODY = "Q_RES","I41": LOCATION = "R4701" #&CDS_LOCATION = "R4701" &SEC = "1" #&CDS_SEC = "1";
"A":   PN = "1"  !CDS_PN = "1";
"B":   PN = "2"  !CDS_PN = "2";
BODY = "Q_CAP","I51": LOCATION = "C2371" #&CDS_LOCATION = "C2371" &SEC = "1" #&CDS_SEC = "1";
"A":   PN = "1"  !CDS_PN = "1";
"B":   PN = "2"  !CDS_PN = "2";
BODY = "Q_CAP","I52": LOCATION = "C2297" #&CDS_LOCATION = "C2297" &SEC = "1" #&CDS_SEC = "1";
"A":   PN = "1"  !CDS_PN = "1";
"B":   PN = "2"  !CDS_PN = "2";
BODY = "Q_CAP","I53": LOCATION = "C2296" #&CDS_LOCATION = "C2296" &SEC = "1" #&CDS_SEC = "1";
"A":   PN = "1"  !CDS_PN = "1";
"B":   PN = "2"  !CDS_PN = "2";
BODY = "Q_CAP","I54": LOCATION = "C2295" #&CDS_LOCATION = "C2295" &SEC = "1" #&CDS_SEC = "1";
"A":   PN = "1"  !CDS_PN = "1";
"B":   PN = "2"  !CDS_PN = "2";
BODY = "Q_CAP","I55": LOCATION = "C2294" #&CDS_LOCATION = "C2294" &SEC = "1" #&CDS_SEC = "1";
"A":   PN = "1"  !CDS_PN = "1";
"B":   PN = "2"  !CDS_PN = "2";
BODY = "Q_CAP","I57": LOCATION = "C2293" #&CDS_LOCATION = "C2293" &SEC = "1" #&CDS_SEC = "1";
"A":   PN = "1"  !CDS_PN = "1";
"B":   PN = "2"  !CDS_PN = "2";
DRAWING = "@s9s_mb_2u_lib.s9s_mb_2u(sch_1):page196";
BODY = "Q_RES","I10": LOCATION = "R3201" #&CDS_LOCATION = "R3201" &SEC = "1" #&CDS_SEC = "1";
"A":   PN = "1"  !CDS_PN = "1";
"B":   PN = "2"  !CDS_PN = "2";
BODY = "Q_RES","I11": LOCATION = "R3200" #&CDS_LOCATION = "R3200" &SEC = "1" #&CDS_SEC = "1";
"A":   PN = "1"  !CDS_PN = "1";
"B":   PN = "2"  !CDS_PN = "2";
BODY = "Q_RES","I12": LOCATION = "R3199" #&CDS_LOCATION = "R3199" &SEC = "1" #&CDS_SEC = "1";
"A":   PN = "1"  !CDS_PN = "1";
"B":   PN = "2"  !CDS_PN = "2";
BODY = "Q_RES","I13": LOCATION = "R3198" #&CDS_LOCATION = "R3198" &SEC = "1" #&CDS_SEC = "1";
"A":   PN = "1"  !CDS_PN = "1";
"B":   PN = "2"  !CDS_PN = "2";
BODY = "Q_RES","I14": LOCATION = "R3197" #&CDS_LOCATION = "R3197" &SEC = "1" #&CDS_SEC = "1";
"A":   PN = "1"  !CDS_PN = "1";
"B":   PN = "2"  !CDS_PN = "2";
BODY = "Q_RES","I15": LOCATION = "R3196" #&CDS_LOCATION = "R3196" &SEC = "1" #&CDS_SEC = "1";
"A":   PN = "1"  !CDS_PN = "1";
"B":   PN = "2"  !CDS_PN = "2";
BODY = "Q_RES","I16": LOCATION = "R3195" #&CDS_LOCATION = "R3195" &SEC = "1" #&CDS_SEC = "1";
"A":   PN = "1"  !CDS_PN = "1";
"B":   PN = "2"  !CDS_PN = "2";
BODY = "Q_RES","I17": LOCATION = "R3194" #&CDS_LOCATION = "R3194" &SEC = "1" #&CDS_SEC = "1";
"A":   PN = "1"  !CDS_PN = "1";
"B":   PN = "2"  !CDS_PN = "2";
BODY = "Q_RES","I18": LOCATION = "R3355" #&CDS_LOCATION = "R3355" &SEC = "1" #&CDS_SEC = "1";
"A":   PN = "1"  !CDS_PN = "1";
"B":   PN = "2"  !CDS_PN = "2";
BODY = "Q_RES","I24": LOCATION = "R3354" #&CDS_LOCATION = "R3354" &SEC = "1" #&CDS_SEC = "1";
"A":   PN = "1"  !CDS_PN = "1";
"B":   PN = "2"  !CDS_PN = "2";
BODY = "Q_RES","I25": LOCATION = "R3353" #&CDS_LOCATION = "R3353" &SEC = "1" #&CDS_SEC = "1";
"A":   PN = "1"  !CDS_PN = "1";
"B":   PN = "2"  !CDS_PN = "2";
BODY = "Q_RES","I26": LOCATION = "R3352" #&CDS_LOCATION = "R3352" &SEC = "1" #&CDS_SEC = "1";
"A":   PN = "1"  !CDS_PN = "1";
"B":   PN = "2"  !CDS_PN = "2";
BODY = "Q_RES","I27": LOCATION = "R2659" #&CDS_LOCATION = "R2659" &SEC = "1" #&CDS_SEC = "1";
"A":   PN = "1"  !CDS_PN = "1";
"B":   PN = "2"  !CDS_PN = "2";
BODY = "Q_RES","I28": LOCATION = "R2660" #&CDS_LOCATION = "R2660" &SEC = "1" #&CDS_SEC = "1";
"A":   PN = "1"  !CDS_PN = "1";
"B":   PN = "2"  !CDS_PN = "2";
DRAWING = "@s9s_mb_2u_lib.s9s_mb_2u(sch_1):page198";
BODY = "Q_RES","I7": LOCATION = "R1011" #&CDS_LOCATION = "R1011" &SEC = "1" #&CDS_SEC = "1";
"A":   PN = "1"  !CDS_PN = "1";
"B":   PN = "2"  !CDS_PN = "2";
BODY = "Q_RES","I8": LOCATION = "R1010" #&CDS_LOCATION = "R1010" &SEC = "1" #&CDS_SEC = "1";
"A":   PN = "1"  !CDS_PN = "1";
"B":   PN = "2"  !CDS_PN = "2";
BODY = "Q_RES","I9": LOCATION = "R1019" #&CDS_LOCATION = "R1019" &SEC = "1" #&CDS_SEC = "1";
"A":   PN = "1"  !CDS_PN = "1";
"B":   PN = "2"  !CDS_PN = "2";
BODY = "Q_RES","I10": LOCATION = "R1018" #&CDS_LOCATION = "R1018" &SEC = "1" #&CDS_SEC = "1";
"A":   PN = "1"  !CDS_PN = "1";
"B":   PN = "2"  !CDS_PN = "2";
BODY = "Q_RES","I11": LOCATION = "R1017" #&CDS_LOCATION = "R1017" &SEC = "1" #&CDS_SEC = "1";
"A":   PN = "1"  !CDS_PN = "1";
"B":   PN = "2"  !CDS_PN = "2";
BODY = "Q_RES","I12": LOCATION = "R1016" #&CDS_LOCATION = "R1016" &SEC = "1" #&CDS_SEC = "1";
"A":   PN = "1"  !CDS_PN = "1";
"B":   PN = "2"  !CDS_PN = "2";
BODY = "Q_RES","I19": LOCATION = "R1015" #&CDS_LOCATION = "R1015" &SEC = "1" #&CDS_SEC = "1";
"A":   PN = "1"  !CDS_PN = "1";
"B":   PN = "2"  !CDS_PN = "2";
BODY = "Q_RES","I20": LOCATION = "R1014" #&CDS_LOCATION = "R1014" &SEC = "1" #&CDS_SEC = "1";
"A":   PN = "1"  !CDS_PN = "1";
"B":   PN = "2"  !CDS_PN = "2";
BODY = "Q_RES","I21": LOCATION = "R1013" #&CDS_LOCATION = "R1013" &SEC = "1" #&CDS_SEC = "1";
"A":   PN = "1"  !CDS_PN = "1";
"B":   PN = "2"  !CDS_PN = "2";
BODY = "Q_RES","I22": LOCATION = "R1012" #&CDS_LOCATION = "R1012" &SEC = "1" #&CDS_SEC = "1";
"A":   PN = "1"  !CDS_PN = "1";
"B":   PN = "2"  !CDS_PN = "2";
BODY = "Q_RES","I23": LOCATION = "R1276" #&CDS_LOCATION = "R1276" &SEC = "1" #&CDS_SEC = "1";
"A":   PN = "1"  !CDS_PN = "1";
"B":   PN = "2"  !CDS_PN = "2";
BODY = "Q_RES","I24": LOCATION = "R1275" #&CDS_LOCATION = "R1275" &SEC = "1" #&CDS_SEC = "1";
"A":   PN = "1"  !CDS_PN = "1";
"B":   PN = "2"  !CDS_PN = "2";
BODY = "Q_RES","I27": LOCATION = "R1023" #&CDS_LOCATION = "R1023" &SEC = "1" #&CDS_SEC = "1";
"A":   PN = "1"  !CDS_PN = "1";
"B":   PN = "2"  !CDS_PN = "2";
BODY = "Q_RES","I28": LOCATION = "R1022" #&CDS_LOCATION = "R1022" &SEC = "1" #&CDS_SEC = "1";
"A":   PN = "1"  !CDS_PN = "1";
"B":   PN = "2"  !CDS_PN = "2";
BODY = "Q_RES","I29": LOCATION = "R1021" #&CDS_LOCATION = "R1021" &SEC = "1" #&CDS_SEC = "1";
"A":   PN = "1"  !CDS_PN = "1";
"B":   PN = "2"  !CDS_PN = "2";
BODY = "Q_RES","I30": LOCATION = "R1020" #&CDS_LOCATION = "R1020" &SEC = "1" #&CDS_SEC = "1";
"A":   PN = "1"  !CDS_PN = "1";
"B":   PN = "2"  !CDS_PN = "2";
BODY = "Q_RES","I43": LOCATION = "R1274" #&CDS_LOCATION = "R1274" &SEC = "1" #&CDS_SEC = "1";
"A":   PN = "1"  !CDS_PN = "1";
"B":   PN = "2"  !CDS_PN = "2";
BODY = "Q_RES","I44": LOCATION = "R1273" #&CDS_LOCATION = "R1273" &SEC = "1" #&CDS_SEC = "1";
"A":   PN = "1"  !CDS_PN = "1";
"B":   PN = "2"  !CDS_PN = "2";
BODY = "Q_RES","I45": LOCATION = "R566" #&CDS_LOCATION = "R566" &SEC = "1" #&CDS_SEC = "1";
"A":   PN = "1"  !CDS_PN = "1";
"B":   PN = "2"  !CDS_PN = "2";
BODY = "Q_RES","I46": LOCATION = "R565" #&CDS_LOCATION = "R565" &SEC = "1" #&CDS_SEC = "1";
"A":   PN = "1"  !CDS_PN = "1";
"B":   PN = "2"  !CDS_PN = "2";
BODY = "Q_RES","I47": LOCATION = "R564" #&CDS_LOCATION = "R564" &SEC = "1" #&CDS_SEC = "1";
"A":   PN = "1"  !CDS_PN = "1";
"B":   PN = "2"  !CDS_PN = "2";
BODY = "Q_RES","I48": LOCATION = "R563" #&CDS_LOCATION = "R563" &SEC = "1" #&CDS_SEC = "1";
"A":   PN = "1"  !CDS_PN = "1";
"B":   PN = "2"  !CDS_PN = "2";
BODY = "Q_RES","I57": LOCATION = "R554" #&CDS_LOCATION = "R554" &SEC = "1" #&CDS_SEC = "1";
"A":   PN = "1"  !CDS_PN = "1";
"B":   PN = "2"  !CDS_PN = "2";
BODY = "Q_RES","I58": LOCATION = "R553" #&CDS_LOCATION = "R553" &SEC = "1" #&CDS_SEC = "1";
"A":   PN = "1"  !CDS_PN = "1";
"B":   PN = "2"  !CDS_PN = "2";
END.
